G04 ================== begin FILE IDENTIFICATION RECORD ==================*
G04 Layout Name:  D:/<user>/Wistron_project/16315-1/gbr/16315-1.brd*
G04 Film Name:    L1*
G04 File Format:  Gerber RS274X*
G04 File Origin:  Cadence Allegro 16.5-S056*
G04 Origin Date:  Fri Jun 09 15:31:10 2017*
G04 *
G04 Layer:  VIA CLASS/TOP*
G04 Layer:  PIN/TOP*
G04 Layer:  ETCH/TOP*
G04 Layer:  DRAWING FORMAT/LAYER_PCB_STORY*
G04 Layer:  DRAWING FORMAT/LAYER_L1*
G04 *
G04 Offset:    (0.00 0.00)*
G04 Mirror:    No*
G04 Mode:      Positive*
G04 Rotation:  0*
G04 FullContactRelief:  No*
G04 UndefLineWidth:     6.00*
G04 ================== end FILE IDENTIFICATION RECORD ====================*
%FSLAX35Y35*MOIN*%
%IR0*IPPOS*OFA0.00000B0.00000*MIA0B0*SFA1.00000B1.00000*%
%AMMACRO46*
4,1,40,.013,.017,
-.013,.017,
-.013695,.016939,
-.014368,.016759,
-.015,.016464,
-.015571,.016064,
-.016064,.015571,
-.016464,.015,
-.016759,.014368,
-.016939,.013695,
-.017,.013,
-.017,-.013,
-.016939,-.013695,
-.016759,-.014368,
-.016464,-.015,
-.016064,-.015571,
-.015571,-.016064,
-.015,-.016464,
-.014368,-.016759,
-.013695,-.016939,
-.013,-.017,
.013,-.017,
.013695,-.016939,
.014368,-.016759,
.015,-.016464,
.015571,-.016064,
.016064,-.015571,
.016464,-.015,
.016759,-.014368,
.016939,-.013695,
.017,-.013,
.017,.013,
.016939,.013695,
.016759,.014368,
.016464,.015,
.016064,.015571,
.015571,.016064,
.015,.016464,
.014368,.016759,
.013695,.016939,
.013,.017,
0.0*
%
%ADD46MACRO46*%
%AMMACRO17*
4,1,40,.017,-.013,
.017,.013,
.016939,.013695,
.016759,.014368,
.016464,.015,
.016064,.015571,
.015571,.016064,
.015,.016464,
.014368,.016759,
.013695,.016939,
.013,.017,
-.013,.017,
-.013695,.016939,
-.014368,.016759,
-.015,.016464,
-.015571,.016064,
-.016064,.015571,
-.016464,.015,
-.016759,.014368,
-.016939,.013695,
-.017,.013,
-.017,-.013,
-.016939,-.013695,
-.016759,-.014368,
-.016464,-.015,
-.016064,-.015571,
-.015571,-.016064,
-.015,-.016464,
-.014368,-.016759,
-.013695,-.016939,
-.013,-.017,
.013,-.017,
.013695,-.016939,
.014368,-.016759,
.015,-.016464,
.015571,-.016064,
.016064,-.015571,
.016464,-.015,
.016759,-.014368,
.016939,-.013695,
.017,-.013,
0.0*
%
%ADD17MACRO17*%
%AMMACRO66*
4,1,40,.019,.017,
-.019,.017,
-.019695,.016939,
-.020368,.016759,
-.021,.016464,
-.021571,.016064,
-.022064,.015571,
-.022464,.015,
-.022759,.014368,
-.022939,.013695,
-.023,.013,
-.023,-.013,
-.022939,-.013695,
-.022759,-.014368,
-.022464,-.015,
-.022064,-.015571,
-.021571,-.016064,
-.021,-.016464,
-.020368,-.016759,
-.019695,-.016939,
-.019,-.017,
.019,-.017,
.019695,-.016939,
.020368,-.016759,
.021,-.016464,
.021571,-.016064,
.022064,-.015571,
.022464,-.015,
.022759,-.014368,
.022939,-.013695,
.023,-.013,
.023,.013,
.022939,.013695,
.022759,.014368,
.022464,.015,
.022064,.015571,
.021571,.016064,
.021,.016464,
.020368,.016759,
.019695,.016939,
.019,.017,
0.0*
%
%ADD66MACRO66*%
%ADD95R,.055X.11*%
%ADD19C,.01*%
%ADD104O,.115X.048*%
%ADD50C,.02*%
%ADD82R,.056X.14*%
%ADD60C,.03*%
%ADD103R,.08X.127*%
%ADD18C,.04*%
%ADD12C,.022*%
%ADD101R,.22X.096*%
%ADD54C,.032*%
%AMMACRO51*
4,1,40,-.007,.004,
-.007,-.004,
-.00697,-.004347,
-.006879,-.004684,
-.006732,-.005,
-.006532,-.005286,
-.006286,-.005532,
-.006,-.005732,
-.005684,-.005879,
-.005347,-.00597,
-.005,-.006,
.005,-.006,
.005347,-.00597,
.005684,-.005879,
.006,-.005732,
.006286,-.005532,
.006532,-.005286,
.006732,-.005,
.006879,-.004684,
.00697,-.004347,
.007,-.004,
.007,.004,
.00697,.004347,
.006879,.004684,
.006732,.005,
.006532,.005286,
.006286,.005532,
.006,.005732,
.005684,.005879,
.005347,.00597,
.005,.006,
-.005,.006,
-.005347,.00597,
-.005684,.005879,
-.006,.005732,
-.006286,.005532,
-.006532,.005286,
-.006732,.005,
-.006879,.004684,
-.00697,.004347,
-.007,.004,
0.0*
%
%ADD51MACRO51*%
%ADD89C,.042*%
%ADD97C,.034*%
%ADD14C,.026*%
%ADD92O,.048X.166*%
%ADD11C,.028*%
%ADD93C,.048*%
%AMMACRO74*
4,1,40,.0225,-.007,
.022378,-.008389,
.022018,-.009736,
.021428,-.011,
.020628,-.012142,
.019642,-.013128,
.0185,-.013928,
.017236,-.014518,
.015889,-.014878,
.0145,-.015,
-.0145,-.015,
-.015889,-.014878,
-.017236,-.014518,
-.0185,-.013928,
-.019642,-.013128,
-.020628,-.012142,
-.021428,-.011,
-.022018,-.009736,
-.022378,-.008389,
-.0225,-.007,
-.0225,.007,
-.022378,.008389,
-.022018,.009736,
-.021428,.011,
-.020628,.012142,
-.019642,.013128,
-.0185,.013928,
-.017236,.014518,
-.015889,.014878,
-.0145,.015,
.0145,.015,
.015889,.014878,
.017236,.014518,
.0185,.013928,
.019642,.013128,
.020628,.012142,
.021428,.011,
.022018,.009736,
.022378,.008389,
.0225,.007,
.0225,-.007,
0.0*
%
%ADD74MACRO74*%
%AMMACRO64*
4,1,46,-.00177,-.018,
-.003163,-.017918,
-.00452,-.017595,
-.0058,-.017042,
-.006965,-.016274,
-.007979,-.015316,
-.008812,-.014196,
-.009437,-.012949,
-.009836,-.011613,
-.009997,-.010227,
-.01,-.01,
-.01,.01,
-.00999,.01,
-.009868,.011389,
-.009507,.012737,
-.008918,.014001,
-.008118,.015143,
-.007132,.016129,
-.005989,.016929,
-.004725,.017519,
-.003378,.01788,
-.001989,.018001,
-.00185,.018,
.00185,.018,
.003241,.017903,
.004595,.017565,
.005869,.016998,
.007025,.016218,
.008028,.015249,
.008848,.01412,
.009459,.012867,
.009843,.011526,
.009989,.010139,
.00999,.01,
.01,.01,
.01,-.01,
.009878,-.01139,
.009517,-.012737,
.008928,-.014002,
.008128,-.015144,
.007141,-.016131,
.005998,-.016931,
.004734,-.017521,
.003387,-.017882,
.001997,-.018003,
.00177,-.018,
-.00177,-.018,
0.0*
%
%ADD64MACRO64*%
%ADD61C,.02617*%
%AMMACRO13*
4,1,40,-.007,-.0225,
-.008389,-.022378,
-.009736,-.022018,
-.011,-.021428,
-.012142,-.020628,
-.013128,-.019642,
-.013928,-.0185,
-.014518,-.017236,
-.014878,-.015889,
-.015,-.0145,
-.015,.0145,
-.014878,.015889,
-.014518,.017236,
-.013928,.0185,
-.013128,.019642,
-.012142,.020628,
-.011,.021428,
-.009736,.022018,
-.008389,.022378,
-.007,.0225,
.007,.0225,
.008389,.022378,
.009736,.022018,
.011,.021428,
.012142,.020628,
.013128,.019642,
.013928,.0185,
.014518,.017236,
.014878,.015889,
.015,.0145,
.015,-.0145,
.014878,-.015889,
.014518,-.017236,
.013928,-.0185,
.013128,-.019642,
.012142,-.020628,
.011,-.021428,
.009736,-.022018,
.008389,-.022378,
.007,-.0225,
-.007,-.0225,
0.0*
%
%ADD13MACRO13*%
%AMMACRO26*
4,1,40,.007,.011,
-.007,.011,
-.007695,.010939,
-.008368,.010759,
-.009,.010464,
-.009571,.010064,
-.010064,.009571,
-.010464,.009,
-.010759,.008368,
-.010939,.007695,
-.011,.007,
-.011,-.007,
-.010939,-.007695,
-.010759,-.008368,
-.010464,-.009,
-.010064,-.009571,
-.009571,-.010064,
-.009,-.010464,
-.008368,-.010759,
-.007695,-.010939,
-.007,-.011,
.007,-.011,
.007695,-.010939,
.008368,-.010759,
.009,-.010464,
.009571,-.010064,
.010064,-.009571,
.010464,-.009,
.010759,-.008368,
.010939,-.007695,
.011,-.007,
.011,.007,
.010939,.007695,
.010759,.008368,
.010464,.009,
.010064,.009571,
.009571,.010064,
.009,.010464,
.008368,.010759,
.007695,.010939,
.007,.011,
0.0*
%
%ADD26MACRO26*%
%AMMACRO20*
4,1,40,.011,-.007,
.011,.007,
.010939,.007695,
.010759,.008368,
.010464,.009,
.010064,.009571,
.009571,.010064,
.009,.010464,
.008368,.010759,
.007695,.010939,
.007,.011,
-.007,.011,
-.007695,.010939,
-.008368,.010759,
-.009,.010464,
-.009571,.010064,
-.010064,.009571,
-.010464,.009,
-.010759,.008368,
-.010939,.007695,
-.011,.007,
-.011,-.007,
-.010939,-.007695,
-.010759,-.008368,
-.010464,-.009,
-.010064,-.009571,
-.009571,-.010064,
-.009,-.010464,
-.008368,-.010759,
-.007695,-.010939,
-.007,-.011,
.007,-.011,
.007695,-.010939,
.008368,-.010759,
.009,-.010464,
.009571,-.010064,
.010064,-.009571,
.010464,-.009,
.010759,-.008368,
.010939,-.007695,
.011,-.007,
0.0*
%
%ADD20MACRO20*%
%AMMACRO34*
4,1,40,-.012,.008,
-.012,-.008,
-.011939,-.008695,
-.011759,-.009368,
-.011464,-.01,
-.011064,-.010571,
-.010571,-.011064,
-.01,-.011464,
-.009368,-.011759,
-.008695,-.011939,
-.008,-.012,
.008,-.012,
.008695,-.011939,
.009368,-.011759,
.01,-.011464,
.010571,-.011064,
.011064,-.010571,
.011464,-.01,
.011759,-.009368,
.011939,-.008695,
.012,-.008,
.012,.008,
.011939,.008695,
.011759,.009368,
.011464,.01,
.011064,.010571,
.010571,.011064,
.01,.011464,
.009368,.011759,
.008695,.011939,
.008,.012,
-.008,.012,
-.008695,.011939,
-.009368,.011759,
-.01,.011464,
-.010571,.011064,
-.011064,.010571,
-.011464,.01,
-.011759,.009368,
-.011939,.008695,
-.012,.008,
0.0*
%
%ADD34MACRO34*%
%AMMACRO57*
4,1,40,.008,.012,
-.008,.012,
-.008695,.011939,
-.009368,.011759,
-.01,.011464,
-.010571,.011064,
-.011064,.010571,
-.011464,.01,
-.011759,.009368,
-.011939,.008695,
-.012,.008,
-.012,-.008,
-.011939,-.008695,
-.011759,-.009368,
-.011464,-.01,
-.011064,-.010571,
-.010571,-.011064,
-.01,-.011464,
-.009368,-.011759,
-.008695,-.011939,
-.008,-.012,
.008,-.012,
.008695,-.011939,
.009368,-.011759,
.01,-.011464,
.010571,-.011064,
.011064,-.010571,
.011464,-.01,
.011759,-.009368,
.011939,-.008695,
.012,-.008,
.012,.008,
.011939,.008695,
.011759,.009368,
.011464,.01,
.011064,.010571,
.010571,.011064,
.01,.011464,
.009368,.011759,
.008695,.011939,
.008,.012,
0.0*
%
%ADD57MACRO57*%
%AMMACRO53*
4,1,40,-.013,-.017,
.013,-.017,
.013695,-.016939,
.014368,-.016759,
.015,-.016464,
.015571,-.016064,
.016064,-.015571,
.016464,-.015,
.016759,-.014368,
.016939,-.013695,
.017,-.013,
.017,.013,
.016939,.013695,
.016759,.014368,
.016464,.015,
.016064,.015571,
.015571,.016064,
.015,.016464,
.014368,.016759,
.013695,.016939,
.013,.017,
-.013,.017,
-.013695,.016939,
-.014368,.016759,
-.015,.016464,
-.015571,.016064,
-.016064,.015571,
-.016464,.015,
-.016759,.014368,
-.016939,.013695,
-.017,.013,
-.017,-.013,
-.016939,-.013695,
-.016759,-.014368,
-.016464,-.015,
-.016064,-.015571,
-.015571,-.016064,
-.015,-.016464,
-.014368,-.016759,
-.013695,-.016939,
-.013,-.017,
0.0*
%
%ADD53MACRO53*%
%AMMACRO38*
4,1,40,-.017,.013,
-.017,-.013,
-.016939,-.013695,
-.016759,-.014368,
-.016464,-.015,
-.016064,-.015571,
-.015571,-.016064,
-.015,-.016464,
-.014368,-.016759,
-.013695,-.016939,
-.013,-.017,
.013,-.017,
.013695,-.016939,
.014368,-.016759,
.015,-.016464,
.015571,-.016064,
.016064,-.015571,
.016464,-.015,
.016759,-.014368,
.016939,-.013695,
.017,-.013,
.017,.013,
.016939,.013695,
.016759,.014368,
.016464,.015,
.016064,.015571,
.015571,.016064,
.015,.016464,
.014368,.016759,
.013695,.016939,
.013,.017,
-.013,.017,
-.013695,.016939,
-.014368,.016759,
-.015,.016464,
-.015571,.016064,
-.016064,.015571,
-.016464,.015,
-.016759,.014368,
-.016939,.013695,
-.017,.013,
0.0*
%
%ADD38MACRO38*%
%AMMACRO112*
4,1,40,.023,-.013,
.023,.013,
.022939,.013695,
.022759,.014368,
.022464,.015,
.022064,.015571,
.021571,.016064,
.021,.016464,
.020368,.016759,
.019695,.016939,
.019,.017,
-.019,.017,
-.019695,.016939,
-.020368,.016759,
-.021,.016464,
-.021571,.016064,
-.022064,.015571,
-.022464,.015,
-.022759,.014368,
-.022939,.013695,
-.023,.013,
-.023,-.013,
-.022939,-.013695,
-.022759,-.014368,
-.022464,-.015,
-.022064,-.015571,
-.021571,-.016064,
-.021,-.016464,
-.020368,-.016759,
-.019695,-.016939,
-.019,-.017,
.019,-.017,
.019695,-.016939,
.020368,-.016759,
.021,-.016464,
.021571,-.016064,
.022064,-.015571,
.022464,-.015,
.022759,-.014368,
.022939,-.013695,
.023,-.013,
0.0*
%
%ADD112MACRO112*%
%AMMACRO27*
4,1,40,.007,.011,
-.007,.011,
-.007695,.010939,
-.008368,.010759,
-.009,.010464,
-.009571,.010064,
-.010064,.009571,
-.010464,.009,
-.010759,.008368,
-.010939,.007695,
-.011,.007,
-.011,-.007,
-.010939,-.007695,
-.010759,-.008368,
-.010464,-.009,
-.010064,-.009571,
-.009571,-.010064,
-.009,-.010464,
-.008368,-.010759,
-.007695,-.010939,
-.007,-.011,
.007,-.011,
.007695,-.010939,
.008368,-.010759,
.009,-.010464,
.009571,-.010064,
.010064,-.009571,
.010464,-.009,
.010759,-.008368,
.010939,-.007695,
.011,-.007,
.011,.007,
.010939,.007695,
.010759,.008368,
.010464,.009,
.010064,.009571,
.009571,.010064,
.009,.010464,
.008368,.010759,
.007695,.010939,
.007,.011,
0.0*
%
%ADD27MACRO27*%
%AMMACRO21*
4,1,40,.011,-.007,
.011,.007,
.010939,.007695,
.010759,.008368,
.010464,.009,
.010064,.009571,
.009571,.010064,
.009,.010464,
.008368,.010759,
.007695,.010939,
.007,.011,
-.007,.011,
-.007695,.010939,
-.008368,.010759,
-.009,.010464,
-.009571,.010064,
-.010064,.009571,
-.010464,.009,
-.010759,.008368,
-.010939,.007695,
-.011,.007,
-.011,-.007,
-.010939,-.007695,
-.010759,-.008368,
-.010464,-.009,
-.010064,-.009571,
-.009571,-.010064,
-.009,-.010464,
-.008368,-.010759,
-.007695,-.010939,
-.007,-.011,
.007,-.011,
.007695,-.010939,
.008368,-.010759,
.009,-.010464,
.009571,-.010064,
.010064,-.009571,
.010464,-.009,
.010759,-.008368,
.010939,-.007695,
.011,-.007,
0.0*
%
%ADD21MACRO21*%
%AMMACRO35*
4,1,40,-.012,.008,
-.012,-.008,
-.011939,-.008695,
-.011759,-.009368,
-.011464,-.01,
-.011064,-.010571,
-.010571,-.011064,
-.01,-.011464,
-.009368,-.011759,
-.008695,-.011939,
-.008,-.012,
.008,-.012,
.008695,-.011939,
.009368,-.011759,
.01,-.011464,
.010571,-.011064,
.011064,-.010571,
.011464,-.01,
.011759,-.009368,
.011939,-.008695,
.012,-.008,
.012,.008,
.011939,.008695,
.011759,.009368,
.011464,.01,
.011064,.010571,
.010571,.011064,
.01,.011464,
.009368,.011759,
.008695,.011939,
.008,.012,
-.008,.012,
-.008695,.011939,
-.009368,.011759,
-.01,.011464,
-.010571,.011064,
-.011064,.010571,
-.011464,.01,
-.011759,.009368,
-.011939,.008695,
-.012,.008,
0.0*
%
%ADD35MACRO35*%
%AMMACRO58*
4,1,40,.008,.012,
-.008,.012,
-.008695,.011939,
-.009368,.011759,
-.01,.011464,
-.010571,.011064,
-.011064,.010571,
-.011464,.01,
-.011759,.009368,
-.011939,.008695,
-.012,.008,
-.012,-.008,
-.011939,-.008695,
-.011759,-.009368,
-.011464,-.01,
-.011064,-.010571,
-.010571,-.011064,
-.01,-.011464,
-.009368,-.011759,
-.008695,-.011939,
-.008,-.012,
.008,-.012,
.008695,-.011939,
.009368,-.011759,
.01,-.011464,
.010571,-.011064,
.011064,-.010571,
.011464,-.01,
.011759,-.009368,
.011939,-.008695,
.012,-.008,
.012,.008,
.011939,.008695,
.011759,.009368,
.011464,.01,
.011064,.010571,
.010571,.011064,
.01,.011464,
.009368,.011759,
.008695,.011939,
.008,.012,
0.0*
%
%ADD58MACRO58*%
%AMMACRO52*
4,1,40,-.013,-.017,
.013,-.017,
.013695,-.016939,
.014368,-.016759,
.015,-.016464,
.015571,-.016064,
.016064,-.015571,
.016464,-.015,
.016759,-.014368,
.016939,-.013695,
.017,-.013,
.017,.013,
.016939,.013695,
.016759,.014368,
.016464,.015,
.016064,.015571,
.015571,.016064,
.015,.016464,
.014368,.016759,
.013695,.016939,
.013,.017,
-.013,.017,
-.013695,.016939,
-.014368,.016759,
-.015,.016464,
-.015571,.016064,
-.016064,.015571,
-.016464,.015,
-.016759,.014368,
-.016939,.013695,
-.017,.013,
-.017,-.013,
-.016939,-.013695,
-.016759,-.014368,
-.016464,-.015,
-.016064,-.015571,
-.015571,-.016064,
-.015,-.016464,
-.014368,-.016759,
-.013695,-.016939,
-.013,-.017,
0.0*
%
%ADD52MACRO52*%
%AMMACRO39*
4,1,40,-.017,.013,
-.017,-.013,
-.016939,-.013695,
-.016759,-.014368,
-.016464,-.015,
-.016064,-.015571,
-.015571,-.016064,
-.015,-.016464,
-.014368,-.016759,
-.013695,-.016939,
-.013,-.017,
.013,-.017,
.013695,-.016939,
.014368,-.016759,
.015,-.016464,
.015571,-.016064,
.016064,-.015571,
.016464,-.015,
.016759,-.014368,
.016939,-.013695,
.017,-.013,
.017,.013,
.016939,.013695,
.016759,.014368,
.016464,.015,
.016064,.015571,
.015571,.016064,
.015,.016464,
.014368,.016759,
.013695,.016939,
.013,.017,
-.013,.017,
-.013695,.016939,
-.014368,.016759,
-.015,.016464,
-.015571,.016064,
-.016064,.015571,
-.016464,.015,
-.016759,.014368,
-.016939,.013695,
-.017,.013,
0.0*
%
%ADD39MACRO39*%
%AMMACRO113*
4,1,40,-.019,-.017,
.019,-.017,
.019695,-.016939,
.020368,-.016759,
.021,-.016464,
.021571,-.016064,
.022064,-.015571,
.022464,-.015,
.022759,-.014368,
.022939,-.013695,
.023,-.013,
.023,.013,
.022939,.013695,
.022759,.014368,
.022464,.015,
.022064,.015571,
.021571,.016064,
.021,.016464,
.020368,.016759,
.019695,.016939,
.019,.017,
-.019,.017,
-.019695,.016939,
-.020368,.016759,
-.021,.016464,
-.021571,.016064,
-.022064,.015571,
-.022464,.015,
-.022759,.014368,
-.022939,.013695,
-.023,.013,
-.023,-.013,
-.022939,-.013695,
-.022759,-.014368,
-.022464,-.015,
-.022064,-.015571,
-.021571,-.016064,
-.021,-.016464,
-.020368,-.016759,
-.019695,-.016939,
-.019,-.017,
0.0*
%
%ADD113MACRO113*%
%ADD79R,.2X.208*%
%ADD78R,.001X.001*%
%ADD99R,.208X.2*%
%ADD98R,.001X.001*%
%ADD63R,.04X.022*%
%ADD96R,.02X.06*%
%ADD75R,.06X.03*%
%ADD28R,.022X.04*%
%ADD105R,.012X.06*%
%ADD100R,.03X.06*%
%ADD72R,.012X.042*%
%ADD70R,.042X.012*%
%ADD87R,.06X.014*%
%ADD62R,.04X.016*%
%ADD76R,.045X.03*%
%ADD56R,.014X.06*%
%ADD44R,.016X.04*%
%ADD108R,.03X.045*%
%ADD71R,.012X.036*%
%ADD69R,.036X.012*%
%AMMACRO106*
4,1,40,.007,-.004,
.007,.004,
.00697,.004347,
.006879,.004684,
.006732,.005,
.006532,.005286,
.006286,.005532,
.006,.005732,
.005684,.005879,
.005347,.00597,
.005,.006,
-.005,.006,
-.005347,.00597,
-.005684,.005879,
-.006,.005732,
-.006286,.005532,
-.006532,.005286,
-.006732,.005,
-.006879,.004684,
-.00697,.004347,
-.007,.004,
-.007,-.004,
-.00697,-.004347,
-.006879,-.004684,
-.006732,-.005,
-.006532,-.005286,
-.006286,-.005532,
-.006,-.005732,
-.005684,-.005879,
-.005347,-.00597,
-.005,-.006,
.005,-.006,
.005347,-.00597,
.005684,-.005879,
.006,-.005732,
.006286,-.005532,
.006532,-.005286,
.006732,-.005,
.006879,-.004684,
.00697,-.004347,
.007,-.004,
0.0*
%
%ADD106MACRO106*%
%ADD86R,.016X.06*%
%ADD42R,.093X.02*%
%ADD94R,.02X.093*%
%ADD31R,.05X.065*%
%ADD45R,.065X.05*%
%ADD107R,.065X.025*%
%ADD77R,.045X.09*%
%ADD43R,.093X.024*%
%ADD36R,.028X.034*%
%ADD109R,.09X.045*%
%ADD90R,.024X.093*%
%ADD55R,.048X.016*%
%ADD41R,.102X.102*%
%ADD33R,.025X.065*%
%ADD32R,.045X.055*%
%ADD91R,.016X.048*%
%ADD48R,.055X.045*%
%ADD81R,.024X.059*%
%ADD15C,.256*%
%AMMACRO111*
4,1,46,.00177,.018,
.003163,.017918,
.00452,.017595,
.0058,.017042,
.006965,.016274,
.007979,.015316,
.008812,.014196,
.009437,.012949,
.009836,.011613,
.009997,.010227,
.01,.01,
.01,-.01,
.00999,-.01,
.009868,-.011389,
.009507,-.012737,
.008918,-.014001,
.008118,-.015143,
.007132,-.016129,
.005989,-.016929,
.004725,-.017519,
.003378,-.01788,
.001989,-.018001,
.00185,-.018,
-.00185,-.018,
-.003241,-.017903,
-.004595,-.017565,
-.005869,-.016998,
-.007025,-.016218,
-.008028,-.015249,
-.008848,-.01412,
-.009459,-.012867,
-.009843,-.011526,
-.009989,-.010139,
-.00999,-.01,
-.01,-.01,
-.01,.01,
-.009878,.01139,
-.009517,.012737,
-.008928,.014002,
-.008128,.015144,
-.007141,.016131,
-.005998,.016931,
-.004734,.017521,
-.003387,.017882,
-.001997,.018003,
-.00177,.018,
.00177,.018,
0.0*
%
%ADD111MACRO111*%
%ADD102R,.035X.096*%
%ADD84R,.057X.083*%
%ADD83R,.09X.095*%
%AMMACRO110*
4,1,40,-.0225,.007,
-.022378,.008389,
-.022018,.009736,
-.021428,.011,
-.020628,.012142,
-.019642,.013128,
-.0185,.013928,
-.017236,.014518,
-.015889,.014878,
-.0145,.015,
.0145,.015,
.015889,.014878,
.017236,.014518,
.0185,.013928,
.019642,.013128,
.020628,.012142,
.021428,.011,
.022018,.009736,
.022378,.008389,
.0225,.007,
.0225,-.007,
.022378,-.008389,
.022018,-.009736,
.021428,-.011,
.020628,-.012142,
.019642,-.013128,
.0185,-.013928,
.017236,-.014518,
.015889,-.014878,
.0145,-.015,
-.0145,-.015,
-.015889,-.014878,
-.017236,-.014518,
-.0185,-.013928,
-.019642,-.013128,
-.020628,-.012142,
-.021428,-.011,
-.022018,-.009736,
-.022378,-.008389,
-.0225,-.007,
-.0225,.007,
0.0*
%
%ADD110MACRO110*%
%ADD85R,.083X.057*%
%ADD40C,.375*%
%AMMACRO37*
4,1,40,.007,.0225,
.008389,.022378,
.009736,.022018,
.011,.021428,
.012142,.020628,
.013128,.019642,
.013928,.0185,
.014518,.017236,
.014878,.015889,
.015,.0145,
.015,-.0145,
.014878,-.015889,
.014518,-.017236,
.013928,-.0185,
.013128,-.019642,
.012142,-.020628,
.011,-.021428,
.009736,-.022018,
.008389,-.022378,
.007,-.0225,
-.007,-.0225,
-.008389,-.022378,
-.009736,-.022018,
-.011,-.021428,
-.012142,-.020628,
-.013128,-.019642,
-.013928,-.0185,
-.014518,-.017236,
-.014878,-.015889,
-.015,-.0145,
-.015,.0145,
-.014878,.015889,
-.014518,.017236,
-.013928,.0185,
-.013128,.019642,
-.012142,.020628,
-.011,.021428,
-.009736,.022018,
-.008389,.022378,
-.007,.0225,
.007,.0225,
0.0*
%
%ADD37MACRO37*%
%ADD73R,.136X.136*%
%ADD10C,.296*%
%ADD59R,.272X.272*%
%ADD49O,.552X.788*%
%ADD80R,.059X.079*%
%AMMACRO68*
4,1,40,-.008,-.012,
.008,-.012,
.008695,-.011939,
.009368,-.011759,
.01,-.011464,
.010571,-.011064,
.011064,-.010571,
.011464,-.01,
.011759,-.009368,
.011939,-.008695,
.012,-.008,
.012,.008,
.011939,.008695,
.011759,.009368,
.011464,.01,
.011064,.010571,
.010571,.011064,
.01,.011464,
.009368,.011759,
.008695,.011939,
.008,.012,
-.008,.012,
-.008695,.011939,
-.009368,.011759,
-.01,.011464,
-.010571,.011064,
-.011064,.010571,
-.011464,.01,
-.011759,.009368,
-.011939,.008695,
-.012,.008,
-.012,-.008,
-.011939,-.008695,
-.011759,-.009368,
-.011464,-.01,
-.011064,-.010571,
-.010571,-.011064,
-.01,-.011464,
-.009368,-.011759,
-.008695,-.011939,
-.008,-.012,
0.0*
%
%ADD68MACRO68*%
%AMMACRO29*
4,1,40,.012,-.008,
.012,.008,
.011939,.008695,
.011759,.009368,
.011464,.01,
.011064,.010571,
.010571,.011064,
.01,.011464,
.009368,.011759,
.008695,.011939,
.008,.012,
-.008,.012,
-.008695,.011939,
-.009368,.011759,
-.01,.011464,
-.010571,.011064,
-.011064,.010571,
-.011464,.01,
-.011759,.009368,
-.011939,.008695,
-.012,.008,
-.012,-.008,
-.011939,-.008695,
-.011759,-.009368,
-.011464,-.01,
-.011064,-.010571,
-.010571,-.011064,
-.01,-.011464,
-.009368,-.011759,
-.008695,-.011939,
-.008,-.012,
.008,-.012,
.008695,-.011939,
.009368,-.011759,
.01,-.011464,
.010571,-.011064,
.011064,-.010571,
.011464,-.01,
.011759,-.009368,
.011939,-.008695,
.012,-.008,
0.0*
%
%ADD29MACRO29*%
%AMMACRO24*
4,1,40,-.007,-.011,
.007,-.011,
.007695,-.010939,
.008368,-.010759,
.009,-.010464,
.009571,-.010064,
.010064,-.009571,
.010464,-.009,
.010759,-.008368,
.010939,-.007695,
.011,-.007,
.011,.007,
.010939,.007695,
.010759,.008368,
.010464,.009,
.010064,.009571,
.009571,.010064,
.009,.010464,
.008368,.010759,
.007695,.010939,
.007,.011,
-.007,.011,
-.007695,.010939,
-.008368,.010759,
-.009,.010464,
-.009571,.010064,
-.010064,.009571,
-.010464,.009,
-.010759,.008368,
-.010939,.007695,
-.011,.007,
-.011,-.007,
-.010939,-.007695,
-.010759,-.008368,
-.010464,-.009,
-.010064,-.009571,
-.009571,-.010064,
-.009,-.010464,
-.008368,-.010759,
-.007695,-.010939,
-.007,-.011,
0.0*
%
%ADD24MACRO24*%
%AMMACRO22*
4,1,40,-.011,.007,
-.011,-.007,
-.010939,-.007695,
-.010759,-.008368,
-.010464,-.009,
-.010064,-.009571,
-.009571,-.010064,
-.009,-.010464,
-.008368,-.010759,
-.007695,-.010939,
-.007,-.011,
.007,-.011,
.007695,-.010939,
.008368,-.010759,
.009,-.010464,
.009571,-.010064,
.010064,-.009571,
.010464,-.009,
.010759,-.008368,
.010939,-.007695,
.011,-.007,
.011,.007,
.010939,.007695,
.010759,.008368,
.010464,.009,
.010064,.009571,
.009571,.010064,
.009,.010464,
.008368,.010759,
.007695,.010939,
.007,.011,
-.007,.011,
-.007695,.010939,
-.008368,.010759,
-.009,.010464,
-.009571,.010064,
-.010064,.009571,
-.010464,.009,
-.010759,.008368,
-.010939,.007695,
-.011,.007,
0.0*
%
%ADD22MACRO22*%
%AMMACRO88*
4,1,45,.25591,.11811,
.25591,-.11811,
.252022,-.162547,
.240477,-.205635,
.221625,-.246062,
.19604,-.282603,
.164498,-.314145,
.127958,-.33973,
.08753,-.358582,
.044442,-.370127,
.000005,-.374015,
-.044432,-.370127,
-.08752,-.358582,
-.127947,-.33973,
-.164488,-.314145,
-.19603,-.282603,
-.221615,-.246063,
-.240467,-.205635,
-.252012,-.162547,
-.2559,-.11811,
-.2559,.11811,
-.252012,.162547,
-.240467,.205634,
-.221616,.246061,
-.19603,.282601,
-.164488,.314143,
-.127949,.339728,
-.087521,.35858,
-.044434,.370125,
.000003,.374013,
.04444,.370125,
.087526,.35858,
.127954,.339728,
.16179,.31638,
.165832,.290964,
.174225,.266637,
.186715,.244136,
.202923,.224146,
.222356,.207275,
.24439,.19405,
.248391,.17971,
.251551,.165162,
.25386,.150455,
.25531,.135639,
.255896,.120763,
.25591,.11811,
0.0*
%
%ADD88MACRO88*%
%AMMACRO47*
4,1,40,.013,.017,
-.013,.017,
-.013695,.016939,
-.014368,.016759,
-.015,.016464,
-.015571,.016064,
-.016064,.015571,
-.016464,.015,
-.016759,.014368,
-.016939,.013695,
-.017,.013,
-.017,-.013,
-.016939,-.013695,
-.016759,-.014368,
-.016464,-.015,
-.016064,-.015571,
-.015571,-.016064,
-.015,-.016464,
-.014368,-.016759,
-.013695,-.016939,
-.013,-.017,
.013,-.017,
.013695,-.016939,
.014368,-.016759,
.015,-.016464,
.015571,-.016064,
.016064,-.015571,
.016464,-.015,
.016759,-.014368,
.016939,-.013695,
.017,-.013,
.017,.013,
.016939,.013695,
.016759,.014368,
.016464,.015,
.016064,.015571,
.015571,.016064,
.015,.016464,
.014368,.016759,
.013695,.016939,
.013,.017,
0.0*
%
%ADD47MACRO47*%
%AMMACRO16*
4,1,40,.017,-.013,
.017,.013,
.016939,.013695,
.016759,.014368,
.016464,.015,
.016064,.015571,
.015571,.016064,
.015,.016464,
.014368,.016759,
.013695,.016939,
.013,.017,
-.013,.017,
-.013695,.016939,
-.014368,.016759,
-.015,.016464,
-.015571,.016064,
-.016064,.015571,
-.016464,.015,
-.016759,.014368,
-.016939,.013695,
-.017,.013,
-.017,-.013,
-.016939,-.013695,
-.016759,-.014368,
-.016464,-.015,
-.016064,-.015571,
-.015571,-.016064,
-.015,-.016464,
-.014368,-.016759,
-.013695,-.016939,
-.013,-.017,
.013,-.017,
.013695,-.016939,
.014368,-.016759,
.015,-.016464,
.015571,-.016064,
.016064,-.015571,
.016464,-.015,
.016759,-.014368,
.016939,-.013695,
.017,-.013,
0.0*
%
%ADD16MACRO16*%
%AMMACRO65*
4,1,40,-.023,.013,
-.023,-.013,
-.022939,-.013695,
-.022759,-.014368,
-.022464,-.015,
-.022064,-.015571,
-.021571,-.016064,
-.021,-.016464,
-.020368,-.016759,
-.019695,-.016939,
-.019,-.017,
.019,-.017,
.019695,-.016939,
.020368,-.016759,
.021,-.016464,
.021571,-.016064,
.022064,-.015571,
.022464,-.015,
.022759,-.014368,
.022939,-.013695,
.023,-.013,
.023,.013,
.022939,.013695,
.022759,.014368,
.022464,.015,
.022064,.015571,
.021571,.016064,
.021,.016464,
.020368,.016759,
.019695,.016939,
.019,.017,
-.019,.017,
-.019695,.016939,
-.020368,.016759,
-.021,.016464,
-.021571,.016064,
-.022064,.015571,
-.022464,.015,
-.022759,.014368,
-.022939,.013695,
-.023,.013,
0.0*
%
%ADD65MACRO65*%
%AMMACRO67*
4,1,40,-.008,-.012,
.008,-.012,
.008695,-.011939,
.009368,-.011759,
.01,-.011464,
.010571,-.011064,
.011064,-.010571,
.011464,-.01,
.011759,-.009368,
.011939,-.008695,
.012,-.008,
.012,.008,
.011939,.008695,
.011759,.009368,
.011464,.01,
.011064,.010571,
.010571,.011064,
.01,.011464,
.009368,.011759,
.008695,.011939,
.008,.012,
-.008,.012,
-.008695,.011939,
-.009368,.011759,
-.01,.011464,
-.010571,.011064,
-.011064,.010571,
-.011464,.01,
-.011759,.009368,
-.011939,.008695,
-.012,.008,
-.012,-.008,
-.011939,-.008695,
-.011759,-.009368,
-.011464,-.01,
-.011064,-.010571,
-.010571,-.011064,
-.01,-.011464,
-.009368,-.011759,
-.008695,-.011939,
-.008,-.012,
0.0*
%
%ADD67MACRO67*%
%AMMACRO30*
4,1,40,.012,-.008,
.012,.008,
.011939,.008695,
.011759,.009368,
.011464,.01,
.011064,.010571,
.010571,.011064,
.01,.011464,
.009368,.011759,
.008695,.011939,
.008,.012,
-.008,.012,
-.008695,.011939,
-.009368,.011759,
-.01,.011464,
-.010571,.011064,
-.011064,.010571,
-.011464,.01,
-.011759,.009368,
-.011939,.008695,
-.012,.008,
-.012,-.008,
-.011939,-.008695,
-.011759,-.009368,
-.011464,-.01,
-.011064,-.010571,
-.010571,-.011064,
-.01,-.011464,
-.009368,-.011759,
-.008695,-.011939,
-.008,-.012,
.008,-.012,
.008695,-.011939,
.009368,-.011759,
.01,-.011464,
.010571,-.011064,
.011064,-.010571,
.011464,-.01,
.011759,-.009368,
.011939,-.008695,
.012,-.008,
0.0*
%
%ADD30MACRO30*%
%AMMACRO25*
4,1,40,-.007,-.011,
.007,-.011,
.007695,-.010939,
.008368,-.010759,
.009,-.010464,
.009571,-.010064,
.010064,-.009571,
.010464,-.009,
.010759,-.008368,
.010939,-.007695,
.011,-.007,
.011,.007,
.010939,.007695,
.010759,.008368,
.010464,.009,
.010064,.009571,
.009571,.010064,
.009,.010464,
.008368,.010759,
.007695,.010939,
.007,.011,
-.007,.011,
-.007695,.010939,
-.008368,.010759,
-.009,.010464,
-.009571,.010064,
-.010064,.009571,
-.010464,.009,
-.010759,.008368,
-.010939,.007695,
-.011,.007,
-.011,-.007,
-.010939,-.007695,
-.010759,-.008368,
-.010464,-.009,
-.010064,-.009571,
-.009571,-.010064,
-.009,-.010464,
-.008368,-.010759,
-.007695,-.010939,
-.007,-.011,
0.0*
%
%ADD25MACRO25*%
%AMMACRO23*
4,1,40,-.011,.007,
-.011,-.007,
-.010939,-.007695,
-.010759,-.008368,
-.010464,-.009,
-.010064,-.009571,
-.009571,-.010064,
-.009,-.010464,
-.008368,-.010759,
-.007695,-.010939,
-.007,-.011,
.007,-.011,
.007695,-.010939,
.008368,-.010759,
.009,-.010464,
.009571,-.010064,
.010064,-.009571,
.010464,-.009,
.010759,-.008368,
.010939,-.007695,
.011,-.007,
.011,.007,
.010939,.007695,
.010759,.008368,
.010464,.009,
.010064,.009571,
.009571,.010064,
.009,.010464,
.008368,.010759,
.007695,.010939,
.007,.011,
-.007,.011,
-.007695,.010939,
-.008368,.010759,
-.009,.010464,
-.009571,.010064,
-.010064,.009571,
-.010464,.009,
-.010759,.008368,
-.010939,.007695,
-.011,.007,
0.0*
%
%ADD23MACRO23*%
%ADD114C,.012*%
%ADD115C,.014*%
%ADD116C,.015*%
%ADD117C,.024*%
%ADD118C,.016*%
%ADD119C,.006*%
%ADD120C,.005*%
%ADD121C,.0065*%
%ADD122C,.00675*%
%ADD123C,.09204*%
%ADD127C,.06604*%
%ADD126C,.324*%
%ADD125C,.3222*%
%ADD124R,.008X.008*%
%ADD128C,.13704*%
%ADD129R,.29604X.29604*%
G75*
%LPD*%
G75*
G36*
G01X399235Y166022D02*
X408292Y190592D01*
X410100Y192400D01*
X411900D01*
X413168Y191132D01*
Y177529D01*
X413167Y177521D01*
G03Y175079I16057J-1221D01*
G01X413168Y175071D01*
Y163555D01*
X419382D01*
G03X436300Y161835I9842J12745D01*
G01X436341Y161855D01*
X445368D01*
Y160355D01*
X452369D01*
G03X463135Y157033I9831J12754D01*
G02X463558Y156634I23J-399D01*
G01Y154303D01*
X463517Y154250D01*
G03X460266Y143214I12802J-9768D01*
G01X460280Y143037D01*
X454343Y141868D01*
X453442Y140624D01*
X453323Y140642D01*
G03X443898Y139189I-2337J-16135D01*
G03X426062Y136765I-7087J-14682D01*
G03X413218Y120670I3662J-16095D01*
G01Y92323D01*
G03X413473Y89434I16506J1D01*
G03X413409Y87993I16251J-1444D01*
G01Y82056D01*
X408351D01*
Y62059D01*
X405512D01*
G03X398571Y55118I0J-6941D01*
G01Y3937D01*
G02X397638Y3004I-933J0D01*
G01X3937D01*
G02X3004Y3937I0J933D01*
G01Y10212D01*
G02X3691Y10491I400J0D01*
G03X23503Y8000I11466J11162D01*
G01X44929D01*
Y23001D01*
G03X23001Y50405I-29772J-1348D01*
G01X22854Y50445D01*
Y50446D01*
G03X8000Y50585I-7697J-28793D01*
G01Y35965D01*
G03X3691Y32815I7157J-14312D01*
G02X3004Y33094I-287J279D01*
G01Y461899D01*
G02X3678Y462191I400J0D01*
G03X8000Y459248I11482J12217D01*
G01Y445477D01*
G03X23001Y445656I7156J28932D01*
G01Y445657D01*
X23147Y445697D01*
G03X33502Y450921I-7990J28712D01*
G03X36125Y449365I9593J13182D01*
G01X36156Y449350D01*
X39760Y445746D01*
Y362346D01*
X56946Y345160D01*
X75154D01*
X81994Y352000D01*
X90745D01*
G03X101406Y334903I40456J13354D01*
G02X101126Y334217I-280J-286D01*
G01X90921D01*
Y315618D01*
G03X85293Y312667I4517J-15457D01*
G01X78731D01*
Y302670D01*
X78278Y302217D01*
X76481D01*
Y300420D01*
X48478Y272417D01*
X36381D01*
Y264087D01*
G03X36260Y263917I13058J-9423D01*
G01X32681D01*
Y255120D01*
X32436Y254875D01*
Y235947D01*
X32681Y235702D01*
Y207405D01*
X37978D01*
X40431Y204952D01*
Y198455D01*
X40631D01*
Y194455D01*
X43831D01*
Y192742D01*
X43747Y192683D01*
G03X49431Y163875I9340J-13122D01*
G01Y162155D01*
X56731D01*
Y161855D01*
X72631D01*
Y160555D01*
X90921D01*
Y121767D01*
X131127D01*
Y131957D01*
G03X134160Y145350I-12690J9914D01*
G02X134550Y145836I390J86D01*
G01X137865D01*
Y156186D01*
X144615D01*
Y162743D01*
G03X146310Y164752I-10767J10804D01*
G01X152608Y173680D01*
G03X154454Y177193I-12464J8791D01*
G01X160822Y194455D01*
X168043D01*
Y192771D01*
X167960Y192712D01*
G03X168043Y166551I9439J-13051D01*
G01Y163555D01*
X173643D01*
Y162155D01*
X180943D01*
Y161855D01*
X196943D01*
Y160555D01*
X215133D01*
Y121767D01*
X255339D01*
Y131957D01*
G03X258372Y145350I-12690J9914D01*
G02X258762Y145836I390J86D01*
G01X262077D01*
Y156186D01*
X268827D01*
Y161673D01*
X273853Y164855D01*
X284765Y194455D01*
X292256D01*
Y192771D01*
X292173Y192712D01*
G03X292256Y166551I9439J-13051D01*
G01Y163555D01*
X297856D01*
Y162155D01*
X305256D01*
Y161855D01*
X321256D01*
Y160355D01*
X339346D01*
Y146282D01*
G02X338916Y145883I-400J0D01*
G03X334890Y145676I-1192J-16062D01*
G03X334568Y145710I-1852J-15999D01*
G03X319034Y149103I-10756J-11988D01*
G03X300339Y141447I-4595J-15434D01*
G01X298264D01*
Y125537D01*
X296606D01*
Y120127D01*
X295677Y119198D01*
Y100509D01*
X296606Y99580D01*
Y88279D01*
G03X296006Y88005I6388J-14782D01*
G01X295965Y87985D01*
X290849D01*
Y84067D01*
X290801Y84011D01*
G03X287113Y70874I12199J-10511D01*
G03X290849Y57896I15916J-2445D01*
G01Y52373D01*
X301800D01*
X301808Y52372D01*
G03X304250I1221J16057D01*
G01X304258Y52373D01*
X309973D01*
Y52239D01*
X320115D01*
G03X321530Y49688I14731J6503D01*
G01X321565Y49637D01*
Y46729D01*
X322723D01*
Y42539D01*
X352419D01*
G03X357964Y42536I2781J15861D01*
G01X357981Y42539D01*
X358735D01*
Y42689D01*
X358889Y42725D01*
G03X371294Y57853I-3689J15675D01*
G03X377503Y67382I-9518J12989D01*
G03X378479Y68672I-12340J10350D01*
G03X379847Y68845I-1334J16048D01*
G03X383029Y69731I-2706J15874D01*
G03X392597Y89250I-5885J14989D01*
G03X381268Y111685I-14653J6679D01*
G01Y111976D01*
X379286D01*
X379278Y111977D01*
G03X376610I-1334J-16048D01*
G01X376602Y111976D01*
X373217D01*
X373200Y111979D01*
G03X371007Y112211I-2808J-16059D01*
G01Y121767D01*
X379552D01*
Y131957D01*
G03X382585Y145350I-12690J9914D01*
G02X382975Y145836I390J86D01*
G01X386290D01*
Y156186D01*
X393040D01*
Y162101D01*
X399235Y166022D01*
G37*
G36*
G01X385423Y1366803D02*
X223928Y1268500D01*
X212967D01*
Y1296746D01*
X205909D01*
X197715Y1304940D01*
X172496D01*
G03X93880Y1315014I-41296J-10474D01*
G02X93235Y1314937I-350J193D01*
G03X77088Y1321108I-14235J-13037D01*
G03X61789Y1333357I-16334J-4723D01*
G02X61418Y1333819I24J399D01*
G03X50406Y1351709I-15900J2547D01*
G01X50267Y1351754D01*
Y1351802D01*
G03X41791Y1352080I-4749J-15436D01*
G01X40630Y1351709D01*
G03X40422Y1351641I4900J-15339D01*
G03X43529Y1319608I957J-16074D01*
G02X43977Y1319146I53J-396D01*
G03X47615Y1305594I16777J-2761D01*
G02X47306Y1304940I-309J-254D01*
G01X44571D01*
X28497Y1288866D01*
Y1243633D01*
G03X23670Y1238792I8730J-13531D01*
G01X23611Y1238700D01*
X23001D01*
Y1238714D01*
X8000D01*
Y1099936D01*
X26851D01*
G03X28155Y1099999I-124J16102D01*
G01X28164Y1100000D01*
X37000D01*
Y1086670D01*
X36999Y1086660D01*
G03X43831Y1071850I16028J-1587D01*
G01Y1068967D01*
X49431D01*
Y1067667D01*
X56731D01*
Y1067367D01*
X72731D01*
Y1066067D01*
X90921D01*
Y1027279D01*
X124571D01*
G02X124777Y1026536I0J-400D01*
G03X120404Y1022682I8287J-13811D01*
G03X119459Y1022851I-3341J-15957D01*
G03X116063Y1023228I-3398J-15126D01*
G01X101463D01*
G03X91299Y1019431I0J-15502D01*
G01X86057D01*
Y1014021D01*
X86018Y1013968D01*
G03X83005Y1005891I12445J-9243D01*
G01X82991Y1005706D01*
X78600D01*
G03X63814Y996408I0J-16406D01*
G03X50794Y967013I-5639J-15083D01*
G01Y934249D01*
X51433D01*
G02X51832Y933826I0J-400D01*
G03X52769Y927380I16277J-925D01*
G01Y910400D01*
X33602D01*
X33594Y910401D01*
G03X26873Y910093I-2097J-27724D01*
G01X26857Y910090D01*
X8000D01*
Y854875D01*
X31703D01*
G03X32689Y854900I-212J27802D01*
G01X52769D01*
Y843990D01*
X51403D01*
Y809375D01*
X8000Y765972D01*
Y646968D01*
X27024D01*
X27025Y646969D01*
X27108D01*
G03X31990Y647715I37J16103D01*
G03X36061Y648588I-1313J16049D01*
G01X36093Y648600D01*
X40600D01*
Y642490D01*
X40556Y642435D01*
G03X49431Y616631I12531J-10118D01*
G01Y614911D01*
X56731D01*
Y614611D01*
X69090D01*
Y613525D01*
X71235D01*
G03X90391Y606412I13911J8112D01*
G02X90921Y606034I130J-378D01*
G01Y574523D01*
X110900D01*
Y569031D01*
G03X103357Y555225I8863J-13806D01*
G01Y546225D01*
G03X119763Y529819I16406J0D01*
G01X124263D01*
G03X140669Y546225I0J16406D01*
G01Y552619D01*
X145583D01*
Y550690D01*
X152144Y544129D01*
Y538144D01*
X158129D01*
X158526Y537747D01*
X158641D01*
G02X158962Y537108I0J-400D01*
G03X155847Y529159I12899J-9640D01*
G01X155828Y528980D01*
X152305D01*
Y524148D01*
X146851D01*
Y489636D01*
X152642D01*
Y426457D01*
G02X152046Y426109I-400J0D01*
G03X90283Y400818I-20845J-37155D01*
G01X90269Y400769D01*
X89100Y399600D01*
X87900D01*
X87389Y400111D01*
Y418680D01*
G03Y429720I-15340J5520D01*
G01Y481494D01*
X89206D01*
Y520506D01*
X83347D01*
G03X79211Y523241I-10846J-11907D01*
G01X79094Y523295D01*
Y524153D01*
X77890D01*
Y526286D01*
X77891Y526294D01*
G03Y528736I-16057J1221D01*
G01X77890Y528744D01*
Y529126D01*
X77857D01*
X77837Y529304D01*
G03X54716Y541960I-16003J-1789D01*
G03X31604Y529300I-7109J-14449D01*
G01X31584Y529122D01*
X28051D01*
Y524190D01*
X8000D01*
Y489570D01*
G03X3678Y486627I7160J-15160D01*
G02X3004Y486919I-274J292D01*
G01Y949606D01*
X3001D01*
Y1028346D01*
X3004D01*
Y1370866D01*
G02X3937Y1371799I933J0D01*
G01X746850D01*
G03X753791Y1378740I0J6941D01*
G01Y1464567D01*
G02X754724Y1465500I933J0D01*
G01X783465D01*
G03X790406Y1472441I0J6941D01*
G01Y1654331D01*
G02X791339Y1655264I933J0D01*
G01X799372D01*
Y1650268D01*
X795402D01*
Y1472441D01*
G02X795364Y1471483I-11937J-6D01*
G03X794795Y1468683I1484J-1759D01*
G02X783465Y1460504I-11330J3758D01*
G01X778175D01*
Y1445503D01*
X783465D01*
G03X794244Y1447754I-1J26938D01*
G03X800850Y1445594I8190J13865D01*
G03X810705Y1444837I6101J14902D01*
G01X815957Y1439585D01*
X852394D01*
Y1419694D01*
X855376D01*
X855392Y1419512D01*
G03X857854Y1412274I16041J1418D01*
G03X858052Y1408399I16064J-1122D01*
G03X861293Y1394302I15642J-3825D01*
G01X861339Y1394247D01*
Y1391491D01*
X861638D01*
Y1391214D01*
X861587Y1391157D01*
G03X857706Y1377639I11983J-10756D01*
G03X857609Y1375063I15994J-1892D01*
G03X857208Y1374634I11927J-11550D01*
G01X852566D01*
Y1341801D01*
X825244Y1336331D01*
X824540Y1336800D01*
X810679Y1334029D01*
X810678Y1334028D01*
X806555Y1333204D01*
X806553Y1333202D01*
X805716Y1333034D01*
X805662Y1333206D01*
G03X787828Y1344324I-15372J-4796D01*
G03X783905Y1344379I-2186J-15954D01*
G03X777206Y1344067I-2617J-15889D01*
G03X760743Y1339111I-4306J-15517D01*
G03X760122Y1338671I8997J-13356D01*
G01X760051Y1338618D01*
X694920Y1351802D01*
Y1366803D01*
X385423D01*
G37*
G36*
G01X90937Y200161D02*
X72437D01*
X71437Y201161D01*
Y210161D01*
X72437Y211161D01*
X90937D01*
X91937Y210161D01*
Y201161D01*
X90937Y200161D01*
G37*
G36*
G01X67937Y241161D02*
X48437D01*
X47437Y242161D01*
Y248661D01*
X48437Y249661D01*
X56937D01*
X58937Y251661D01*
Y261661D01*
X89437Y292161D01*
X122937D01*
X123437Y291661D01*
Y284661D01*
X122937Y284161D01*
X99437D01*
X96937Y281661D01*
X90437D01*
X73437Y264661D01*
Y250661D01*
X68937Y246161D01*
Y242161D01*
X67937Y241161D01*
G37*
G36*
G01X62937Y220720D02*
X59378Y217161D01*
X58937D01*
X58607Y216831D01*
X58587Y216819D01*
G03X58079Y216311I850J-1358D01*
G01X58067Y216291D01*
X57937Y216161D01*
Y216023D01*
X57926Y215991D01*
G03X57836Y215461I1511J-529D01*
G01Y213861D01*
G03X57848Y213665I1601J0D01*
G01Y213572D01*
X57437Y213161D01*
X55937D01*
X51937Y217161D01*
X49437D01*
X47937Y218661D01*
Y228661D01*
X48937Y229661D01*
X61937D01*
X62937Y228661D01*
Y220720D01*
G37*
G36*
G01X67937Y693917D02*
X48437D01*
X47437Y694917D01*
Y701417D01*
X48437Y702417D01*
X56937D01*
X58937Y704417D01*
Y714417D01*
X89437Y744917D01*
X122937D01*
X123437Y744417D01*
Y737417D01*
X122937Y736917D01*
X99437D01*
X96937Y734417D01*
X90437D01*
X73437Y717417D01*
Y703417D01*
X68937Y698917D01*
Y694917D01*
X67937Y693917D01*
G37*
G36*
G01X62937Y673476D02*
X59378Y669917D01*
X58937D01*
X58607Y669587D01*
X58587Y669575D01*
G03X58079Y669067I850J-1358D01*
G01X58067Y669047D01*
X57937Y668917D01*
Y668779D01*
X57926Y668747D01*
G03X57836Y668217I1511J-529D01*
G01Y666617D01*
G03X57848Y666421I1601J0D01*
G01Y666328D01*
X57437Y665917D01*
X55937D01*
X51937Y669917D01*
X49437D01*
X47937Y671417D01*
Y681417D01*
X48937Y682417D01*
X61937D01*
X62937Y681417D01*
Y673476D01*
G37*
G36*
G01X90937Y652917D02*
X72437D01*
X71437Y653917D01*
Y662917D01*
X72437Y663917D01*
X90937D01*
X91937Y662917D01*
Y653917D01*
X90937Y652917D01*
G37*
G36*
G01X87389Y798795D02*
Y804800D01*
X90729D01*
G03X101405Y787659I40470J13311D01*
G02X101125Y786973I-280J-286D01*
G01X90921D01*
Y768374D01*
G03X85293Y765423I4517J-15457D01*
G01X78731D01*
Y755426D01*
X78278Y754973D01*
X76481D01*
Y753176D01*
X48478Y725173D01*
X47140D01*
Y754687D01*
G03X49943Y761299I-13240J9513D01*
G01X49954Y761360D01*
X87389Y798795D01*
G37*
G36*
G01X62937Y1126232D02*
X59378Y1122673D01*
X58937D01*
X58607Y1122343D01*
X58587Y1122331D01*
G03X58079Y1121823I850J-1358D01*
G01X58067Y1121803D01*
X57937Y1121673D01*
Y1121535D01*
X57926Y1121503D01*
G03X57836Y1120973I1511J-529D01*
G01Y1119373D01*
G03X57848Y1119177I1601J0D01*
G01Y1119084D01*
X57437Y1118673D01*
X55937D01*
X51937Y1122673D01*
X49437D01*
X47937Y1124173D01*
Y1134173D01*
X48937Y1135173D01*
X61937D01*
X62937Y1134173D01*
Y1126232D01*
G37*
G36*
G01X90937Y1105673D02*
X72437D01*
X71437Y1106673D01*
Y1115673D01*
X72437Y1116673D01*
X90937D01*
X91937Y1115673D01*
Y1106673D01*
X90937Y1105673D01*
G37*
G36*
G01X67937Y1146673D02*
X48437D01*
X47437Y1147673D01*
Y1154173D01*
X48437Y1155173D01*
X56937D01*
X58937Y1157173D01*
Y1167173D01*
X89437Y1197673D01*
X122937D01*
X123437Y1197173D01*
Y1190173D01*
X122937Y1189673D01*
X99437D01*
X96937Y1187173D01*
X90437D01*
X73437Y1170173D01*
Y1156173D01*
X68937Y1151673D01*
Y1147673D01*
X67937Y1146673D01*
G37*
G36*
G01X67940Y1214246D02*
X86349Y1232655D01*
Y1257500D01*
X90749D01*
G03X101406Y1240415I40452J13366D01*
G02X101126Y1239729I-280J-286D01*
G01X90921D01*
Y1221130D01*
G03X85293Y1218179I4517J-15457D01*
G01X78731D01*
Y1208182D01*
X78278Y1207729D01*
X76481D01*
Y1205932D01*
X69452Y1198902D01*
G02X68772Y1199235I-283J282D01*
G03X67952Y1206787I-16172J2065D01*
G01X67940Y1206820D01*
Y1214246D01*
G37*
G36*
G01X77437Y251161D02*
X76937Y251661D01*
Y257661D01*
X82437Y263161D01*
X87937D01*
X98186Y273410D01*
X98188D01*
Y273412D01*
X107437Y282661D01*
X122937D01*
X123437Y282161D01*
Y279161D01*
X122937Y278661D01*
X109937D01*
X82437Y251161D01*
X77437D01*
G37*
G36*
G01X97600Y236500D02*
X90037D01*
X89937Y236600D01*
Y242161D01*
X90437Y242661D01*
X95437D01*
X105437Y252661D01*
X122937D01*
X123437Y252161D01*
Y249161D01*
X122937Y248661D01*
X109761D01*
X97600Y236500D01*
G37*
G36*
G01X77437Y223161D02*
X76437Y224161D01*
Y233161D01*
X77437Y234161D01*
Y242161D01*
X79768Y244492D01*
G03X80306Y245030I-831J1369D01*
G01X80437Y245161D01*
Y245299D01*
X80448Y245331D01*
G03X80538Y245861I-1511J529D01*
G01Y248262D01*
X81937Y249661D01*
X83437D01*
X95937Y262161D01*
X122937D01*
X123437Y261661D01*
Y254661D01*
X122937Y254161D01*
X102937D01*
X95437Y246661D01*
X91937D01*
X88437Y243161D01*
Y233161D01*
X90937Y230661D01*
Y224161D01*
X89937Y223161D01*
X77437D01*
G37*
G36*
G01X109396Y699313D02*
X99283Y689200D01*
X90237D01*
X89937Y689500D01*
Y694917D01*
X90437Y695417D01*
X95437D01*
X105437Y705417D01*
X122937D01*
X123437Y704917D01*
Y701917D01*
X122937Y701417D01*
X111500D01*
X110372Y700289D01*
X110346Y700275D01*
G03X109410Y699339I1091J-2027D01*
G01X109396Y699313D01*
G37*
G36*
G01X77437Y675917D02*
X76437Y676917D01*
Y685917D01*
X77437Y686917D01*
Y694917D01*
X79767Y697247D01*
X79787Y697259D01*
G03X80295Y697767I-850J1358D01*
G01X80307Y697787D01*
X80437Y697917D01*
Y698055D01*
X80448Y698087D01*
G03X80538Y698617I-1511J529D01*
G01Y701018D01*
X81937Y702417D01*
X83437D01*
X95937Y714917D01*
X122937D01*
X123437Y714417D01*
Y707417D01*
X122937Y706917D01*
X102937D01*
X95437Y699417D01*
X91937D01*
X88437Y695917D01*
Y685917D01*
X90937Y683417D01*
Y676917D01*
X89937Y675917D01*
X77437D01*
G37*
G36*
G01Y703917D02*
X76937Y704417D01*
Y710417D01*
X82437Y715917D01*
X87937D01*
X98186Y726166D01*
X98188D01*
Y726168D01*
X107437Y735417D01*
X122937D01*
X123437Y734917D01*
Y731917D01*
X122937Y731417D01*
X109937D01*
X82437Y703917D01*
X77437D01*
G37*
G36*
G01X87389Y854600D02*
Y917580D01*
G03X87401Y928587I-15340J5520D01*
G01X87389Y928620D01*
Y934249D01*
X89206D01*
Y950144D01*
X91429D01*
X91826Y949747D01*
X100238D01*
Y948319D01*
X102557D01*
X102752Y948124D01*
X107892D01*
G03X129824Y947557I11271J11501D01*
G03X156274Y950529I12154J11015D01*
G01X158234D01*
Y955556D01*
X158262D01*
Y956600D01*
X158263Y956612D01*
G03Y960532I-16285J1960D01*
G01X158262Y960544D01*
Y976234D01*
X158264Y976247D01*
G03X158399Y979008I-16258J2179D01*
G02X158799Y979422I400J14D01*
G01X167320D01*
G02X167707Y978921I0J-400D01*
G03X167178Y974789I15877J-4133D01*
G01Y969789D01*
G03X170508Y959881I16405J0D01*
G03X167911Y951112I13509J-8770D01*
G01Y945612D01*
G03X175711Y931813I16106J0D01*
G03X184028Y925916I12995J9515D01*
G03X183876Y921608I15872J-2717D01*
G03X183373Y917713I14837J-3896D01*
G01Y853267D01*
X181474Y851368D01*
G03X177378Y843990I10847J-10848D01*
G01X173742D01*
X173731Y844178D01*
G03X90594Y854600I-42531J-2469D01*
G01X87389D01*
G37*
G36*
G01X108054Y985623D02*
G03X110565Y988089I9J2502D01*
G01X110568Y988286D01*
X121457D01*
X122200Y987543D01*
Y970026D01*
X122142D01*
Y963768D01*
X121500Y963125D01*
X108966D01*
X107853Y964238D01*
Y985423D01*
G02X108054Y985623I200J0D01*
G37*
G36*
G01X98040Y964748D02*
X93884Y968904D01*
Y978039D01*
X94676Y978831D01*
X100583D01*
X100614Y978821D01*
G03X102192I789J2374D01*
G01X102223Y978831D01*
X105223D01*
X105652Y978402D01*
Y965158D01*
X105242Y964748D01*
X98040D01*
G37*
G36*
G01X106663Y997725D02*
X104663Y999725D01*
Y1004525D01*
X105263Y1005125D01*
X114563D01*
X116263Y1003425D01*
Y1001625D01*
X117963Y999925D01*
Y998125D01*
X117563Y997725D01*
X113892D01*
X113853Y997742D01*
G03X113200Y997882I-655J-1462D01*
G01X111800D01*
G03X111147Y997742I2J-1602D01*
G01X111108Y997725D01*
X109625D01*
X109593Y997736D01*
G03X109063Y997826I-529J-1511D01*
G01X107663D01*
G03X107133Y997736I-1J-1601D01*
G01X107101Y997725D01*
X106663D01*
G37*
G36*
G01X77437Y1128673D02*
X76437Y1129673D01*
Y1138673D01*
X77437Y1139673D01*
Y1147673D01*
X79767Y1150003D01*
X79787Y1150015D01*
G03X80295Y1150523I-850J1358D01*
G01X80307Y1150543D01*
X80437Y1150673D01*
Y1150811D01*
X80448Y1150843D01*
G03X80538Y1151373I-1511J529D01*
G01Y1153774D01*
X81937Y1155173D01*
X83437D01*
X95937Y1167673D01*
X122937D01*
X123437Y1167173D01*
Y1160173D01*
X122937Y1159673D01*
X102937D01*
X95437Y1152173D01*
X91937D01*
X88437Y1148673D01*
Y1138673D01*
X90937Y1136173D01*
Y1129673D01*
X89937Y1128673D01*
X77437D01*
G37*
G36*
G01Y1156673D02*
X76937Y1157173D01*
Y1163173D01*
X82437Y1168673D01*
X87937D01*
X98186Y1178922D01*
X98188D01*
Y1178924D01*
X107437Y1188173D01*
X122937D01*
X123437Y1187673D01*
Y1184673D01*
X122937Y1184173D01*
X109937D01*
X82437Y1156673D01*
X77437D01*
G37*
G36*
G01X110372Y1153045D02*
X110346Y1153031D01*
G03X109410Y1152095I1091J-2027D01*
G01X109396Y1152069D01*
X98627Y1141300D01*
X90637D01*
X89937Y1142000D01*
Y1147673D01*
X90437Y1148173D01*
X95437D01*
X105437Y1158173D01*
X122937D01*
X123437Y1157673D01*
Y1154673D01*
X122937Y1154173D01*
X111500D01*
X110372Y1153045D01*
G37*
G36*
G01X154285Y279015D02*
G03X138864Y287229I-14348J-8354D01*
G02X138438Y287628I-26J399D01*
G01Y297875D01*
X137865Y298448D01*
Y310148D01*
X134550D01*
G02X134160Y310634I0J400D01*
G03X132376Y322178I-15723J3480D01*
G02X132708Y322778I346J200D01*
G03X171016Y350193I-1506J42577D01*
G02X171672Y350334I374J-142D01*
G01X179746Y342260D01*
X196654D01*
X206467Y352073D01*
X212967D01*
Y391235D01*
X211601D01*
Y391980D01*
X211613Y392013D01*
G03X211601Y403020I-15352J5487D01*
G01Y481494D01*
X213418D01*
Y520506D01*
X207559D01*
G03X203464Y523222I-10845J-11907D01*
G01X203348Y523276D01*
Y524111D01*
X202144D01*
Y526244D01*
X202145Y526252D01*
G03Y528694I-16057J1221D01*
G01X202144Y528702D01*
Y528984D01*
X202121D01*
X202102Y529163D01*
G03X201405Y532443I-16014J-1689D01*
G02X201991Y532909I381J123D01*
G03X224066Y538432I8272J13816D01*
G01X224124Y538529D01*
X224934D01*
Y540087D01*
X224952Y540126D01*
G03X226322Y547915I-14689J6599D01*
G03X226327Y553504I-16059J2809D01*
G02X226721Y553972I394J68D01*
G01X228199D01*
X228224Y553965D01*
G03X234606Y553572I4174J15760D01*
G03X236944Y547981I16044J3425D01*
G03X234480Y539420I13642J-8561D01*
G01Y533920D01*
G03X241590Y520561I16105J0D01*
G03X255203Y513062I13613J8606D01*
G01X260703D01*
G03X270382Y516295I0J16105D01*
G02X271022Y515975I240J-320D01*
G01Y489636D01*
X275998D01*
X276023Y489465D01*
G03X276219Y488385I16130J2369D01*
G03X299233Y471596I15934J-2326D01*
G03X310127Y470359I7155J14426D01*
G03X315925Y469279I5798J15026D01*
G01X320925D01*
G03X336554Y481494I0J16106D01*
G01X337631D01*
Y520506D01*
X331772D01*
G03X327636Y523241I-10846J-11907D01*
G01X327519Y523295D01*
Y524111D01*
X326315D01*
Y526244D01*
X326316Y526252D01*
G03Y528694I-16057J1221D01*
G01X326315Y528702D01*
Y528984D01*
X326292D01*
X326273Y529163D01*
G03X303141Y541918I-16014J-1690D01*
G03X282241Y535782I-7109J-14449D01*
G02X281498Y535988I-343J206D01*
G01Y539225D01*
G03X279141Y547613I-16106J-1D01*
G03X279592Y548319I-13596J9182D01*
G01X292263D01*
G03X308669Y564725I0J16406D01*
G01Y569725D01*
G03X307791Y575019I-16406J-1D01*
G03X305737Y593692I-14028J7906D01*
G03X290263Y605331I-15474J-4467D01*
G01X281111D01*
G03X275354Y614958I-15836J-2935D01*
G03X274012Y617201I-14447J-7121D01*
G03X276527Y620209I-10347J11206D01*
G01X281701Y628327D01*
X286034D01*
G03X297856Y616755I15578J4090D01*
G01Y614911D01*
X305156D01*
Y614611D01*
X317626D01*
Y613323D01*
X320027D01*
G03X338818Y606596I13655J8535D01*
G02X339346Y606217I128J-379D01*
G01Y574523D01*
X379552D01*
Y584713D01*
G03X382585Y598106I-12690J9914D01*
G02X382975Y598592I390J86D01*
G01X386290D01*
Y608942D01*
X393040D01*
Y613302D01*
X399446Y617380D01*
X405572Y626982D01*
X405629Y627241D01*
X410539D01*
G03X422068Y616655I15285J5076D01*
G01Y614911D01*
X429368D01*
Y614611D01*
X441797D01*
Y613576D01*
X444185D01*
G03X463029Y606842I13668J8515D01*
G02X463558Y606463I129J-379D01*
G01Y595761D01*
G03X486251Y574523I8464J-13699D01*
G01X496511D01*
Y550925D01*
X497143D01*
Y550570D01*
X496994Y550531D01*
G03X488363Y544892I4028J-15591D01*
G03X489490Y517477I8988J-13361D01*
G01Y495546D01*
G02X488907Y495191I-400J0D01*
G03X467365Y488529I-7374J-14316D01*
G03X462045Y489402I-5231J-15229D01*
G02X461844Y489602I-1J200D01*
G01Y520506D01*
X455985D01*
G03X451786Y523269I-10844J-11908D01*
G01X451669Y523323D01*
Y524074D01*
X450465D01*
Y526207D01*
X450466Y526215D01*
G03Y528657I-16057J1221D01*
G01X450465Y528665D01*
Y528947D01*
X450442D01*
X450423Y529126D01*
G03X427291Y541881I-16014J-1690D01*
G03X404168Y529122I-7109J-14449D01*
G01X404149Y528943D01*
X400626D01*
Y524111D01*
X395172D01*
Y490598D01*
X352493D01*
Y433392D01*
X352599D01*
G02X352707Y433023I0J-200D01*
G01X348946Y430627D01*
X221502Y349438D01*
X162167Y272867D01*
X159787D01*
G03X154285Y279015I-14350J-7306D01*
G37*
G36*
G01X137865Y598592D02*
Y608942D01*
X144615D01*
Y613645D01*
X146177Y614640D01*
G03X150846Y619309I-8195J12864D01*
G01X153251Y623083D01*
X153419Y622977D01*
G03X168644Y618656I14889J23480D01*
G02X169049Y618248I5J-400D01*
G03X169092Y616728I16100J-305D01*
G01X169093Y616720D01*
Y611228D01*
X168163D01*
G03X157664Y607131I1J-15503D01*
G01X152757D01*
Y602021D01*
X152718Y601968D01*
G03X149660Y592725I12445J-9245D01*
G01Y592720D01*
G02X149248Y592321I-400J1D01*
G03X137708Y587933I-484J-16096D01*
G03X134916Y586337I6555J-14708D01*
G01X134864Y586300D01*
X133100D01*
Y587314D01*
X133122Y587356D01*
G03X134476Y598106I-14369J7270D01*
G02X134866Y598592I390J86D01*
G01X137865D01*
G37*
G36*
G01X164740Y552748D02*
X160584Y556904D01*
Y566039D01*
X161376Y566831D01*
X167283D01*
X167314Y566821D01*
G03X168892I789J2374D01*
G01X168923Y566831D01*
X171923D01*
X172352Y566402D01*
Y553158D01*
X171942Y552748D01*
X164740D01*
G37*
G36*
G01X215149Y200161D02*
X196649D01*
X195649Y201161D01*
Y210161D01*
X196649Y211161D01*
X215149D01*
X216149Y210161D01*
Y201161D01*
X215149Y200161D01*
G37*
G36*
G01X201649Y251161D02*
X201149Y251661D01*
Y257661D01*
X206649Y263161D01*
X212149D01*
X222398Y273410D01*
X222400D01*
Y273412D01*
X231649Y282661D01*
X247149D01*
X247649Y282161D01*
Y279161D01*
X247149Y278661D01*
X234149D01*
X206649Y251161D01*
X201649D01*
G37*
G36*
G01X221149Y236000D02*
X215049D01*
X214149Y236900D01*
Y242161D01*
X214649Y242661D01*
X219649D01*
X229649Y252661D01*
X247149D01*
X247649Y252161D01*
Y249161D01*
X247149Y248661D01*
X233810D01*
X221149Y236000D01*
G37*
G36*
G01X192149Y241161D02*
X172649D01*
X171649Y242161D01*
Y248661D01*
X172649Y249661D01*
X181149D01*
X183149Y251661D01*
Y261661D01*
X213649Y292161D01*
X247149D01*
X247649Y291661D01*
Y284661D01*
X247149Y284161D01*
X223649D01*
X221149Y281661D01*
X214649D01*
X197649Y264661D01*
Y250661D01*
X193149Y246161D01*
Y242161D01*
X192149Y241161D01*
G37*
G36*
G01X201649Y223161D02*
X200649Y224161D01*
Y233161D01*
X201649Y234161D01*
Y242161D01*
X203980Y244492D01*
G03X204518Y245030I-831J1369D01*
G01X204649Y245161D01*
Y245299D01*
X204660Y245331D01*
G03X204750Y245861I-1511J529D01*
G01Y248262D01*
X206149Y249661D01*
X207649D01*
X220149Y262161D01*
X247149D01*
X247649Y261661D01*
Y254661D01*
X247149Y254161D01*
X227149D01*
X219649Y246661D01*
X216149D01*
X212649Y243161D01*
Y233161D01*
X215149Y230661D01*
Y224161D01*
X214149Y223161D01*
X201649D01*
G37*
G36*
G01X180149Y213161D02*
X176149Y217161D01*
X173649D01*
X172149Y218661D01*
Y228661D01*
X173149Y229661D01*
X186149D01*
X187149Y228661D01*
Y220720D01*
X183590Y217161D01*
X183149D01*
X182818Y216830D01*
G03X182280Y216292I831J-1369D01*
G01X182149Y216161D01*
Y216023D01*
X182138Y215991D01*
G03X182048Y215461I1511J-529D01*
G01Y213861D01*
G03X182060Y213665I1601J0D01*
G01Y213572D01*
X181649Y213161D01*
X180149D01*
G37*
G36*
G01X175900Y568900D02*
Y573896D01*
G03X177265Y576089I-1137J2229D01*
G01X177268Y576286D01*
X188157D01*
X188900Y575543D01*
Y558026D01*
X188842D01*
Y551768D01*
X188200Y551125D01*
X175666D01*
X174553Y552238D01*
Y567553D01*
X175900Y568900D01*
G37*
G36*
G01X173363Y585725D02*
X171363Y587725D01*
Y592525D01*
X171963Y593125D01*
X181263D01*
X182963Y591425D01*
Y589625D01*
X184663Y587925D01*
Y586125D01*
X184263Y585725D01*
X180592D01*
X180553Y585742D01*
G03X179900Y585882I-655J-1462D01*
G01X178500D01*
G03X177847Y585742I2J-1602D01*
G01X177808Y585725D01*
X176325D01*
X176293Y585736D01*
G03X175763Y585826I-529J-1511D01*
G01X174363D01*
G03X173833Y585736I-1J-1601D01*
G01X173801Y585725D01*
X173363D01*
G37*
G36*
G01X222583Y689200D02*
X214449D01*
X214149Y689500D01*
Y694917D01*
X214649Y695417D01*
X219649D01*
X229649Y705417D01*
X247149D01*
X247649Y704917D01*
Y701917D01*
X247149Y701417D01*
X234800D01*
X222583Y689200D01*
G37*
G36*
G01X192149Y693917D02*
X172649D01*
X171649Y694917D01*
Y701417D01*
X172649Y702417D01*
X181149D01*
X183149Y704417D01*
Y714417D01*
X213649Y744917D01*
X247149D01*
X247649Y744417D01*
Y737417D01*
X247149Y736917D01*
X223649D01*
X221149Y734417D01*
X214649D01*
X197649Y717417D01*
Y703417D01*
X193149Y698917D01*
Y694917D01*
X192149Y693917D01*
G37*
G36*
G01X201649Y675917D02*
X200649Y676917D01*
Y685917D01*
X201649Y686917D01*
Y694917D01*
X203979Y697247D01*
X203999Y697259D01*
G03X204507Y697767I-850J1358D01*
G01X204519Y697787D01*
X204649Y697917D01*
Y698055D01*
X204660Y698087D01*
G03X204750Y698617I-1511J529D01*
G01Y701018D01*
X206149Y702417D01*
X207649D01*
X220149Y714917D01*
X247149D01*
X247649Y714417D01*
Y707417D01*
X247149Y706917D01*
X227149D01*
X219649Y699417D01*
X216149D01*
X212649Y695917D01*
Y685917D01*
X215149Y683417D01*
Y676917D01*
X214149Y675917D01*
X201649D01*
G37*
G36*
G01X177798Y665768D02*
X172149Y671417D01*
Y681417D01*
X173149Y682417D01*
X187566D01*
X187698Y682285D01*
Y673966D01*
X187799D01*
Y672554D01*
G03X187798Y672489I1600J-57D01*
G01Y670889D01*
G03X187799Y670824I1601J-8D01*
G01Y668354D01*
G03X187798Y668289I1600J-57D01*
G01Y666889D01*
G03X187799Y666824I1601J-8D01*
G01Y666143D01*
X187424Y665768D01*
X177798D01*
G37*
G36*
G01X196649Y652917D02*
X195649Y653917D01*
Y662917D01*
X196649Y663917D01*
X215149D01*
X216149Y662917D01*
Y653917D01*
X215149Y652917D01*
X210708D01*
X210685Y652922D01*
G03X210000Y653002I-688J-2922D01*
G01X206250D01*
G03X205565Y652922I3J-3002D01*
G01X205542Y652917D01*
X196649D01*
G37*
G36*
G01X201649Y703917D02*
X201149Y704417D01*
Y710417D01*
X206649Y715917D01*
X212149D01*
X222398Y726166D01*
X222400D01*
Y726168D01*
X231649Y735417D01*
X247149D01*
X247649Y734917D01*
Y731917D01*
X247149Y731417D01*
X234149D01*
X206649Y703917D01*
X201649D01*
G37*
G36*
G01X235666Y934049D02*
X238418D01*
Y966532D01*
G03X240317Y969551I-12855J10193D01*
G03X250273Y974101I-1317J16049D01*
G03X254219Y974137I1827J15999D01*
G03X268879Y966216I13881J8163D01*
G03X282170Y995140I4421J15484D01*
G02X282351Y995871I220J333D01*
G03X296636Y1014825I-1551J16029D01*
G02X297029Y1015298I393J73D01*
G01X348140D01*
G03X360570Y1018498I2533J15902D01*
G01X395589D01*
G02X395906Y1017854I0J-400D01*
G03X423344Y1001401I12766J-9815D01*
G02X423925Y1001572I364J-165D01*
G03X426607Y1000179I8731J13531D01*
G03X440700Y982309I15993J-1879D01*
G02X440859Y981569I-47J-397D01*
G03X435871Y976886I8276J-13813D01*
G03X429291Y973261I4267J-15531D01*
G01X423432D01*
Y934249D01*
X424509D01*
G03X426542Y929506I15629J3892D01*
G03X424847Y927632I11058J-11706D01*
G03X419020Y914057I10235J-12432D01*
G01X419032Y913881D01*
X367223Y903511D01*
X222797Y811400D01*
X212967D01*
Y829273D01*
X217874Y834180D01*
Y904819D01*
G02X218391Y905201I400J0D01*
G03X235135Y931299I4709J15399D01*
G03X235646Y933871I-14735J4264D01*
G01X235666Y934049D01*
G37*
G36*
G01X201649Y1128673D02*
X200649Y1129673D01*
Y1138673D01*
X201649Y1139673D01*
Y1147673D01*
X203979Y1150003D01*
X203999Y1150015D01*
G03X204507Y1150523I-850J1358D01*
G01X204519Y1150543D01*
X204649Y1150673D01*
Y1150811D01*
X204660Y1150843D01*
G03X204750Y1151373I-1511J529D01*
G01Y1153774D01*
X206149Y1155173D01*
X207649D01*
X220149Y1167673D01*
X247149D01*
X247649Y1167173D01*
Y1160173D01*
X247149Y1159673D01*
X227149D01*
X219649Y1152173D01*
X216149D01*
X212649Y1148673D01*
Y1138673D01*
X215149Y1136173D01*
Y1129673D01*
X214149Y1128673D01*
X201649D01*
G37*
G36*
G01X180773Y1117100D02*
X175200Y1122673D01*
X173649D01*
X172149Y1124173D01*
Y1134173D01*
X173149Y1135173D01*
X186327D01*
X187698Y1133802D01*
Y1126722D01*
X187700D01*
Y1118940D01*
X186531D01*
X185991Y1118400D01*
X185800D01*
X184500Y1117100D01*
X180773D01*
G37*
G36*
G01X215149Y1105673D02*
X196649D01*
X195649Y1106673D01*
Y1115673D01*
X196649Y1116673D01*
X215149D01*
X216149Y1115673D01*
Y1106673D01*
X215149Y1105673D01*
G37*
G36*
G01X201649Y1156673D02*
X201149Y1157173D01*
Y1163173D01*
X206649Y1168673D01*
X212149D01*
X222398Y1178922D01*
X222400D01*
Y1178924D01*
X231649Y1188173D01*
X247149D01*
X247649Y1187673D01*
Y1184673D01*
X247149Y1184173D01*
X234149D01*
X206649Y1156673D01*
X201649D01*
G37*
G36*
G01X222327Y1141500D02*
X214849D01*
X214149Y1142200D01*
Y1147673D01*
X214649Y1148173D01*
X219649D01*
X229649Y1158173D01*
X247149D01*
X247649Y1157673D01*
Y1154673D01*
X247149Y1154173D01*
X235000D01*
X222327Y1141500D01*
G37*
G36*
G01X192149Y1146673D02*
X172649D01*
X171649Y1147673D01*
Y1154173D01*
X172649Y1155173D01*
X181149D01*
X183149Y1157173D01*
Y1167173D01*
X213649Y1197673D01*
X247149D01*
X247649Y1197173D01*
Y1190173D01*
X247149Y1189673D01*
X223649D01*
X221149Y1187173D01*
X214649D01*
X197649Y1170173D01*
Y1156173D01*
X193149Y1151673D01*
Y1147673D01*
X192149Y1146673D01*
G37*
G36*
G01X277756Y280174D02*
G03X263076Y287229I-13607J-9513D01*
G02X262650Y287628I-26J399D01*
G01Y297875D01*
X262077Y298448D01*
Y310148D01*
X258762D01*
G02X258372Y310634I0J400D01*
G03X255339Y324027I-15723J3479D01*
G01Y333461D01*
X299213Y361411D01*
G02X299828Y361074I215J-337D01*
G01Y352073D01*
X304922D01*
G03X316534Y347128I11612J11161D01*
G01X320474D01*
G03X332015Y352000I0J16105D01*
G01X338776D01*
G03X344951Y340059I40456J13354D01*
G02X344715Y339431I-322J-237D01*
G01X340047Y338409D01*
X315855Y321732D01*
X284630Y273648D01*
G02X283940Y273682I-335J218D01*
G03X277756Y280174I-14291J-7421D01*
G37*
G36*
G01X265506Y787100D02*
X247100D01*
Y789355D01*
X294525Y819600D01*
X295100D01*
X295800Y818900D01*
Y817394D01*
X265506Y787100D01*
G37*
G36*
G01X324754Y113144D02*
X325062Y112837D01*
Y109715D01*
G03X325524Y108319I2340J0D01*
G01Y106702D01*
X325213Y106391D01*
X319294D01*
G03X316330I-1482J-2610D01*
G01X311010D01*
X310678Y106723D01*
Y112984D01*
X312116Y114422D01*
X318875D01*
X320153Y113144D01*
X324754D01*
G37*
G36*
G01X316362Y241161D02*
X296862D01*
X295862Y242161D01*
Y248661D01*
X296862Y249661D01*
X305362D01*
X307362Y251661D01*
Y261661D01*
X337862Y292161D01*
X371362D01*
X371862Y291661D01*
Y284661D01*
X371362Y284161D01*
X347862D01*
X345362Y281661D01*
X338862D01*
X321862Y264661D01*
Y250661D01*
X317362Y246161D01*
Y242161D01*
X316362Y241161D01*
G37*
G36*
G01X304362Y213161D02*
X300362Y217161D01*
X297862D01*
X296362Y218661D01*
Y228661D01*
X297362Y229661D01*
X310362D01*
X311362Y228661D01*
Y220720D01*
X307803Y217161D01*
X307362D01*
X307032Y216831D01*
X307012Y216819D01*
G03X306504Y216311I850J-1358D01*
G01X306492Y216291D01*
X306362Y216161D01*
Y216023D01*
X306351Y215991D01*
G03X306260Y215461I1511J-532D01*
G01Y213861D01*
G03X306272Y213665I1602J0D01*
G01Y213572D01*
X305862Y213161D01*
X304362D01*
G37*
G36*
G01X316362Y693917D02*
X296862D01*
X295862Y694917D01*
Y701417D01*
X296862Y702417D01*
X305362D01*
X307362Y704417D01*
Y714417D01*
X337862Y744917D01*
X371362D01*
X371862Y744417D01*
Y737417D01*
X371362Y736917D01*
X347862D01*
X345362Y734417D01*
X338862D01*
X321862Y717417D01*
Y703417D01*
X317362Y698917D01*
Y694917D01*
X316362Y693917D01*
G37*
G36*
G01X304362Y665917D02*
X300362Y669917D01*
X297862D01*
X296362Y671417D01*
Y681417D01*
X297362Y682417D01*
X310362D01*
X311362Y681417D01*
Y673476D01*
X307803Y669917D01*
X307362D01*
X307031Y669586D01*
G03X306493Y669048I831J-1369D01*
G01X306362Y668917D01*
Y668779D01*
X306351Y668747D01*
G03X306260Y668217I1511J-532D01*
G01Y666617D01*
G03X306272Y666421I1602J0D01*
G01Y666328D01*
X305862Y665917D01*
X304362D01*
G37*
G36*
G01Y1118673D02*
X300362Y1122673D01*
X297862D01*
X296362Y1124173D01*
Y1134173D01*
X297362Y1135173D01*
X310362D01*
X311362Y1134173D01*
Y1126232D01*
X307803Y1122673D01*
X307362D01*
X307032Y1122343D01*
X307012Y1122331D01*
G03X306504Y1121823I850J-1358D01*
G01X306492Y1121803D01*
X306362Y1121673D01*
Y1121535D01*
X306351Y1121503D01*
G03X306260Y1120973I1511J-532D01*
G01Y1119373D01*
G03X306272Y1119177I1602J0D01*
G01Y1119084D01*
X305862Y1118673D01*
X304362D01*
G37*
G36*
G01X316362Y1146673D02*
X296862D01*
X295862Y1147673D01*
Y1154173D01*
X296862Y1155173D01*
X305362D01*
X307362Y1157173D01*
Y1167173D01*
X337862Y1197673D01*
X371362D01*
X371862Y1197173D01*
Y1190173D01*
X371362Y1189673D01*
X347862D01*
X345362Y1187173D01*
X338862D01*
X321862Y1170173D01*
Y1156173D01*
X317362Y1151673D01*
Y1147673D01*
X316362Y1146673D01*
G37*
G36*
G01X320862Y200161D02*
X319862Y201161D01*
Y209302D01*
X321721Y211161D01*
X339362D01*
X340362Y210161D01*
Y201161D01*
X339362Y200161D01*
X320862D01*
G37*
G36*
G01X325862Y251161D02*
X325362Y251661D01*
Y257661D01*
X330862Y263161D01*
X336362D01*
X346610Y273410D01*
X346614D01*
Y273412D01*
X355862Y282661D01*
X371362D01*
X371862Y282161D01*
Y279161D01*
X371362Y278661D01*
X358362D01*
X330862Y251161D01*
X325862D01*
G37*
G36*
G01X345362Y236100D02*
X338662D01*
X338362Y236400D01*
Y242161D01*
X338862Y242661D01*
X343862D01*
X353862Y252661D01*
X371362D01*
X371862Y252161D01*
Y249161D01*
X371362Y248661D01*
X357923D01*
X345362Y236100D01*
G37*
G36*
G01X325862Y223161D02*
X324862Y224161D01*
Y233161D01*
X325862Y234161D01*
Y242161D01*
X328193Y244492D01*
G03X328720Y245011I-830J1370D01*
G01X328732Y245031D01*
X328862Y245161D01*
Y245299D01*
X328873Y245331D01*
G03X328964Y245861I-1511J532D01*
G01Y248262D01*
X330362Y249661D01*
X331862D01*
X344362Y262161D01*
X371362D01*
X371862Y261661D01*
Y254661D01*
X371362Y254161D01*
X351362D01*
X343862Y246661D01*
X340362D01*
X336862Y243161D01*
Y233161D01*
X339362Y230661D01*
Y224161D01*
X338362Y223161D01*
X325862D01*
G37*
G36*
G01X345783Y688900D02*
X339062D01*
X338362Y689600D01*
Y694917D01*
X338862Y695417D01*
X343862D01*
X353862Y705417D01*
X371362D01*
X371862Y704917D01*
Y701917D01*
X371362Y701417D01*
X358300D01*
X345783Y688900D01*
G37*
G36*
G01X325862Y675917D02*
X324862Y676917D01*
Y685917D01*
X325862Y686917D01*
Y694917D01*
X328193Y697248D01*
G03X328731Y697786I-831J1369D01*
G01X328862Y697917D01*
Y698055D01*
X328873Y698087D01*
G03X328964Y698617I-1511J532D01*
G01Y701018D01*
X330362Y702417D01*
X331862D01*
X344362Y714917D01*
X371362D01*
X371862Y714417D01*
Y707417D01*
X371362Y706917D01*
X351362D01*
X343862Y699417D01*
X340362D01*
X336862Y695917D01*
Y685917D01*
X339362Y683417D01*
Y676917D01*
X338362Y675917D01*
X325862D01*
G37*
G36*
G01X339362Y652917D02*
X320862D01*
X319862Y653917D01*
Y662917D01*
X320862Y663917D01*
X339362D01*
X340362Y662917D01*
Y653917D01*
X339362Y652917D01*
G37*
G36*
G01X325862Y703917D02*
X325362Y704417D01*
Y710417D01*
X330862Y715917D01*
X336362D01*
X346610Y726166D01*
X346614D01*
Y726168D01*
X355862Y735417D01*
X371362D01*
X371862Y734917D01*
Y731917D01*
X371362Y731417D01*
X358362D01*
X330862Y703917D01*
X325862D01*
G37*
G36*
G01X348400Y786973D02*
X339346D01*
Y768374D01*
G03X333718Y765423I4517J-15457D01*
G01X327156D01*
Y755426D01*
X326703Y754973D01*
X324906D01*
Y753176D01*
X320130Y748400D01*
X318500D01*
X318000Y748900D01*
Y750122D01*
X336135Y794600D01*
X343703D01*
G03X348345Y788767I35528J23511D01*
G01X348400Y788709D01*
Y786973D01*
G37*
G36*
G01X325862Y1128673D02*
X324862Y1129673D01*
Y1138673D01*
X325862Y1139673D01*
Y1147673D01*
X328192Y1150003D01*
X328212Y1150015D01*
G03X328720Y1150523I-850J1358D01*
G01X328732Y1150543D01*
X328862Y1150673D01*
Y1150811D01*
X328873Y1150843D01*
G03X328964Y1151373I-1511J532D01*
G01Y1153774D01*
X330362Y1155173D01*
X331862D01*
X344362Y1167673D01*
X371362D01*
X371862Y1167173D01*
Y1160173D01*
X371362Y1159673D01*
X351362D01*
X343862Y1152173D01*
X340362D01*
X336862Y1148673D01*
Y1138673D01*
X339362Y1136173D01*
Y1129673D01*
X338362Y1128673D01*
X325862D01*
G37*
G36*
G01X339362Y1105673D02*
X320862D01*
X319862Y1106673D01*
Y1115673D01*
X320862Y1116673D01*
X339362D01*
X340362Y1115673D01*
Y1106673D01*
X339362Y1105673D01*
G37*
G36*
G01X325862Y1156673D02*
X325362Y1157173D01*
Y1163173D01*
X330862Y1168673D01*
X336362D01*
X346610Y1178922D01*
X346614D01*
Y1178925D01*
X355862Y1188173D01*
X371362D01*
X371862Y1187673D01*
Y1184673D01*
X371362Y1184173D01*
X358362D01*
X330862Y1156673D01*
X325862D01*
G37*
G36*
G01X346327Y1141800D02*
X338762D01*
X338362Y1142200D01*
Y1147673D01*
X338862Y1148173D01*
X343862D01*
X353862Y1158173D01*
X371362D01*
X371862Y1157673D01*
Y1154673D01*
X371362Y1154173D01*
X358700D01*
X346327Y1141800D01*
G37*
G36*
G01X386863Y297875D02*
X386290Y298448D01*
Y310148D01*
X382975D01*
G02X382585Y310634I0J400D01*
G03X382928Y315213I-15723J3480D01*
G01X382916Y315385D01*
X435752Y326948D01*
X436900Y325800D01*
Y318345D01*
X407370Y272867D01*
X404819D01*
X404794Y273038D01*
G03X387289Y287229I-16432J-2377D01*
G02X386863Y287628I-26J399D01*
G01Y297875D01*
G37*
G36*
G01X461393Y391235D02*
X455691D01*
G03X444687Y395580I-11004J-11762D01*
G01X440747D01*
G03X429743Y391235I0J-16107D01*
G01X424041D01*
Y356790D01*
X421421Y356217D01*
G02X420944Y356689I-85J391D01*
G03X421835Y365354I-41712J8667D01*
G01Y388954D01*
G03X409526Y418909I-42604J0D01*
G02X409714Y419578I285J281D01*
G01X436992Y426351D01*
G02X437469Y425841I96J-388D01*
G03X464044Y432439I15330J-4929D01*
G02X464227Y433114I279J287D01*
G01X600219Y466881D01*
X600800Y466300D01*
Y461800D01*
X598376Y459376D01*
X463955Y368212D01*
X463849Y368270D01*
G03X461393Y369344I-7657J-14166D01*
G01Y391235D01*
G37*
G36*
G01X410703Y1109803D02*
X410887Y1109742D01*
G03X425430Y1108191I10766J31990D01*
G02X425874Y1107789I44J-397D01*
G03X427843Y1099859I16102J-211D01*
G01X427867Y1099814D01*
Y1091532D01*
X426367D01*
Y1064408D01*
G02X425653Y1064160I-400J0D01*
G03X397452Y1050006I-12654J-9960D01*
G02X397066Y1049502I-386J-104D01*
G01X386300D01*
Y1061698D01*
X393040D01*
Y1067597D01*
G03X397474Y1073941I-9875J11624D01*
G01X410703Y1109803D01*
G37*
G36*
G01X463451Y204156D02*
X444951D01*
X443951Y205156D01*
Y214156D01*
X444951Y215156D01*
X463451D01*
X464451Y214156D01*
Y205156D01*
X463451Y204156D01*
G37*
G36*
G01X450074Y251161D02*
X449574Y251661D01*
Y257661D01*
X455074Y263161D01*
X460574D01*
X470822Y273410D01*
X470826D01*
Y273412D01*
X480074Y282661D01*
X495574D01*
X496074Y282161D01*
Y279161D01*
X495574Y278661D01*
X482574D01*
X455074Y251161D01*
X450074D01*
G37*
G36*
G01X440574Y241161D02*
X421074D01*
X420074Y242161D01*
Y248661D01*
X421074Y249661D01*
X429574D01*
X431574Y251661D01*
Y261661D01*
X462074Y292161D01*
X495574D01*
X496074Y291661D01*
Y284661D01*
X495574Y284161D01*
X472074D01*
X469574Y281661D01*
X463074D01*
X446074Y264661D01*
Y250661D01*
X441574Y246161D01*
Y242161D01*
X440574Y241161D01*
G37*
G36*
G01X450074Y223161D02*
X449074Y224161D01*
Y233161D01*
X450074Y234161D01*
Y242161D01*
X452405Y244492D01*
G03X452932Y245011I-830J1370D01*
G01X452944Y245031D01*
X453074Y245161D01*
Y245299D01*
X453085Y245331D01*
G03X453176Y245861I-1511J532D01*
G01Y248262D01*
X454574Y249661D01*
X456074D01*
X468574Y262161D01*
X495574D01*
X496074Y261661D01*
Y254661D01*
X495574Y254161D01*
X475574D01*
X468074Y246661D01*
X464574D01*
X461074Y243161D01*
Y233161D01*
X463574Y230661D01*
Y224161D01*
X462574Y223161D01*
X450074D01*
G37*
G36*
G01X428574Y213161D02*
X424574Y217161D01*
X422074D01*
X420574Y218661D01*
Y228661D01*
X421574Y229661D01*
X434574D01*
X435574Y228661D01*
Y220720D01*
X432015Y217161D01*
X431574D01*
X431244Y216831D01*
X431224Y216819D01*
G03X430716Y216311I850J-1358D01*
G01X430704Y216291D01*
X430574Y216161D01*
Y216023D01*
X430563Y215991D01*
G03X430472Y215461I1511J-532D01*
G01Y213861D01*
G03X430484Y213665I1602J0D01*
G01Y213572D01*
X430074Y213161D01*
X428574D01*
G37*
G36*
G01X440574Y693917D02*
X421074D01*
X420074Y694917D01*
Y701417D01*
X421074Y702417D01*
X429574D01*
X431574Y704417D01*
Y714417D01*
X462074Y744917D01*
X495574D01*
X496074Y744417D01*
Y737417D01*
X495574Y736917D01*
X472074D01*
X469574Y734417D01*
X463074D01*
X446074Y717417D01*
Y703417D01*
X441574Y698917D01*
Y694917D01*
X440574Y693917D01*
G37*
G36*
G01X450074Y675917D02*
X449074Y676917D01*
Y685917D01*
X450074Y686917D01*
Y694917D01*
X452405Y697248D01*
G03X452943Y697786I-831J1369D01*
G01X453074Y697917D01*
Y698055D01*
X453085Y698087D01*
G03X453176Y698617I-1511J532D01*
G01Y701018D01*
X454574Y702417D01*
X456074D01*
X468574Y714917D01*
X495574D01*
X496074Y714417D01*
Y707417D01*
X495574Y706917D01*
X475574D01*
X468074Y699417D01*
X464574D01*
X461074Y695917D01*
Y685917D01*
X463574Y683417D01*
Y676917D01*
X462574Y675917D01*
X450074D01*
G37*
G36*
G01X428574Y665917D02*
X424574Y669917D01*
X422074D01*
X420574Y671417D01*
Y681417D01*
X421574Y682417D01*
X434574D01*
X435574Y681417D01*
Y673476D01*
X432015Y669917D01*
X431574D01*
X431243Y669586D01*
G03X430705Y669048I831J-1369D01*
G01X430574Y668917D01*
Y668779D01*
X430563Y668747D01*
G03X430472Y668217I1511J-532D01*
G01Y666617D01*
G03X430484Y666421I1602J0D01*
G01Y666328D01*
X430074Y665917D01*
X428574D01*
G37*
G36*
G01X463574Y652917D02*
X445074D01*
X444074Y653917D01*
Y662917D01*
X445074Y663917D01*
X463574D01*
X464574Y662917D01*
Y653917D01*
X463574Y652917D01*
G37*
G36*
G01X450074Y703917D02*
X449574Y704417D01*
Y710417D01*
X455074Y715917D01*
X460574D01*
X470822Y726166D01*
X470826D01*
Y726168D01*
X480074Y735417D01*
X495574D01*
X496074Y734917D01*
Y731917D01*
X495574Y731417D01*
X482574D01*
X455074Y703917D01*
X450074D01*
G37*
G36*
G01X449118Y753176D02*
X434943Y739000D01*
X431600D01*
Y744490D01*
X440940Y786658D01*
X444041Y800659D01*
X444687D01*
G03X454208Y803775I-1J16106D01*
G02X454796Y803643I236J-323D01*
G03X463500Y791734I48452J26277D01*
G01Y768357D01*
G03X457930Y765423I4575J-15439D01*
G01X451368D01*
Y755426D01*
X450915Y754973D01*
X449118D01*
Y753176D01*
G37*
G36*
G01X523218Y1042506D02*
X520944Y1044780D01*
X521006Y1044907D01*
G03X517318Y1063829I-14506J6993D01*
G01X517252Y1063888D01*
Y1067612D01*
X534548Y1078643D01*
G02X535127Y1078472I215J-337D01*
G03X546281Y1069450I14646J6701D01*
G01Y1067667D01*
X553581D01*
Y1067367D01*
X569581D01*
Y1066067D01*
X587771D01*
Y1027279D01*
X627977D01*
Y1037469D01*
G03X631010Y1050862I-12690J9914D01*
G02X631400Y1051348I390J86D01*
G01X634715D01*
Y1054737D01*
G02X635359Y1055054I400J0D01*
G03X637669Y1053567I9839J12747D01*
G03X655254Y1032669I32410J9425D01*
G02X655289Y1031970I-176J-359D01*
G03X658272Y1003175I8511J-13670D01*
G03X658281Y999978I16028J-1553D01*
G01X658294Y999848D01*
X586652Y959642D01*
G02X586056Y959991I-196J349D01*
G01Y973261D01*
X580197D01*
G03X569350Y977461I-10847J-11907D01*
G01X564350D01*
G03X553503Y973261I0J-16107D01*
G01X547644D01*
Y939621D01*
X461976Y922475D01*
G02X461502Y922928I-79J392D01*
G03X460130Y932255I-15920J2423D01*
G03X460767Y934249I-14991J5888D01*
G01X461844D01*
Y957866D01*
G03X451036Y983748I-12707J9891D01*
G02X450878Y984488I48J397D01*
G03X457983Y1003061I-8278J13812D01*
G02X458531Y1003543I382J118D01*
G03X481302Y1018297I6669J14657D01*
G01Y1018498D01*
X502800D01*
G03X523585Y1013904I13000J9502D01*
G03X546839Y1026867I7215J14396D01*
G02X547364Y1027211I399J-36D01*
G03X555665Y1026718I5073J15283D01*
G03X552793Y1058593I357J16099D01*
G03X536397Y1043927I-357J-16099D01*
G02X535872Y1043583I-399J36D01*
G03X523348Y1042574I-5071J-15283D01*
G01X523218Y1042506D01*
G37*
G36*
G01X457400Y1120100D02*
X447400D01*
X445954Y1121546D01*
Y1133467D01*
X447544Y1135056D01*
X458144D01*
X459400Y1133800D01*
Y1122100D01*
X457400Y1120100D01*
G37*
G36*
G01X463500Y1146573D02*
X445727D01*
X445300Y1147000D01*
Y1168436D01*
X443600Y1170136D01*
Y1183300D01*
X457873Y1197573D01*
X495100D01*
X496300Y1196373D01*
Y1190373D01*
X495500Y1189573D01*
X477800D01*
X475300Y1187073D01*
X461273D01*
X459150Y1184950D01*
Y1177900D01*
X461200Y1175850D01*
Y1156400D01*
X464050Y1153550D01*
Y1147123D01*
X463500Y1146573D01*
G37*
G36*
G01X540500Y1310485D02*
Y1308248D01*
X443386Y1232697D01*
G02X442740Y1233013I-246J316D01*
G01Y1243946D01*
X454494Y1255700D01*
G03X456096Y1257584I-10847J10847D01*
G01X461393D01*
Y1296746D01*
X454335D01*
X446141Y1304940D01*
X420527D01*
G03X418453Y1311101I-41296J-10472D01*
G02X418560Y1311363I184J78D01*
G03X428386Y1326941I-6260J14837D01*
G01X428378Y1327112D01*
X442866Y1330012D01*
X505960Y1317393D01*
X506002Y1317301D01*
G03X531460Y1312210I14598J6799D01*
G01X531534Y1312278D01*
X540500Y1310485D01*
G37*
G36*
G01X469574Y236500D02*
X463274D01*
X462574Y237200D01*
Y242161D01*
X463074Y242661D01*
X468074D01*
X478074Y252661D01*
X495574D01*
X496074Y252161D01*
Y249161D01*
X495574Y248661D01*
X481735D01*
X469574Y236500D01*
G37*
G36*
G01X535810Y290410D02*
X529000Y283600D01*
X525994D01*
X525010Y284584D01*
X524996Y284611D01*
G03X511075Y293299I-14297J-7411D01*
G01Y297875D01*
X510502Y298448D01*
Y310148D01*
X507187D01*
G02X506797Y310634I0J400D01*
G03X503764Y324027I-15723J3479D01*
G01Y334217D01*
X487213D01*
G02X486987Y334947I0J400D01*
G01X518296Y356423D01*
G02X518919Y356045I226J-330D01*
G03X550856Y351900I15986J-1940D01*
G01X550880Y352073D01*
X553347D01*
X553406Y352012D01*
G03X557264Y349085I11553J11222D01*
G01X557416Y349002D01*
X535810Y290410D01*
G37*
G36*
G01X470483Y689000D02*
X462974D01*
X462574Y689400D01*
Y694917D01*
X463074Y695417D01*
X468074D01*
X478074Y705417D01*
X495574D01*
X496074Y704917D01*
Y701917D01*
X495574Y701417D01*
X482900D01*
X470483Y689000D01*
G37*
G36*
G01X470700Y1155300D02*
X464500D01*
X463850Y1155950D01*
Y1171850D01*
X480073Y1188073D01*
X495900D01*
X496700Y1187273D01*
Y1184673D01*
X496100Y1184073D01*
X483773D01*
X481681Y1181981D01*
Y1175982D01*
X472149Y1166450D01*
Y1156749D01*
X470700Y1155300D01*
G37*
G36*
G01X512226Y1143673D02*
X509693Y1146206D01*
X509686Y1146277D01*
G03X507004Y1148959I-2986J-304D01*
G01X506933Y1148966D01*
X501726Y1154173D01*
X486226D01*
X485726Y1154673D01*
Y1157673D01*
X486226Y1158173D01*
X503726D01*
X513726Y1148173D01*
X518726D01*
X519226Y1147673D01*
Y1139173D01*
X518226Y1138173D01*
X513226D01*
X512226Y1139173D01*
Y1143673D01*
G37*
G36*
G01X519226Y1128673D02*
X518226Y1129673D01*
Y1136173D01*
X520726Y1138673D01*
Y1148673D01*
X517226Y1152173D01*
X513726D01*
X506226Y1159673D01*
X486226D01*
X485726Y1160173D01*
Y1167173D01*
X486226Y1167673D01*
X513226D01*
X522856Y1158043D01*
X522869Y1158023D01*
G03X523639Y1157260I1960J1208D01*
G01X525726Y1155173D01*
X527226D01*
X528249Y1154150D01*
Y1151150D01*
X528912Y1150487D01*
X528919Y1150478D01*
G03X529179Y1150218I1255J995D01*
G01X529188Y1150211D01*
X531000Y1148399D01*
Y1140399D01*
X532726Y1138673D01*
Y1129673D01*
X531726Y1128673D01*
X519226D01*
G37*
G36*
G01X570287Y250661D02*
X569709Y250083D01*
X569598Y250112D01*
G03X566784Y247298I-589J-2225D01*
G01X566813Y247187D01*
X565787Y246161D01*
Y242161D01*
X564787Y241161D01*
X545287D01*
X544287Y242161D01*
Y248661D01*
X545287Y249661D01*
X553787D01*
X555787Y251661D01*
Y261661D01*
X586287Y292161D01*
X619787D01*
X620287Y291661D01*
Y284661D01*
X619787Y284161D01*
X596287D01*
X593787Y281661D01*
X587287D01*
X584688Y279062D01*
X583431D01*
X583404Y279071D01*
G03X580896Y275508I-646J-2210D01*
G01X580996Y275370D01*
X570287Y264661D01*
Y250661D01*
G37*
G36*
G01X552787Y213161D02*
X548787Y217161D01*
X546287D01*
X544787Y218661D01*
Y228661D01*
X545787Y229661D01*
X558787D01*
X559787Y228661D01*
Y221161D01*
X555457Y216831D01*
X555437Y216819D01*
G03X554929Y216311I850J-1358D01*
G01X554917Y216291D01*
X554787Y216161D01*
Y216023D01*
X554776Y215991D01*
G03X554686Y215461I1511J-529D01*
G01Y213861D01*
G03X554698Y213665I1601J0D01*
G01Y213572D01*
X554287Y213161D01*
X552787D01*
G37*
G36*
G01X528430Y626400D02*
X534957D01*
G03X546281Y616631I14980J5917D01*
G01Y614911D01*
X553581D01*
Y614611D01*
X569581D01*
Y613311D01*
X587771D01*
Y596997D01*
X542283D01*
X539286Y594000D01*
X510500D01*
Y598592D01*
X510502D01*
Y608942D01*
X517252D01*
Y613969D01*
X519888Y615649D01*
G03X524554Y620316I-8198J12862D01*
G01X528430Y626400D01*
G37*
G36*
G01X538951Y559409D02*
X538276Y560084D01*
Y571775D01*
X548497Y581996D01*
X594088D01*
X595277Y580807D01*
Y573450D01*
X594810Y572983D01*
X586616D01*
X586138Y572505D01*
Y571370D01*
X585712Y570944D01*
X582942D01*
X582427Y571459D01*
Y572541D01*
X581985Y572983D01*
X580641D01*
X580628Y572985D01*
G03X580418Y572998I-204J-1588D01*
G01X579018D01*
G03X578808Y572985I-6J-1601D01*
G01X578795Y572983D01*
X560093D01*
X558743Y571633D01*
Y566621D01*
X558069Y565947D01*
X556301D01*
X555787Y566461D01*
Y569867D01*
X554024Y571630D01*
X549213D01*
X546313Y568730D01*
X546275Y568714D01*
G03X545396Y567835I604J-1483D01*
G01X545380Y567797D01*
X545249Y567666D01*
Y559922D01*
X544736Y559409D01*
X538951D01*
G37*
G36*
G01X564787Y693917D02*
X545287D01*
X544287Y694917D01*
Y701417D01*
X545287Y702417D01*
X553787D01*
X555787Y704417D01*
Y714417D01*
X586287Y744917D01*
X619787D01*
X620287Y744417D01*
Y737417D01*
X619787Y736917D01*
X596287D01*
X593787Y734417D01*
X587287D01*
X570287Y717417D01*
Y703417D01*
X565787Y698917D01*
Y694917D01*
X564787Y693917D01*
G37*
G36*
G01X552787Y665917D02*
X548787Y669917D01*
X546287D01*
X544787Y671417D01*
Y681417D01*
X545787Y682417D01*
X558787D01*
X559787Y681417D01*
Y673919D01*
X555451Y669583D01*
G03X554921Y669053I836J-1366D01*
G01X554694Y668826D01*
Y668382D01*
X554693Y668372D01*
G03X554686Y668217I1594J-150D01*
G01Y666617D01*
G03X554693Y666462I1601J-5D01*
G01X554694Y666452D01*
Y666324D01*
X554287Y665917D01*
X552787D01*
G37*
G36*
G01X615900Y912326D02*
X604280Y894085D01*
G02X603668Y894009I-337J215D01*
G03X577262Y877439I-11054J-11709D01*
G03X584729Y863766I16103J-81D01*
G01X584898Y863659D01*
X574496Y847332D01*
X574346Y847386D01*
G03X568899Y848335I-5447J-15157D01*
G01X564959D01*
G03X556512Y845942I0J-16105D01*
G02X555920Y846165I-210J340D01*
G03X521200Y882035I-52671J-16244D01*
G01Y886187D01*
X545363Y891341D01*
X572327Y897099D01*
G03X576611Y898716I-3183J14917D01*
G01X578525Y899791D01*
G03X578784Y899940I-7476J13295D01*
G01X578786Y899941D01*
X611767Y918500D01*
X615900D01*
Y912326D01*
G37*
G36*
G01X552787Y1118673D02*
X548787Y1122673D01*
X546287D01*
X544787Y1124173D01*
Y1134173D01*
X545787Y1135173D01*
X558787D01*
X559787Y1134173D01*
Y1126232D01*
X556228Y1122673D01*
X555787D01*
X555456Y1122342D01*
G03X554929Y1121823I830J-1370D01*
G01X554917Y1121803D01*
X554787Y1121673D01*
Y1121535D01*
X554776Y1121503D01*
G03X554686Y1120973I1511J-529D01*
G01Y1119373D01*
G03X554698Y1119177I1601J0D01*
G01Y1119084D01*
X554287Y1118673D01*
X552787D01*
G37*
G36*
G01X531474Y1105573D02*
X512974D01*
X511974Y1106573D01*
Y1115573D01*
X512974Y1116573D01*
X531474D01*
X532474Y1115573D01*
Y1106573D01*
X531474Y1105573D01*
G37*
G36*
G01X564787Y1146673D02*
X546843D01*
X546051Y1147465D01*
Y1154592D01*
X546632Y1155173D01*
X553787D01*
X555787Y1157173D01*
Y1167173D01*
X586287Y1197673D01*
X619787D01*
X620287Y1197173D01*
Y1190173D01*
X619787Y1189673D01*
X596287D01*
X593787Y1187173D01*
X587287D01*
X570287Y1170173D01*
Y1156173D01*
X565787Y1151673D01*
Y1147673D01*
X564787Y1146673D01*
G37*
G36*
G01X593555Y55118D02*
G03X586614Y62059I-6941J0D01*
G01X585600D01*
Y85251D01*
X655555D01*
X657146Y83660D01*
X786300D01*
Y61770D01*
X783057Y58527D01*
Y49975D01*
X783056Y49966D01*
G03X782996Y48575I16046J-1389D01*
G01Y43575D01*
G03X783056Y42184I16106J-2D01*
G01X783057Y42175D01*
Y34114D01*
X784406Y32765D01*
Y30568D01*
X776535D01*
Y21765D01*
G03X773346Y8000I12510J-10150D01*
G01X783465D01*
G02X789514Y6354I0J-11937D01*
G01Y5617D01*
X790621D01*
G02X794689Y126I-7156J-9554D01*
G01X796727D01*
Y-4870D01*
X791339D01*
G02X790406Y-3937I0J933D01*
G03X783465Y3004I-6941J0D01*
G01X594488D01*
G02X593555Y3937I0J933D01*
G01Y55118D01*
G37*
G36*
G01X587787Y200161D02*
X569287D01*
X568287Y201161D01*
Y210161D01*
X569287Y211161D01*
X587787D01*
X588787Y210161D01*
Y201161D01*
X587787Y200161D01*
G37*
G36*
G01X574287Y251161D02*
X573787Y251661D01*
Y257661D01*
X579287Y263161D01*
X584787D01*
X595036Y273410D01*
X595038D01*
Y273412D01*
X604287Y282661D01*
X619787D01*
X620287Y282161D01*
Y279161D01*
X619787Y278661D01*
X606787D01*
X579287Y251161D01*
X574287D01*
G37*
G36*
G01X593500Y236500D02*
X587187D01*
X586787Y236900D01*
Y242161D01*
X587287Y242661D01*
X592287D01*
X602287Y252661D01*
X619787D01*
X620287Y252161D01*
Y249161D01*
X619787Y248661D01*
X605661D01*
X593500Y236500D01*
G37*
G36*
G01X574287Y223161D02*
X573287Y224161D01*
Y233161D01*
X574287Y234161D01*
Y242161D01*
X576617Y244491D01*
X576637Y244503D01*
G03X577145Y245011I-850J1358D01*
G01X577157Y245031D01*
X577287Y245161D01*
Y245299D01*
X577298Y245331D01*
G03X577388Y245861I-1511J529D01*
G01Y248262D01*
X578787Y249661D01*
X580287D01*
X592787Y262161D01*
X606493D01*
G03X609429I1468J1773D01*
G01X619787D01*
X620287Y261661D01*
Y254661D01*
X619787Y254161D01*
X599787D01*
X592287Y246661D01*
X588787D01*
X585287Y243161D01*
Y233161D01*
X587787Y230661D01*
Y224161D01*
X586787Y223161D01*
X574287D01*
G37*
G36*
G01X582585Y498532D02*
X574207D01*
X573303Y499436D01*
Y508657D01*
X574687Y510041D01*
X582528D01*
X583344Y509225D01*
Y499291D01*
X582585Y498532D01*
G37*
G36*
G01X585405Y518805D02*
X577309Y526901D01*
G02X577310Y527186I141J142D01*
G03X577102Y530657I-1610J1645D01*
G01Y534830D01*
X578228D01*
Y534540D01*
X579864D01*
G03X580829Y534240I965J1402D01*
G01X582439D01*
X583765Y532914D01*
X583996D01*
X586579Y530331D01*
Y530319D01*
X590964Y525934D01*
Y519331D01*
X590438Y518805D01*
X585405D01*
G37*
G36*
G01X585197Y503499D02*
X584546Y504150D01*
Y509723D01*
X584544Y509724D01*
Y516795D01*
X585280Y517531D01*
X596438D01*
X596921Y517048D01*
Y503857D01*
X596563Y503499D01*
X585197D01*
G37*
G36*
G01X593787Y688700D02*
X587687D01*
X586787Y689600D01*
Y694917D01*
X587287Y695417D01*
X592287D01*
X602287Y705417D01*
X619787D01*
X620287Y704917D01*
Y701917D01*
X619787Y701417D01*
X606504D01*
X593787Y688700D01*
G37*
G36*
G01X574287Y675917D02*
X573287Y676917D01*
Y685917D01*
X574287Y686917D01*
Y694917D01*
X576618Y697248D01*
G03X577156Y697786I-831J1369D01*
G01X577287Y697917D01*
Y698055D01*
X577298Y698087D01*
G03X577388Y698617I-1511J529D01*
G01Y701018D01*
X578787Y702417D01*
X580287D01*
X592787Y714917D01*
X619787D01*
X620287Y714417D01*
Y707417D01*
X619787Y706917D01*
X599787D01*
X592287Y699417D01*
X588787D01*
X585287Y695917D01*
Y685917D01*
X587787Y683417D01*
Y676917D01*
X586787Y675917D01*
X574287D01*
G37*
G36*
G01X587787Y652917D02*
X569287D01*
X568287Y653917D01*
Y662917D01*
X569287Y663917D01*
X587787D01*
X588787Y662917D01*
Y653917D01*
X587787Y652917D01*
G37*
G36*
G01X574287Y703917D02*
X573787Y704417D01*
Y710417D01*
X579287Y715917D01*
X584787D01*
X595036Y726166D01*
X595038D01*
Y726168D01*
X604287Y735417D01*
X619787D01*
X620287Y734917D01*
Y731917D01*
X619787Y731417D01*
X606787D01*
X579287Y703917D01*
X574287D01*
G37*
G36*
G01X575581Y765423D02*
Y755426D01*
X575128Y754973D01*
X573331D01*
Y753176D01*
X559855Y739700D01*
X557700D01*
Y741004D01*
X564856Y773280D01*
X577482Y793100D01*
X587700D01*
Y768353D01*
G03X582143Y765423I4588J-15436D01*
G01X575581D01*
G37*
G36*
G01X574287Y1128673D02*
X573287Y1129673D01*
Y1138673D01*
X574287Y1139673D01*
Y1147673D01*
X576617Y1150003D01*
X576637Y1150015D01*
G03X577145Y1150523I-850J1358D01*
G01X577157Y1150543D01*
X577287Y1150673D01*
Y1150811D01*
X577298Y1150843D01*
G03X577388Y1151373I-1511J529D01*
G01Y1153775D01*
X578787Y1155173D01*
X580287D01*
X592787Y1167673D01*
X619787D01*
X620287Y1167173D01*
Y1160173D01*
X619787Y1159673D01*
X599787D01*
X592287Y1152173D01*
X588787D01*
X585287Y1148673D01*
Y1138673D01*
X587787Y1136173D01*
Y1129673D01*
X586787Y1128673D01*
X574287D01*
G37*
G36*
G01X587787Y1105673D02*
X569287D01*
X568287Y1106673D01*
Y1115673D01*
X569287Y1116673D01*
X587787D01*
X588787Y1115673D01*
Y1106673D01*
X587787Y1105673D01*
G37*
G36*
G01X574287Y1156673D02*
X573787Y1157173D01*
Y1163173D01*
X579287Y1168673D01*
X584787D01*
X595036Y1178922D01*
X595038D01*
Y1178925D01*
X604287Y1188173D01*
X619787D01*
X620287Y1187673D01*
Y1184673D01*
X619787Y1184173D01*
X606787D01*
X579287Y1156673D01*
X574287D01*
G37*
G36*
G01X594927Y1140900D02*
X587587D01*
X586787Y1141700D01*
Y1147673D01*
X587287Y1148173D01*
X592287D01*
X602287Y1158173D01*
X619787D01*
X620287Y1157673D01*
Y1154673D01*
X619787Y1154173D01*
X608200D01*
X594927Y1140900D01*
G37*
G36*
G01X661494Y163455D02*
X670494D01*
Y162155D01*
X677794D01*
Y161855D01*
X693794D01*
Y160355D01*
X711984D01*
Y148891D01*
G03X708909Y142359I12661J-9950D01*
G01X708867Y142166D01*
X666279Y150852D01*
X635277Y144752D01*
G02X634800Y145144I-77J392D01*
G01Y156186D01*
X641465D01*
Y161674D01*
X649356Y166670D01*
X657642Y189142D01*
X658800Y190300D01*
X660000D01*
X661494Y188806D01*
Y187840D01*
X661492Y187827D01*
G03Y183511I15958J-2158D01*
G01X661494Y183498D01*
Y163455D01*
G37*
G36*
G01X655266Y275992D02*
G03X649892Y280655I-12980J-9531D01*
G03X635714Y287029I-13105J-10194D01*
G02X635288Y287428I-26J399D01*
G01Y297875D01*
X634715Y298448D01*
Y310148D01*
X631400D01*
G02X631010Y310634I0J400D01*
G03X629207Y322211I-15723J3480D01*
G02X629531Y322812I346J202D01*
G03X669866Y365354I-2267J42542D01*
G01Y388954D01*
G03X642740Y428646I-42603J0D01*
G02X642659Y429348I146J372D01*
G01X695560Y465637D01*
X695675Y465550D01*
G03X720842Y482814I9673J12874D01*
G01X720803Y482952D01*
X731077Y490000D01*
X732900D01*
X734319Y488581D01*
X701710Y400149D01*
G02X701136Y399941I-375J139D01*
G03X693112Y402082I-8024J-13965D01*
G01X689172D01*
G03X673949Y391235I0J-16106D01*
G01X672466D01*
Y352073D01*
X673446D01*
G03X680103Y341986I15786J3178D01*
G01X680231Y341898D01*
X655964Y276090D01*
G02X655266Y275992I-375J138D01*
G37*
G36*
G01X653214Y532697D02*
G03X643421Y536744I-10704J-12030D01*
G02X643045Y537178I22J399D01*
G03X643106Y538580I-16045J1400D01*
G01Y542909D01*
G03X637510Y555113I-16106J0D01*
G03X638907Y558854I-14274J7462D01*
G01X643915D01*
X647115Y555659D01*
X665759D01*
X669811Y559711D01*
X673821D01*
Y563721D01*
X675042Y564942D01*
Y566354D01*
X675602D01*
X675647Y566330D01*
G03X683341Y564373I7695J14150D01*
G01X689748D01*
G03X693618Y564845I-1J16106D01*
G03X707141Y568300I3169J15788D01*
G01X713425D01*
G02X713749Y567666I0J-400D01*
G01X708321Y560162D01*
X670026Y528048D01*
G02X669369Y528354I-257J306D01*
G01Y528506D01*
X667686D01*
X667636Y528540D01*
G03X659313Y531269I-8990J-13360D01*
G03X653214Y532697I-6651J-14669D01*
G37*
G36*
G01X641713Y573855D02*
X640713Y574855D01*
Y587355D01*
X643213Y589855D01*
X651213D01*
X651513Y589555D01*
Y579730D01*
X651454Y579672D01*
Y574596D01*
X650713Y573855D01*
X641713D01*
G37*
G36*
G01X628482Y588255D02*
X626672Y590065D01*
Y607019D01*
X627608Y607955D01*
X650113D01*
X651213Y606855D01*
Y592186D01*
X650613Y591586D01*
X643844D01*
X643314Y591056D01*
X642715D01*
X639914Y588255D01*
X637978D01*
G03X637913Y588256I-57J-1600D01*
G01X636513D01*
G03X636448Y588255I-8J-1601D01*
G01X628482D01*
G37*
G36*
G01X639400Y890297D02*
X654786Y914448D01*
X654924Y914416D01*
G03X663252Y914691I3651J15684D01*
G01X663280Y914700D01*
X673832D01*
Y858900D01*
X666244D01*
G03X639400Y882548I-38981J-17190D01*
G01Y890297D01*
G37*
G36*
G01X712000Y200161D02*
X693500D01*
X692500Y201161D01*
Y210161D01*
X693500Y211161D01*
X712000D01*
X713000Y210161D01*
Y201161D01*
X712000Y200161D01*
G37*
G36*
G01X698500Y251161D02*
X698000Y251661D01*
Y257661D01*
X703500Y263161D01*
X709000D01*
X719248Y273410D01*
X719252D01*
Y273412D01*
X728500Y282661D01*
X744000D01*
X744500Y282161D01*
Y279161D01*
X744000Y278661D01*
X731000D01*
X703500Y251161D01*
X698500D01*
G37*
G36*
G01X689000Y241161D02*
X669500D01*
X668500Y242161D01*
Y248661D01*
X669500Y249661D01*
X678000D01*
X680000Y251661D01*
Y261661D01*
X710500Y292161D01*
X744000D01*
X744500Y291661D01*
Y284661D01*
X744000Y284161D01*
X720500D01*
X718000Y281661D01*
X711500D01*
X694500Y264661D01*
Y250661D01*
X690000Y246161D01*
Y242161D01*
X689000Y241161D01*
G37*
G36*
G01X698500Y223161D02*
X697500Y224161D01*
Y233161D01*
X698500Y234161D01*
Y242161D01*
X700830Y244491D01*
X700850Y244503D01*
G03X701358Y245011I-850J1358D01*
G01X701370Y245031D01*
X701500Y245161D01*
Y245299D01*
X701511Y245331D01*
G03X701602Y245861I-1511J532D01*
G01Y248262D01*
X703000Y249661D01*
X704500D01*
X717000Y262161D01*
X744000D01*
X744500Y261661D01*
Y254661D01*
X744000Y254161D01*
X724000D01*
X716500Y246661D01*
X713270D01*
X709500Y242891D01*
Y233161D01*
X712000Y230661D01*
Y224161D01*
X711000Y223161D01*
X698500D01*
G37*
G36*
G01X677000Y213161D02*
X673000Y217161D01*
X670500D01*
X669000Y218661D01*
Y228661D01*
X670000Y229661D01*
X683000D01*
X684000Y228661D01*
Y220720D01*
X680441Y217161D01*
X680000D01*
X679670Y216831D01*
X679650Y216819D01*
G03X679142Y216311I850J-1358D01*
G01X679130Y216291D01*
X679000Y216161D01*
Y216023D01*
X678989Y215991D01*
G03X678898Y215461I1511J-532D01*
G01Y213861D01*
G03X678910Y213665I1602J0D01*
G01Y213572D01*
X678500Y213161D01*
X677000D01*
G37*
G36*
G01X653322Y570660D02*
X652656Y571325D01*
Y579174D01*
X653728Y580246D01*
X656212D01*
X656222Y580245D01*
G03X656742I260J2589D01*
G01X656752Y580246D01*
X658825D01*
X660041Y579030D01*
Y571156D01*
X659545Y570660D01*
X653322D01*
G37*
G36*
G01X659516Y581355D02*
Y581418D01*
X659352D01*
X659323Y581448D01*
X655120D01*
X653213Y583355D01*
Y613355D01*
X655213Y615355D01*
X684713D01*
X685713Y614355D01*
Y589328D01*
X683592D01*
Y589221D01*
X679866D01*
X679378Y588733D01*
Y582589D01*
X678144Y581355D01*
X659516D01*
G37*
G36*
G01X694713Y586855D02*
X694213Y587355D01*
Y588855D01*
X693906Y589162D01*
X689496D01*
Y589328D01*
X687496D01*
X687418Y589296D01*
X687237Y589477D01*
Y613747D01*
X688845Y615355D01*
X705213D01*
X706713Y613855D01*
Y587855D01*
X705713Y586855D01*
X698246D01*
X698209Y586871D01*
G03X697587Y586996I-620J-1476D01*
G01X695987D01*
G03X695365Y586871I-2J-1601D01*
G01X695328Y586855D01*
X694713D01*
G37*
G36*
G01X688381Y616956D02*
X688150Y617187D01*
Y625967D01*
X690501Y628318D01*
X694353D01*
X695492Y627178D01*
X699763D01*
X700902Y628318D01*
X705538D01*
X706699Y627157D01*
Y618199D01*
X705456Y616956D01*
X688381D01*
G37*
G36*
G01X689000Y693917D02*
X669500D01*
X668500Y694917D01*
Y701417D01*
X669500Y702417D01*
X678000D01*
X680000Y704417D01*
Y714417D01*
X710500Y744917D01*
X744000D01*
X744500Y744417D01*
Y737417D01*
X744000Y736917D01*
X720500D01*
X718000Y734417D01*
X711500D01*
X694500Y717417D01*
Y703417D01*
X690000Y698917D01*
Y694917D01*
X689000Y693917D01*
G37*
G36*
G01X698500Y675917D02*
X697500Y676917D01*
Y685917D01*
X698500Y686917D01*
Y694917D01*
X700831Y697248D01*
G03X701369Y697786I-831J1369D01*
G01X701500Y697917D01*
Y698055D01*
X701511Y698087D01*
G03X701602Y698617I-1511J532D01*
G01Y701018D01*
X703000Y702417D01*
X704500D01*
X717000Y714917D01*
X744000D01*
X744500Y714417D01*
Y707417D01*
X744000Y706917D01*
X724000D01*
X716500Y699417D01*
X713000D01*
X709500Y695917D01*
Y685917D01*
X712000Y683417D01*
Y676917D01*
X711000Y675917D01*
X698500D01*
G37*
G36*
G01X675681Y664737D02*
X674505Y665912D01*
X669000Y671417D01*
Y681417D01*
X670000Y682417D01*
X683000D01*
X684000Y681417D01*
Y673418D01*
X682974Y672392D01*
X680241D01*
X679399Y671550D01*
Y670755D01*
G03X679398Y670717I1600J-61D01*
G01Y669117D01*
G03X679399Y669079I1601J23D01*
G01Y666555D01*
G03X679398Y666517I1600J-61D01*
G01Y665117D01*
G03X679399Y665079I1601J23D01*
G01Y664902D01*
X679234Y664737D01*
X675681D01*
G37*
G36*
G01X694422Y652917D02*
X692500Y654839D01*
Y662917D01*
X693500Y663917D01*
X712000D01*
X713000Y662917D01*
Y653917D01*
X712000Y652917D01*
X694422D01*
G37*
G36*
G01X698500Y703917D02*
X698000Y704417D01*
Y710417D01*
X703500Y715917D01*
X709000D01*
X719248Y726166D01*
X719252D01*
Y726168D01*
X728500Y735417D01*
X744000D01*
X744500Y734917D01*
Y731917D01*
X744000Y731417D01*
X731000D01*
X703500Y703917D01*
X698500D01*
G37*
G36*
G01X674032Y750800D02*
X672400D01*
Y753114D01*
X672402Y753127D01*
G03X671584Y760820I-16158J2172D01*
G01Y771770D01*
X699777Y799963D01*
G03X706132Y795776I18330J20905D01*
G02X706283Y795180I-173J-361D01*
G01X674032Y750800D01*
G37*
G36*
G01X698500Y1128673D02*
X697500Y1129673D01*
Y1138673D01*
X698500Y1139673D01*
Y1147673D01*
X700830Y1150003D01*
X700850Y1150015D01*
G03X701358Y1150523I-850J1358D01*
G01X701370Y1150543D01*
X701500Y1150673D01*
Y1150811D01*
X701511Y1150843D01*
G03X701602Y1151373I-1511J532D01*
G01Y1153775D01*
X703000Y1155173D01*
X704500D01*
X717000Y1167673D01*
X744000D01*
X744500Y1167173D01*
Y1160173D01*
X744000Y1159673D01*
X724000D01*
X716500Y1152173D01*
X713000D01*
X709500Y1148673D01*
Y1138673D01*
X712000Y1136173D01*
Y1129673D01*
X711000Y1128673D01*
X698500D01*
G37*
G36*
G01X677100Y1117800D02*
X672227Y1122673D01*
X670500D01*
X669000Y1124173D01*
Y1134173D01*
X670000Y1135173D01*
X683000D01*
X684548Y1133625D01*
Y1126722D01*
X684600D01*
Y1118703D01*
X683948Y1118050D01*
X683242D01*
X682991Y1117800D01*
X677100D01*
G37*
G36*
G01X693500Y1105673D02*
X692500Y1106673D01*
Y1114791D01*
X694382Y1116673D01*
X712000D01*
X713000Y1115673D01*
Y1106673D01*
X712000Y1105673D01*
X693500D01*
G37*
G36*
G01X698500Y1156673D02*
X698000Y1157173D01*
Y1163173D01*
X703500Y1168673D01*
X709000D01*
X719248Y1178922D01*
X719252D01*
Y1178925D01*
X728500Y1188173D01*
X744000D01*
X744500Y1187673D01*
Y1184673D01*
X744000Y1184173D01*
X731000D01*
X703500Y1156673D01*
X698500D01*
G37*
G36*
G01X669500Y1146673D02*
X668500Y1147673D01*
Y1154173D01*
X669500Y1155173D01*
X678000D01*
X680000Y1157173D01*
Y1167173D01*
X710500Y1197673D01*
X744000D01*
X744500Y1197173D01*
Y1190173D01*
X744000Y1189673D01*
X720500D01*
X718000Y1187173D01*
X711500D01*
X694500Y1170173D01*
Y1156173D01*
X693293Y1154966D01*
X693185Y1154991D01*
G03X690427Y1152233I-514J-2244D01*
G01X690452Y1152125D01*
X690000Y1151673D01*
Y1147673D01*
X689000Y1146673D01*
X669500D01*
G37*
G36*
G01X717600Y236600D02*
X711400D01*
X711000Y237000D01*
Y242161D01*
X711500Y242661D01*
X716500D01*
X726500Y252661D01*
X744000D01*
X744500Y252161D01*
Y249161D01*
X744000Y248661D01*
X729661D01*
X717600Y236600D01*
G37*
G36*
G01X788700Y522300D02*
X790075Y520925D01*
X743126Y334217D01*
X711711D01*
G02X711336Y334755I0J400D01*
G01X770833Y496104D01*
X786104Y522300D01*
X788700D01*
G37*
G36*
G01X719783Y688800D02*
X711500D01*
X711000Y689300D01*
Y694917D01*
X711500Y695417D01*
X716500D01*
X726500Y705417D01*
X744000D01*
X744500Y704917D01*
Y701917D01*
X744000Y701417D01*
X732400D01*
X719783Y688800D01*
G37*
G36*
G01X734321Y904234D02*
G03X715206Y892187I-3439J-15732D01*
G02X714668Y891907I-389J91D01*
G03X708452Y893059I-5985J-14949D01*
G01Y930711D01*
G03X715537Y936057I-5969J15278D01*
G03X716999Y935559I6014J15260D01*
G01Y922686D01*
X727886Y911799D01*
X736292D01*
G02X736645Y911212I-1J-400D01*
G03X734806Y904602I14238J-7522D01*
G02X734321Y904234I-399J23D01*
G37*
G36*
G01X742900Y926800D02*
X734100D01*
X732000Y928900D01*
Y949600D01*
X732600Y950200D01*
X743000D01*
X743900Y949300D01*
Y927800D01*
X742900Y926800D01*
G37*
G36*
G01X778917Y975294D02*
X778777Y975276D01*
G03X770069Y971306I2024J-15975D01*
G03X760859Y960717I6331J-14806D01*
G02X760313Y960455I-386J105D01*
G03X752757Y961756I-6432J-14766D01*
G01X752666Y961749D01*
X749214Y965201D01*
X734176D01*
G03X730600Y966768I-8325J-14134D01*
G01Y977649D01*
X776591Y1003546D01*
X776697Y1003461D01*
G03X783953Y1000150I10105J12538D01*
G02X784273Y999671I-71J-394D01*
G01X778917Y975294D01*
G37*
G36*
G01X718300Y1141400D02*
X711800D01*
X711000Y1142200D01*
Y1147673D01*
X711500Y1148173D01*
X716500D01*
X726500Y1158173D01*
X744000D01*
X744500Y1157673D01*
Y1154673D01*
X744000Y1154173D01*
X731073D01*
X718300Y1141400D01*
G37*
G36*
G01X738792Y1263453D02*
G03X744538Y1287262I-7292J14358D01*
G01X744500Y1287314D01*
Y1290101D01*
G02X744979Y1290493I400J0D01*
G01X782500Y1282897D01*
Y1271676D01*
X737544Y1254275D01*
G02X737000Y1254648I-144J373D01*
G01Y1261348D01*
G03X738792Y1263453I-11320J11452D01*
G37*
G36*
G01X910069Y306700D02*
X911700D01*
X912225Y306175D01*
Y63780D01*
G03X913440Y57448I17106J0D01*
G02X913069Y56900I-371J-148D01*
G01X905282D01*
Y94285D01*
X893166Y106401D01*
X833625D01*
X825686Y114340D01*
X777860D01*
X775100Y117100D01*
Y125584D01*
X805677Y145443D01*
X865260Y237482D01*
X865421Y237399D01*
G03X882837Y264303I7375J14315D01*
G01X882696Y264416D01*
X910069Y306700D01*
G37*
G36*
G01X864710Y491887D02*
G03X861409Y490122I5891J-14987D01*
G03X840873Y489028I-9609J-12922D01*
G03X830294Y473900I5527J-15128D01*
G01Y469300D01*
G03X836125Y456898I16106J1D01*
G03X840503Y442925I15875J-2698D01*
G01X840560Y442867D01*
Y441268D01*
X832051Y432759D01*
Y385473D01*
X842725Y374799D01*
X858708D01*
X858715Y374606D01*
G03X858744Y374066I16092J593D01*
G01Y357027D01*
X858743Y357019D01*
G03Y354577I16057J-1221D01*
G01X858744Y354569D01*
Y342994D01*
X865035D01*
G03X871820Y339973I9766J12804D01*
G02X871984Y339258I-74J-393D01*
G03X869181Y315992I9565J-12954D01*
G01X869275Y315879D01*
X845323Y278300D01*
X840600D01*
X838719Y280181D01*
G03X772069Y309736I-42263J-5378D01*
G01X772018Y309700D01*
X770600D01*
X769802Y310498D01*
X780202Y351855D01*
G02X780812Y352091I388J-97D01*
G03X788214Y381523I8927J13402D01*
G02X787788Y382019I-38J398D01*
G01X830228Y550800D01*
X835700D01*
X839102Y547398D01*
X841506Y535587D01*
X848464Y522767D01*
G02X847904Y522235I-351J-191D01*
G03X855595Y508060I-8404J-13734D01*
G02X856347Y508240I400J-11D01*
G01X864915Y492450D01*
G02X864710Y491887I-351J-191D01*
G37*
G36*
G01X802357Y618000D02*
X796291D01*
X794625Y619666D01*
Y636875D01*
X796250Y638500D01*
X806924D01*
X808113Y637311D01*
Y623756D01*
X802357Y618000D01*
G37*
G36*
G01X758928Y1215660D02*
X755613D01*
G02X755223Y1216146I0J400D01*
G03X754154Y1226302I-15723J3479D01*
G02X754374Y1226841I364J166D01*
G01X785055Y1238718D01*
G02X785599Y1238345I144J-373D01*
G01Y1226871D01*
G02X785183Y1226472I-400J1D01*
G03X768238Y1210178I-638J-16294D01*
G01Y1205978D01*
G03X768255Y1205243I16306J9D01*
G03X763229Y1193469I11280J-11775D01*
G01Y1192893D01*
G02X762784Y1192496I-400J0D01*
G03X759924Y1192574I-1881J-16496D01*
G02X759501Y1192974I-23J399D01*
G01Y1203387D01*
X758928Y1203960D01*
Y1215660D01*
G37*
G36*
G01X862443Y51109D02*
X845765D01*
X841277Y55597D01*
Y88071D01*
X844606Y91400D01*
X862968D01*
X863267Y91101D01*
Y51933D01*
X862443Y51109D01*
G37*
G36*
G01X829247Y26898D02*
X828822Y27323D01*
Y32930D01*
X830677Y34785D01*
Y45975D01*
X831706Y47004D01*
X838404D01*
X839436Y45972D01*
Y36799D01*
G03Y36509I2297J-145D01*
G01Y33876D01*
X839332D01*
Y27781D01*
X838448Y26898D01*
X829247D01*
G37*
G36*
G01X811019Y39132D02*
X799254D01*
X798058Y40328D01*
Y52313D01*
X798899Y53154D01*
X811095D01*
X811797Y52452D01*
Y39910D01*
X811019Y39132D01*
G37*
G36*
G01X813501Y59554D02*
X802501D01*
X801301Y60754D01*
Y78854D01*
X802501Y80054D01*
X813901D01*
X814901Y79054D01*
Y60954D01*
X813501Y59554D01*
G37*
G36*
G01X814283Y26860D02*
X813201Y27942D01*
Y32573D01*
X813234Y32606D01*
Y44880D01*
X815104Y46750D01*
X827966D01*
X829150Y45566D01*
Y36059D01*
X828615Y35524D01*
X824983D01*
X823484Y34025D01*
Y27710D01*
X822634Y26860D01*
X814283D01*
G37*
G36*
G01X810327Y644900D02*
X799933D01*
X797771Y647062D01*
Y658156D01*
X805015Y665400D01*
X810522D01*
X812203Y663719D01*
Y646776D01*
X810327Y644900D01*
G37*
G36*
G01X812800Y1190300D02*
X801400D01*
X800400Y1191300D01*
Y1209400D01*
X801800Y1210800D01*
X812800D01*
X814000Y1209600D01*
Y1191500D01*
X812800Y1190300D01*
G37*
G36*
G01Y1217200D02*
X801800D01*
X800600Y1218400D01*
Y1236700D01*
X801900Y1238000D01*
X813300D01*
X814200Y1237100D01*
Y1218600D01*
X812800Y1217200D01*
G37*
G36*
G01X1367075Y3937D02*
G02X1366142Y3004I-933J0D01*
G01X1185039D01*
G03X1178098Y-3937I0J-6941D01*
G01Y-148819D01*
G02X1177165Y-149752I-933J0D01*
G01X870079D01*
G02X869146Y-148819I0J933D01*
G01Y-16366D01*
X874142D01*
Y-50875D01*
X889143D01*
G03X904288Y-55387I15777J25284D01*
G01Y-70078D01*
G03X917921Y-100425I40593J0D01*
G01X917988Y-100485D01*
Y-103088D01*
X917921Y-103147D01*
G03X917988Y-127312I10679J-12053D01*
G01Y-144756D01*
X1130438D01*
Y-124791D01*
G03X1130477Y-105576I-12903J9634D01*
G01X1130438Y-105523D01*
Y-100186D01*
X1135502Y-95121D01*
Y-61699D01*
G03X1130962Y-50738I-15502J0D01*
G01X1130676Y-50452D01*
X1130865Y-50262D01*
X1130932Y-50253D01*
G03X1132161Y-50038I-2158J15957D01*
G03X1150757Y-51221I10132J12516D01*
G03X1158101Y-48890I-1058J16068D01*
G01X1173102D01*
Y-3937D01*
G02X1185039Y8000I11937J0D01*
G01X1194954D01*
Y23001D01*
X1196270Y24317D01*
X1212082D01*
X1216580Y28815D01*
X1216605D01*
Y28840D01*
X1229269Y41504D01*
Y94382D01*
X1219282Y104369D01*
X1215631D01*
X1215596Y104383D01*
G03X1209768Y105474I-5827J-15016D01*
G01X1199660D01*
G03X1189521Y116522I-15572J-4114D01*
G03X1168923Y117466I-10865J-11885D01*
G01X1160743D01*
Y116700D01*
X1140137D01*
Y151985D01*
G03X1148848Y157630I-3934J15615D01*
G03X1154677Y163763I-8348J13770D01*
G03X1155936Y183951I-11877J10874D01*
G03X1140340Y195302I-15386J-4751D01*
G02X1140137Y195502I-3J200D01*
G01Y309437D01*
X1142000Y311300D01*
X1144946D01*
X1157942Y298304D01*
X1157918Y298197D01*
G03X1157560Y294904I14982J-3295D01*
G01Y287900D01*
G03X1157952Y284456I15340J2D01*
G01X1157977Y284348D01*
X1156409Y282780D01*
Y264061D01*
G03X1159941Y248214I15340J-4898D01*
G01X1159994Y248157D01*
Y246694D01*
X1161559D01*
X1161614Y246649D01*
G03X1163494Y245337I10132J12516D01*
G01Y233694D01*
X1173451D01*
G03X1186916Y228898I11649J11406D01*
G01X1187094Y228918D01*
X1193736Y199608D01*
X1201157Y187953D01*
X1201112Y187855D01*
G03X1215574Y165140I14683J-6613D01*
G01X1215682Y165139D01*
X1243123Y122039D01*
X1262196Y110872D01*
X1278528D01*
X1283500Y105900D01*
Y101724D01*
G03X1283463Y100640I16069J-1091D01*
G01Y98804D01*
X1283461Y98789D01*
G03Y93727I16108J-2531D01*
G01X1283463Y93712D01*
Y84272D01*
G03X1302184Y68380I16106J0D01*
G03X1302540Y68330I2418J15924D01*
G01X1302715Y68308D01*
Y66649D01*
X1303849D01*
Y55423D01*
X1307733D01*
X1307741Y55232D01*
G03X1308322Y51590I16088J699D01*
G01X1308329Y51564D01*
Y47723D01*
X1309974D01*
X1310032Y47626D01*
G03X1325602Y39924I13797J8303D01*
G03X1333018Y40405I2694J15876D01*
G03X1346001Y47723I-518J16095D01*
G01X1362079D01*
Y55118D01*
G02X1374016Y67055I11937J0D01*
G01X1376944D01*
Y62059D01*
X1374016D01*
G03X1367075Y55118I0J-6941D01*
G01Y3937D01*
G37*
G36*
G01X876072Y35239D02*
X878688Y32623D01*
Y27404D01*
X878060Y26776D01*
X868800D01*
X868405Y27172D01*
Y33668D01*
X866587Y35486D01*
Y45612D01*
X867223Y46248D01*
X875368D01*
X876072Y45544D01*
Y35239D01*
G37*
G36*
G01X877277Y50957D02*
X877259Y50974D01*
X867822D01*
X867268Y51528D01*
Y90078D01*
X868590Y91400D01*
X886952D01*
X890281Y88071D01*
Y52477D01*
X888761Y50957D01*
X877277D01*
G37*
G36*
G01X852950Y26776D02*
X852401Y27325D01*
Y46073D01*
X852622Y46294D01*
X864294D01*
X864502Y46086D01*
Y35649D01*
X862684Y33831D01*
Y27093D01*
X862368Y26776D01*
X852950D01*
G37*
G36*
G01X864432Y389800D02*
X848939D01*
X847052Y391687D01*
Y426545D01*
X848637Y428130D01*
X864466D01*
X865432Y427164D01*
Y390800D01*
X864432Y389800D01*
G37*
G36*
G01X876094Y572525D02*
G03X875236Y562308I28827J-7565D01*
G03X871026Y558586I8733J-14121D01*
G01X870966Y558511D01*
X869298D01*
X855666Y625490D01*
X866005Y666849D01*
X891314D01*
X901801Y677336D01*
Y683510D01*
X912225D01*
Y627245D01*
X890403D01*
G03X867437Y611905I-6360J-15340D01*
G01Y605505D01*
G03X867791Y602096I16606J2D01*
G03X867537Y599205I16352J-2893D01*
G01Y593105D01*
G03X867778Y590289I16606J3D01*
G03X876094Y572525I16291J-3202D01*
G37*
G36*
G01X885100Y681850D02*
X864950D01*
X863200Y683600D01*
Y692655D01*
X865048Y694504D01*
X876148D01*
X877244Y695600D01*
X885352D01*
X886800Y694152D01*
Y683550D01*
X885100Y681850D01*
G37*
G36*
G01X867051Y698511D02*
X865666Y699896D01*
Y706971D01*
X877479Y725797D01*
X933553D01*
X935499Y723851D01*
G03X940336Y718976I6627J1739D01*
G01X940387Y718963D01*
X943651Y715699D01*
Y708335D01*
X941716Y706400D01*
X940905D01*
G02X940506Y706788I1J400D01*
G03X933904I-3301J-96D01*
G02X933505Y706400I-400J12D01*
G01X925800D01*
X917911Y698511D01*
X867051D01*
G37*
G36*
G01X1070424Y1071566D02*
X1070687Y1071303D01*
X1070648Y1071186D01*
G03X1070498Y1070250I2852J-937D01*
G01Y1067100D01*
G03X1070861Y1065670I3002J1D01*
G01X1070885Y1065626D01*
Y1065100D01*
X1072733Y1063252D01*
X1075059D01*
X1076238Y1064431D01*
Y1065870D01*
X1076254Y1065908D01*
G03X1076502Y1067100I-2753J1195D01*
G01Y1070250D01*
G03X1076375Y1071111I-3002J-3D01*
G01X1076341Y1071225D01*
X1076526Y1071410D01*
X1077104D01*
X1077115Y1071409D01*
G03X1077300Y1071398I187J1591D01*
G01X1078700D01*
G03X1079097Y1071449I-4J1601D01*
G02X1079585Y1070966I99J-388D01*
G03X1079498Y1070250I2915J-717D01*
G01Y1067100D01*
G03X1079909Y1065585I3002J1D01*
G01Y1064052D01*
X1080709Y1063252D01*
X1084214D01*
X1085344Y1064382D01*
Y1066140D01*
X1085354Y1066170D01*
G03X1085502Y1067100I-2854J931D01*
G01Y1070250D01*
G03X1085426Y1070921I-3002J0D01*
G02X1085815Y1071410I390J89D01*
G01X1086104D01*
X1086115Y1071409D01*
G03X1086300Y1071398I187J1591D01*
G01X1087700D01*
G03X1088333Y1071529I-1J1602D01*
G01X1088458Y1071582D01*
X1089060Y1070980D01*
X1089061Y1070897D01*
G03X1089125Y1070356I2339J2D01*
G01X1089130Y1070334D01*
Y1065014D01*
X1090892Y1063252D01*
X1107206D01*
X1108835Y1064881D01*
Y1071261D01*
X1109186Y1071612D01*
X1109208D01*
G03X1109800Y1071498I593J1488D01*
G01X1111200D01*
G03X1111385Y1071509I-2J1602D01*
G01X1111396Y1071510D01*
X1111864D01*
X1111966Y1071612D01*
X1113907D01*
X1113941Y1071599D01*
G03X1114500Y1071498I560J1501D01*
G01X1115900D01*
G03X1116085Y1071509I-2J1602D01*
G01X1116096Y1071510D01*
X1116256D01*
X1116447Y1071319D01*
Y1063905D01*
X1117100Y1063252D01*
X1126022D01*
X1127284Y1064514D01*
Y1066078D01*
X1127298Y1066113D01*
G03X1127502Y1067200I-2798J1088D01*
G01Y1070350D01*
G03X1127426Y1071021I-3002J0D01*
G02X1127815Y1071510I390J89D01*
G01X1128004D01*
X1128015Y1071509D01*
G03X1128200Y1071498I187J1591D01*
G01X1129600D01*
G03X1130423Y1071726I-1J1602D01*
G01X1132245D01*
X1134054Y1069917D01*
Y1060269D01*
X1132785Y1059000D01*
X1034000D01*
X1018800Y1043800D01*
Y1030400D01*
X1018100Y1029700D01*
X1016100D01*
X1015500Y1030300D01*
Y1035700D01*
X1014200Y1037000D01*
X993300D01*
X991200Y1034900D01*
Y1029300D01*
X992300Y1028200D01*
X995000D01*
X995300Y1027900D01*
Y1021340D01*
X998294Y1018346D01*
Y1012140D01*
X998094Y1011940D01*
X994861D01*
G03X991127I-1867J-2350D01*
G01X986060D01*
X984887Y1010767D01*
Y1002004D01*
X986902Y999989D01*
Y982112D01*
X984958Y980168D01*
Y972327D01*
X985685Y971600D01*
X999600D01*
X1000700Y972700D01*
Y978700D01*
X1001200Y979200D01*
X1008000D01*
X1008200Y979000D01*
Y978295D01*
G03X1008192Y978090I2993J-219D01*
G01Y975927D01*
X1008200Y975919D01*
Y970600D01*
X1003300Y965700D01*
X970900D01*
X965900Y960700D01*
Y956400D01*
X965500Y956000D01*
X964665D01*
G03X964600Y956002I-82J-1599D01*
G01X963200D01*
G03X963135Y956000I17J-1601D01*
G01X962900D01*
X962500Y956400D01*
Y962600D01*
X961100Y964000D01*
X950000D01*
X942914Y956914D01*
X942436D01*
X939746Y954223D01*
G03X939021Y953050I2122J-2122D01*
G01X939006Y953006D01*
X937940Y951940D01*
Y945916D01*
X937220Y945195D01*
X936104Y944079D01*
Y939577D01*
X936359Y939322D01*
G03X937212Y938469I1776J923D01*
G01X941002Y934679D01*
Y934635D01*
X941879Y933758D01*
X941888Y933690D01*
G03X943266Y932312I1588J210D01*
G01X943334Y932303D01*
X950143Y925494D01*
Y910301D01*
X951044Y909400D01*
X951735D01*
G03X951800Y909398I82J1599D01*
G01X953200D01*
G03X953265Y909400I-17J1601D01*
G01X956235D01*
G03X956300Y909398I82J1599D01*
G01X957700D01*
G03X957717Y909399I-85J1597D01*
G01X957801D01*
X958200Y909000D01*
Y903400D01*
X959800Y901800D01*
X965063D01*
X969000Y905737D01*
Y908158D01*
G03Y908342I-3000J92D01*
G01Y909200D01*
X969200Y909400D01*
X969735D01*
G03X969800Y909398I82J1599D01*
G01X971200D01*
G03X971265Y909400I-17J1601D01*
G01X971500D01*
X971616Y909284D01*
Y908429D01*
X971632Y908413D01*
Y905059D01*
X971596Y905023D01*
Y904590D01*
X957606Y890600D01*
X914100D01*
X894800Y871300D01*
Y854900D01*
X894500Y854600D01*
X888600D01*
X888200Y855000D01*
Y855914D01*
G03X888204Y856027I-1597J113D01*
G01Y857427D01*
G03X888200Y857540I-1601J0D01*
G01Y861301D01*
X888202Y861314D01*
G03Y861922I-2320J304D01*
G01X888200Y861935D01*
Y863200D01*
X887300Y864100D01*
X872100D01*
X868800Y860800D01*
Y852800D01*
X870500Y851100D01*
X875162D01*
G03X875873Y850619I1737J1801D01*
G01X876304Y850188D01*
Y845553D01*
G03X876642Y844342I2338J0D01*
G01Y842542D01*
X876500Y842400D01*
X872310D01*
G03X868016I-2147J-2097D01*
G01X863700D01*
X862600Y841300D01*
Y818794D01*
X865597Y815797D01*
X871917D01*
X872225Y815489D01*
Y815380D01*
G03X872222Y815280I1598J-98D01*
G01Y813880D01*
G03X872225Y813780I1601J-2D01*
G01Y809775D01*
X873000Y809000D01*
X874141D01*
X874158Y808997D01*
G03X874569Y808960I414J2303D01*
G01X879589D01*
X879629Y809000D01*
X884400D01*
X884850Y808550D01*
Y802450D01*
X884400Y802000D01*
X865600D01*
X858300Y809300D01*
Y858400D01*
X870900Y871000D01*
X884000D01*
X904850Y891850D01*
Y905350D01*
X909650Y910150D01*
X915250D01*
X915700Y909700D01*
Y906098D01*
X912754Y903151D01*
G03X911980Y901817I2122J-2123D01*
G01X911966Y901766D01*
X911600Y901400D01*
Y899170D01*
X912339Y898431D01*
X913372D01*
X913417Y898406D01*
G03X916379Y898431I1459J2623D01*
G01X927358D01*
X927388Y898422D01*
G03X928812I712J2228D01*
G01X928842Y898431D01*
X941370D01*
X941450Y898511D01*
X941520Y898519D01*
G03X943614Y900845I-245J2326D01*
G01Y902597D01*
G03X943976Y903745I-1639J1148D01*
G01Y906645D01*
G03X943614Y907793I-2001J0D01*
G01Y916391D01*
X939298Y920707D01*
Y931268D01*
X933816Y936750D01*
Y944385D01*
X933294Y944907D01*
Y951336D01*
X939900Y957942D01*
Y960568D01*
X938676Y961792D01*
X937791D01*
X937777Y961794D01*
G03X937561Y961808I-211J-1587D01*
G01X936161D01*
G03X935945Y961794I-5J-1601D01*
G01X935931Y961792D01*
X933291D01*
X933277Y961794D01*
G03X933061Y961808I-211J-1587D01*
G01X931661D01*
X931625D01*
X931540Y961806D01*
X931168Y962177D01*
X931155D01*
Y965065D01*
X929124Y967096D01*
X922856D01*
X921478Y965718D01*
Y964323D01*
X921549Y964252D01*
X921540Y964243D01*
Y961883D01*
G02X921336Y961683I-200J0D01*
G03X921307Y961684I-70J-1600D01*
G01X919907D01*
G03X919735Y961674I7J-1602D01*
G01X919725Y961673D01*
X919514D01*
Y966378D01*
X921881Y968746D01*
G03X922732Y971281I-2122J2123D01*
G01X922730Y971295D01*
Y972283D01*
X920476Y974537D01*
Y979546D01*
X920798Y979868D01*
X923064D01*
X923798Y979134D01*
Y978870D01*
X923796Y978853D01*
G03X923760Y978450I2303J-409D01*
G01Y975192D01*
X925636Y973317D01*
G03X925654Y973277I2290J1007D01*
G01X925673Y973237D01*
Y972935D01*
X926960Y971648D01*
X930842D01*
X933982Y968508D01*
X934673D01*
X934691Y968526D01*
X935944D01*
Y968500D01*
X947900D01*
X953600Y974200D01*
Y980000D01*
X953900Y980300D01*
X956000D01*
X956500Y979800D01*
Y979342D01*
G03X956498Y979250I3000J-111D01*
G01Y976582D01*
X956500Y976580D01*
Y975300D01*
X957600Y974200D01*
X958880D01*
X959012Y974069D01*
G03X963256Y978313I2122J2122D01*
G01X962600Y978970D01*
Y980000D01*
X963010Y980410D01*
X963104D01*
G03X963300Y980398I196J1590D01*
G01X964700D01*
G03X965436Y980578I-2J1602D01*
G01X965479Y980600D01*
X965700D01*
X965749Y980551D01*
X965759Y980561D01*
X976383D01*
X980104Y984282D01*
Y1022703D01*
X981568Y1024167D01*
Y1027532D01*
X977900Y1031200D01*
X962900D01*
X961600Y1029900D01*
Y1027050D01*
X961587Y1027016D01*
G03X961539Y1026873I2193J-816D01*
G01X961525Y1026825D01*
X961200Y1026500D01*
X959200D01*
X958800Y1026900D01*
Y1032971D01*
X957805Y1033966D01*
X945997D01*
X943994Y1031963D01*
Y1018761D01*
X945175Y1017580D01*
X949100D01*
X949106Y1017574D01*
Y1016615D01*
X949130Y1016591D01*
Y1011630D01*
X949100Y1011600D01*
X944909D01*
G03X943500Y1011952I-1410J-2650D01*
G01X939507D01*
X938832Y1011277D01*
X937459D01*
X932935Y1006753D01*
Y997632D01*
G03X933920Y993169I2393J-1812D01*
G01Y990253D01*
X931523Y987856D01*
X928486D01*
G03X926801Y987988I-1026J-2282D01*
G01X926689Y987957D01*
X926375Y988270D01*
Y994400D01*
X929790Y997815D01*
Y1017401D01*
X934145Y1021756D01*
X934306D01*
X938791Y1026241D01*
Y1026565D01*
X938816Y1026610D01*
G03X939014Y1027383I-1403J771D01*
G01Y1027447D01*
X939021Y1027472D01*
G03Y1028694I-2258J611D01*
G01X939014Y1028719D01*
Y1028783D01*
Y1036395D01*
X938032Y1037376D01*
G03X934334Y1034583I-1654J-1654D01*
G01Y1033286D01*
X934333Y1033275D01*
G03X934322Y1033090I1591J-187D01*
G01Y1031690D01*
G03X934333Y1031505I1602J2D01*
G01X934334Y1031494D01*
Y1031366D01*
X934069Y1031100D01*
X931922D01*
X931661Y1030839D01*
X930085D01*
X929949Y1030974D01*
X927994D01*
X927969Y1031000D01*
Y1031423D01*
X927974Y1031446D01*
G03X928054Y1032135I-2921J688D01*
G01Y1032510D01*
X928515Y1032970D01*
X928532D01*
G03X930371Y1033096I724J2913D01*
G01X930406Y1033110D01*
X931099D01*
X932351Y1034362D01*
Y1037528D01*
X930812Y1039067D01*
X925285D01*
X922066Y1035848D01*
Y1034048D01*
X922065Y1034038D01*
G03X922052Y1033753I2988J-279D01*
G01Y1032135D01*
G03X922065Y1031850I3001J-6D01*
G01X922066Y1031840D01*
Y1031320D01*
X921774Y1031028D01*
X919890D01*
X919794Y1031124D01*
Y1032771D01*
X919812Y1032789D01*
Y1033844D01*
X919532Y1034124D01*
Y1037632D01*
X924250Y1042350D01*
X956450D01*
X961500Y1037300D01*
X986100D01*
X991800Y1043000D01*
X1008200D01*
X1020291Y1055091D01*
Y1069684D01*
X1022017Y1071410D01*
X1022608D01*
X1022619Y1071409D01*
G03X1022800Y1071398I188J1591D01*
G01X1024200D01*
G03X1024381Y1071409I-7J1602D01*
G01X1024392Y1071410D01*
X1027108D01*
X1027119Y1071409D01*
G03X1027300Y1071398I188J1591D01*
G01X1028700D01*
G03X1028881Y1071409I-7J1602D01*
G01X1028892Y1071410D01*
X1029061D01*
X1029479Y1070992D01*
Y1064811D01*
X1030502Y1063788D01*
X1038244D01*
X1039782Y1065326D01*
Y1065973D01*
X1039796Y1066008D01*
G03X1040002Y1067100I-2796J1093D01*
G01Y1070250D01*
G03X1039926Y1070921I-3002J0D01*
G02X1040315Y1071410I390J89D01*
G01X1040604D01*
X1040615Y1071409D01*
G03X1040800Y1071398I187J1591D01*
G01X1042200D01*
G03X1043321Y1071856I0J1601D01*
G01X1067179D01*
G03X1068300Y1071398I1121J1143D01*
G01X1069700D01*
G03X1070302Y1071516I-1J1602D01*
G01X1070424Y1071566D01*
G37*
G36*
G01X871610Y1469036D02*
X871195Y1469451D01*
Y1476985D01*
G03X871770Y1479149I-2404J1797D01*
G01X871758Y1479246D01*
X872469Y1479957D01*
Y1485592D01*
G03X872638Y1488423I-2556J1573D01*
G01X872580Y1488550D01*
X873132Y1489102D01*
X876035D01*
X876774Y1488363D01*
Y1476518D01*
X877563Y1475729D01*
Y1469259D01*
X877340Y1469036D01*
X871610D01*
G37*
G36*
G01X888024Y1549648D02*
X887000Y1550672D01*
Y1558200D01*
X888764Y1559964D01*
X904464D01*
X920300Y1575800D01*
Y1598341D01*
X917629Y1601012D01*
X912591D01*
X912564Y1601020D01*
G03X911058I-753J-2595D01*
G01X911031Y1601012D01*
X910466D01*
X909199Y1602279D01*
Y1604812D01*
X910367Y1605980D01*
X910498Y1605906D01*
G03X913800Y1606439I1313J2362D01*
G01X924713D01*
X928154Y1602998D01*
Y1599432D01*
X928200D01*
Y1573100D01*
X904748Y1549648D01*
X888024D01*
G37*
G36*
G01X993650Y697912D02*
G03X972553Y714749I-16028J1552D01*
G02X972027Y715128I-126J379D01*
G01Y718504D01*
G03X969458Y727520I-17105J0D01*
G03X972872Y739651I-12558J10080D01*
G03X972303Y748208I-15772J3249D01*
G03X970196Y756163I-16103J-9D01*
G03X973418Y769398I-12567J10069D01*
G03X954009Y785577I-16098J420D01*
G03X938311Y776503I-1189J-16059D01*
G03X936000Y774427I9556J-12961D01*
G03X928414Y761495I8500J-13677D01*
G03X930269Y741818I13586J-8645D01*
G02X930220Y741226I-291J-274D01*
G03X929678Y740798I11907J-15635D01*
G01X909000D01*
Y760498D01*
X982109Y882000D01*
X998285D01*
X1003199Y877086D01*
Y824698D01*
X998854Y820353D01*
Y596597D01*
X972027D01*
Y679497D01*
G02X972557Y679875I400J0D01*
G03X993650Y697912I5237J15228D01*
G37*
G36*
G01X1034206Y155809D02*
X981500D01*
Y319578D01*
X1005622Y343700D01*
X1007200D01*
X1008404Y342496D01*
Y275425D01*
X1034206Y249622D01*
Y155809D01*
G37*
G36*
G01X1033546Y120299D02*
X990669D01*
X987888Y123080D01*
Y137951D01*
X990745Y140808D01*
X1044425D01*
X1045425Y139808D01*
Y121708D01*
X1044025Y120308D01*
X1033555D01*
X1033546Y120299D01*
G37*
G36*
G01X969695Y1169500D02*
X969646Y1169628D01*
G03X967545Y1171103I-2148J-826D01*
G01X967465Y1171105D01*
X966851Y1171719D01*
Y1179353D01*
X969098Y1181600D01*
X970402D01*
G03X973055Y1180002I2653J1403D01*
G01X975400D01*
Y1170100D01*
X974800Y1169500D01*
X969695D01*
G37*
G36*
G01X953010Y1508194D02*
X947000Y1514204D01*
X947051Y1514327D01*
G03X946322Y1517026I-2130J873D01*
G01Y1521004D01*
X946361Y1521042D01*
X947430D01*
X947448Y1521024D01*
Y1520908D01*
X947564D01*
X947628Y1520844D01*
X951457D01*
X952743Y1519558D01*
X953277D01*
X953281Y1519562D01*
X955816D01*
X959284Y1516094D01*
Y1510463D01*
X959064Y1510244D01*
Y1508566D01*
X958692Y1508194D01*
X953010D01*
G37*
G36*
G01X965893Y1511198D02*
G03X967809Y1510056I2105J1353D01*
G01X967882Y1510051D01*
X970777Y1507156D01*
Y1500420D01*
X970317Y1499960D01*
X955500D01*
X955005Y1499464D01*
X953556D01*
X952987Y1500033D01*
Y1505463D01*
X953682Y1506158D01*
X958355D01*
X959671Y1507474D01*
X959838D01*
Y1507640D01*
X960266Y1508068D01*
Y1509746D01*
X961718Y1511198D01*
X965893D01*
G37*
G36*
G01X955767Y1493053D02*
X955241Y1493579D01*
Y1498001D01*
X955998Y1498758D01*
X971617D01*
X972501Y1497874D01*
Y1493895D01*
X971659Y1493053D01*
X955767D01*
G37*
G36*
G01X1013658Y1537942D02*
X1012300Y1539300D01*
Y1561100D01*
X1011500Y1561900D01*
X986447D01*
X984147Y1564200D01*
Y1578892D01*
X986755Y1581500D01*
X1080228D01*
X1084046Y1577682D01*
Y1563531D01*
G03Y1559955I2411J-1788D01*
G01Y1541802D01*
X1080186Y1537942D01*
X1013658D01*
G37*
G36*
G01X1022750Y-73659D02*
X1024000Y-72409D01*
Y-72200D01*
X1028500Y-67700D01*
Y-59300D01*
X1029400Y-58400D01*
X1032700D01*
X1033000Y-58700D01*
Y-64910D01*
G03X1032304Y-66249I2000J-1890D01*
G01X1032292Y-66308D01*
X1032100Y-66500D01*
Y-101100D01*
X1028400Y-104800D01*
Y-104900D01*
X1018074Y-115226D01*
Y-119574D01*
X1018000Y-119648D01*
Y-127100D01*
X1017500Y-127600D01*
X1015100D01*
X1014700Y-127200D01*
Y-111500D01*
X1016150Y-110050D01*
Y-103950D01*
X1022750Y-97350D01*
Y-73659D01*
G37*
G36*
G01X1037431Y-102860D02*
X1024374Y-115918D01*
Y-116326D01*
X1023400Y-117300D01*
Y-126200D01*
X1022700Y-126900D01*
X1020400D01*
X1020000Y-126500D01*
Y-115400D01*
X1041100Y-94300D01*
X1045000D01*
X1048200Y-91100D01*
Y-77738D01*
G03Y-74134I-2400J1802D01*
G01Y-65000D01*
X1049600Y-63600D01*
X1055300D01*
X1055600Y-63900D01*
Y-66278D01*
X1055599Y-66289D01*
G03X1055582Y-66597I2734J-305D01*
G01Y-71571D01*
G03X1055340Y-72547I2751J-1200D01*
G01X1055334Y-72621D01*
X1054782Y-73174D01*
Y-76247D01*
G03X1055600Y-78307I3001J-1D01*
G01Y-93900D01*
X1046640Y-102860D01*
X1037431D01*
G37*
G36*
G01X1010917Y-79899D02*
G03X1012659Y-79074I-117J2499D01*
G01X1019726D01*
X1020526Y-79874D01*
Y-91074D01*
X1019526Y-92074D01*
X1011326D01*
X1010726Y-91474D01*
Y-80099D01*
G02X1010917Y-79899I200J0D01*
G37*
G36*
G01X1043184Y-92987D02*
X1034584D01*
X1033884Y-92287D01*
Y-79616D01*
X1035042Y-78458D01*
X1043042D01*
X1044084Y-79500D01*
Y-92087D01*
X1043184Y-92987D01*
G37*
G36*
G01X1029500Y-55500D02*
X1028839Y-54839D01*
Y-41415D01*
X1029375Y-40879D01*
X1030190D01*
X1030243Y-40919D01*
G03X1032977Y-41381I1811J2394D01*
G02X1033500Y-41761I123J-380D01*
G01Y-55000D01*
X1033000Y-55500D01*
X1029500D01*
G37*
G36*
G01X1044232Y91229D02*
X1033719D01*
X1031883Y93065D01*
Y114703D01*
X1033467Y116287D01*
X1044016D01*
X1045564Y114739D01*
Y92561D01*
X1044232Y91229D01*
G37*
G36*
G01X1073119Y908219D02*
X1048400Y883500D01*
Y875500D01*
X1048000Y875100D01*
X1045500D01*
X1044800Y875800D01*
Y878300D01*
X1043500Y879600D01*
X1033100D01*
X1031900Y878400D01*
Y870253D01*
X1037704Y864450D01*
Y861953D01*
G03X1038100Y860650I2339J-1D01*
G01Y859200D01*
X1037900Y859000D01*
X1033369D01*
G03X1029757I-1806J-2397D01*
G01X1025300D01*
X1023900Y857600D01*
Y834677D01*
X1029977Y828600D01*
X1042200D01*
X1044400Y826400D01*
X1051400D01*
X1053300Y828300D01*
Y833100D01*
X1053500Y833300D01*
X1055500D01*
X1055900Y832900D01*
Y824600D01*
X1052900Y821600D01*
X1027724D01*
X1018200Y831124D01*
Y883300D01*
X997386Y904114D01*
Y930676D01*
X1001446Y934736D01*
Y939353D01*
X1002750Y941520D01*
X1015250Y954020D01*
Y960150D01*
X1018400Y963300D01*
X1023800D01*
X1024400Y962700D01*
Y958800D01*
X1024100Y958500D01*
X1021500D01*
X1020500Y957500D01*
Y954407D01*
X1012452Y946358D01*
X1012079D01*
X1006948Y941228D01*
Y940856D01*
X1006633Y940540D01*
Y937577D01*
G03X1005999Y936308I967J-1276D01*
G03X1005698Y935000I2701J-1310D01*
G01Y930307D01*
X1006633Y929372D01*
Y921570D01*
X1009041Y919162D01*
Y912341D01*
X1010481Y910901D01*
X1016373D01*
X1016882Y910392D01*
Y910310D01*
X1016900Y910291D01*
Y907300D01*
X1016700Y907100D01*
X1016493D01*
G03X1016428Y907102I-82J-1599D01*
G01X1015028D01*
G03X1014963Y907100I17J-1601D01*
G01X1010100D01*
X1008700Y905700D01*
Y903200D01*
X1016600Y895300D01*
X1025900D01*
X1026531Y895931D01*
G03X1026654Y896046I-1535J1765D01*
G01X1027490Y896881D01*
Y896890D01*
X1027500Y896900D01*
Y903241D01*
X1027524Y903266D01*
Y905616D01*
X1028000Y906092D01*
X1035592D01*
X1035831Y905852D01*
Y899669D01*
X1037100Y898400D01*
X1045600D01*
X1047000Y899800D01*
Y905800D01*
X1047289Y906089D01*
X1049489D01*
X1049922Y905656D01*
Y899778D01*
X1051100Y898600D01*
X1054600D01*
X1056400Y900400D01*
Y905800D01*
X1056700Y906100D01*
X1056935D01*
G03X1057000Y906098I82J1599D01*
G01X1058400D01*
G03X1058465Y906100I-17J1601D01*
G01X1061000D01*
X1061900Y907000D01*
Y938890D01*
X1063000Y939990D01*
X1072090D01*
X1073119Y938962D01*
Y908219D01*
G37*
G36*
G01X1026605Y1104701D02*
Y1103250D01*
X1026458Y1103103D01*
X1026403D01*
X1026400Y1103100D01*
X1023187D01*
G03X1019213I-1987J-2250D01*
G01X1015300D01*
X1015297Y1103103D01*
X1015258D01*
X1013733Y1104628D01*
Y1121546D01*
X1009627Y1125652D01*
X994757D01*
X992807Y1127602D01*
Y1141484D01*
X993218Y1141895D01*
X996038D01*
X996352Y1141581D01*
Y1136024D01*
X997910Y1134466D01*
X1005877D01*
X1007504Y1136093D01*
Y1141665D01*
X1007720Y1141881D01*
X1009879D01*
X1010276Y1141484D01*
Y1136072D01*
X1011945Y1134403D01*
X1014965D01*
X1016470Y1135908D01*
Y1141622D01*
X1016735Y1141887D01*
X1018608D01*
X1018969Y1141526D01*
Y1139827D01*
X1020328Y1138468D01*
X1042994D01*
X1046676Y1134786D01*
X1130837D01*
X1131787Y1133836D01*
Y1121987D01*
X1130580Y1120780D01*
X1129762D01*
X1129747Y1120782D01*
G03X1129500Y1120802I-252J-1582D01*
G01X1128100D01*
G03X1127915Y1120791I2J-1602D01*
G01X1127904Y1120790D01*
X1127242D01*
X1126969Y1121062D01*
X1126999Y1121173D01*
G03X1127102Y1121950I-2899J780D01*
G01Y1125100D01*
G03X1126752Y1126505I-3002J-2D01*
G01X1126729Y1126549D01*
Y1127732D01*
X1125845Y1128616D01*
X1113576D01*
X1112759Y1127799D01*
Y1125772D01*
X1112751Y1125745D01*
G03X1112660Y1125100I2249J-646D01*
G01Y1121950D01*
G03X1112696Y1121547I2339J6D01*
G01X1112698Y1121530D01*
Y1121200D01*
G03X1112752Y1120788I1602J0D01*
G01X1112759Y1120763D01*
Y1119637D01*
X1112752Y1119612D01*
G03X1112698Y1119200I1548J-412D01*
G01Y1118870D01*
X1112696Y1118853D01*
G03X1112660Y1118450I2303J-409D01*
G01Y1115801D01*
X1112759Y1115702D01*
Y1114775D01*
X1116640Y1110894D01*
Y1107100D01*
G03X1117478Y1105306I2339J0D01*
G01Y1103990D01*
X1117068Y1103580D01*
X1113899D01*
G03X1109301I-2299J-1930D01*
G01X1105710D01*
X1105155Y1104135D01*
Y1112577D01*
G03Y1114675I-2091J1049D01*
G01Y1127999D01*
X1104188Y1128966D01*
X1069377D01*
X1067752Y1127341D01*
Y1121433D01*
X1068666Y1120519D01*
X1068852D01*
X1068886Y1120506D01*
G03X1069455Y1120402I568J1497D01*
G01X1070855D01*
G03X1071015Y1120410I0J1601D01*
G01X1071516D01*
X1072093Y1119834D01*
Y1116076D01*
X1072086Y1116051D01*
G03Y1114735I2414J-658D01*
G01X1072093Y1114710D01*
Y1114025D01*
X1072160Y1113958D01*
Y1112638D01*
X1073640Y1111158D01*
Y1107100D01*
G03X1074478Y1105306I2339J0D01*
G01Y1104078D01*
X1074400Y1104000D01*
X1070794D01*
G03X1066606I-2094J-2150D01*
G01X1061000D01*
X1058000Y1107000D01*
Y1121202D01*
X1055500Y1123702D01*
X1042071D01*
X1042039Y1123713D01*
G03X1040521I-759J-2213D01*
G01X1040489Y1123702D01*
X1038950D01*
X1037837Y1122589D01*
Y1120814D01*
X1037447Y1120424D01*
X1034947D01*
X1034495Y1120876D01*
Y1130337D01*
X1032684Y1132148D01*
X1021274D01*
X1019596Y1130470D01*
Y1113474D01*
X1020425Y1112645D01*
X1020432Y1112636D01*
G03X1020864Y1112206I1968J1545D01*
G01X1026140Y1106930D01*
Y1106100D01*
G03X1026605Y1104701I2340J1D01*
G37*
G36*
G01X1021370Y1465580D02*
X1015620D01*
X1015058Y1466142D01*
Y1484808D01*
X1015790Y1485540D01*
X1021230D01*
X1022108Y1484662D01*
Y1474033D01*
X1022075Y1474001D01*
Y1466285D01*
X1021370Y1465580D01*
G37*
G36*
G01X1015495Y1453337D02*
X1014884Y1453947D01*
Y1461907D01*
X1015901Y1462923D01*
X1020998D01*
X1022214Y1461707D01*
Y1453833D01*
X1021718Y1453337D01*
X1015495D01*
G37*
G36*
G01X1068130Y1444800D02*
X1011200D01*
X994483Y1461517D01*
Y1484633D01*
X995350Y1485500D01*
X1013280D01*
X1013683Y1485097D01*
Y1453067D01*
X1014800Y1451950D01*
X1022230D01*
X1023683Y1453403D01*
Y1484503D01*
X1024710Y1485530D01*
X1041273D01*
X1041683Y1485120D01*
Y1452947D01*
X1042550Y1452080D01*
X1050240D01*
X1051183Y1453023D01*
Y1483470D01*
X1053243Y1485530D01*
X1069220D01*
X1069500Y1485250D01*
Y1446170D01*
X1068130Y1444800D01*
G37*
G36*
G01X1079610Y1487520D02*
X994870D01*
X994082Y1488308D01*
Y1512750D01*
X994752Y1513420D01*
X1011330D01*
X1012300Y1514390D01*
Y1535000D01*
X1013400Y1536100D01*
X1078400D01*
X1080573Y1533927D01*
Y1502837D01*
X1080568Y1502832D01*
Y1488478D01*
X1079610Y1487520D01*
G37*
G36*
G01X1052772Y-60654D02*
X1052111Y-59993D01*
Y-46569D01*
X1052647Y-46033D01*
X1052737D01*
G03X1056250Y-46223I1888J2333D01*
G01X1056386Y-46136D01*
X1056772Y-46522D01*
Y-60154D01*
X1056272Y-60654D01*
X1052772D01*
G37*
G36*
G01X1076129Y95570D02*
G03X1073212Y95763I-2530J-16105D01*
G03X1066212Y99183I-10359J-12329D01*
G01Y262878D01*
X1040408Y288681D01*
Y366369D01*
G02X1040825Y366769I400J0D01*
G03X1050335Y369395I675J16089D01*
G03X1060875Y380629I-5043J15293D01*
G03X1061299Y381025I-10780J11967D01*
G03X1075638Y376683I11302J11475D01*
G03X1083071Y377281I2460J15917D01*
G01X1083187Y377319D01*
X1098056Y362450D01*
G02X1098022Y361854I-283J-283D01*
G03X1092994Y355889I12214J-15397D01*
G03X1080335Y339371I4447J-16518D01*
G01Y97910D01*
G03X1076129Y95570I5263J-14409D01*
G37*
G36*
G01X1056102Y474006D02*
Y489622D01*
G03X1058317Y490362I-4141J16081D01*
G01X1080335D01*
Y470329D01*
X1079746Y469740D01*
G02X1079136Y469792I-283J282D01*
G03X1056732Y473678I-13151J-9292D01*
G02X1056102Y474006I-230J328D01*
G37*
G36*
G01X1080335Y613955D02*
X1057507D01*
G03X1056102Y614465I-6363J-15339D01*
G01Y721903D01*
X1064216Y730017D01*
G02X1064899Y729734I283J-283D01*
G01Y702986D01*
X1076086Y691799D01*
X1080335D01*
Y613955D01*
G37*
G36*
G01X1120176Y712289D02*
X1115542Y709972D01*
X1115484Y709978D01*
G03X1111868Y706982I-327J-3286D01*
G01X1111852Y706800D01*
X1108620D01*
X1108604Y706982D01*
G03X1102026I-3289J-290D01*
G01X1102010Y706800D01*
X1082300D01*
X1079900Y709200D01*
Y750000D01*
X1083800Y753900D01*
X1180100D01*
X1182378Y751622D01*
Y708878D01*
X1180400Y706900D01*
X1122596D01*
G02X1122506Y707279I-1J200D01*
G01X1122646Y707349D01*
X1122704Y707343D01*
G03X1120206Y712338I327J3286D01*
G01X1120176Y712289D01*
G37*
G36*
G01X1131420Y849868D02*
Y847031D01*
G03X1123356Y838671I6778J-14607D01*
G01X1123341Y838635D01*
X1041091Y756386D01*
G02X1040408Y756669I-283J283D01*
G01Y776978D01*
X1081393Y817962D01*
X1081510Y817923D01*
G03X1099646Y823760I5090J15277D01*
G03X1099636Y848448I-10346J12340D01*
G01Y859625D01*
G02X1100319Y859908I400J0D01*
G01X1108244Y851983D01*
Y851267D01*
X1108960D01*
X1110359Y849868D01*
X1131420D01*
G37*
G36*
G01X1077240Y1465040D02*
X1071660D01*
X1071003Y1465697D01*
Y1485233D01*
X1071330Y1485560D01*
X1077198D01*
X1077908Y1484850D01*
Y1465708D01*
X1077240Y1465040D01*
G37*
G36*
G01X1043460Y1464970D02*
X1042884Y1465545D01*
Y1484842D01*
X1043573Y1485530D01*
X1049183D01*
X1049783Y1484930D01*
Y1465623D01*
X1049130Y1464970D01*
X1043460D01*
G37*
G36*
G01X1043295Y1453337D02*
X1042884Y1453747D01*
Y1462107D01*
X1043701Y1462923D01*
X1048798D01*
X1049982Y1461740D01*
Y1453800D01*
X1049518Y1453337D01*
X1043295D01*
G37*
G36*
G01X1077618D02*
X1071395D01*
X1070729Y1454002D01*
Y1461851D01*
X1071801Y1462923D01*
X1076898D01*
X1078114Y1461707D01*
Y1453833D01*
X1077618Y1453337D01*
G37*
G36*
G01X1217468Y1476378D02*
G02X1216535Y1475445I-933J0D01*
G01X1168110D01*
G03X1161169Y1468504I0J-6941D01*
G01Y1439931D01*
X1156173D01*
Y1456640D01*
X1115925D01*
X1109400Y1450115D01*
X1093115D01*
Y1467921D01*
X1092909Y1468127D01*
Y1479604D01*
X1095569Y1482264D01*
Y1496618D01*
X1095574Y1496623D01*
Y1514619D01*
X1104660D01*
X1114248Y1524207D01*
Y1571506D01*
G02X1114761Y1571890I400J0D01*
G03X1119681Y1571180I4920J16693D01*
G01X1126383D01*
G03X1138837Y1576427I0J17403D01*
G02X1139521Y1576106I286J-279D01*
G03X1139287Y1571654I42369J-4459D01*
G01Y1548054D01*
G03X1197436Y1508388I42603J0D01*
G01X1197471Y1508402D01*
X1212472D01*
Y1611306D01*
X1197471D01*
X1197436Y1611320D01*
G03X1144247Y1591604I-15545J-39666D01*
G02X1143500Y1591719I-354J187D01*
G03X1142605Y1594882I-17118J-3136D01*
G03X1131808Y1617717I-16223J6299D01*
G02X1131570Y1618265I125J380D01*
G03X1133994Y1635252I-27043J12525D01*
G01X1133992Y1635267D01*
Y1650136D01*
X1133860Y1650268D01*
X1071589D01*
Y1655264D01*
X1216535D01*
G02X1217468Y1654331I0J-933D01*
G01Y1476378D01*
G37*
G36*
G01X1091400Y-3000D02*
X1088500Y-100D01*
Y31400D01*
X1093700Y36600D01*
X1101613D01*
G02X1102013Y36202I0J-400D01*
G03X1108617I3302J19D01*
G02X1109017Y36600I400J-2D01*
G01X1111455D01*
G02X1111855Y36202I0J-400D01*
G03X1118459I3302J19D01*
G02X1118859Y36600I400J-2D01*
G01X1129100D01*
X1141500Y49000D01*
Y89000D01*
X1143500Y91000D01*
X1188500D01*
X1191818Y87682D01*
Y41080D01*
X1147738Y-3000D01*
X1091400D01*
G37*
G36*
G01X1213974Y730300D02*
G03X1213704Y733235I-16106J-2D01*
G01X1213701Y733253D01*
Y739414D01*
X1202314Y750801D01*
X1197379D01*
Y757836D01*
X1186314Y768901D01*
X1121100D01*
Y786901D01*
X1162100Y827901D01*
Y900006D01*
X1173254Y911160D01*
X1204394D01*
X1207734Y914500D01*
X1223663D01*
G02X1224060Y914048I0J-400D01*
G03X1224870Y906426I16162J-2136D01*
G01X1224882Y906393D01*
Y900074D01*
X1212429Y887621D01*
Y815143D01*
G03X1216922Y804296I15340J0D01*
G01X1221710Y799508D01*
G03X1232557Y795015I10847J10847D01*
G01X1238081D01*
G03X1248928Y799508I0J15340D01*
G01X1252716Y803296D01*
G03X1254036Y804800I-10845J10849D01*
G01X1261400D01*
G03X1272075Y787659I40470J13309D01*
G02X1271795Y786973I-280J-286D01*
G01X1261590D01*
Y746767D01*
X1266109D01*
G03X1268449Y743387I15585J8290D01*
G01X1268499Y743331D01*
Y738588D01*
X1259484D01*
X1259452Y738599D01*
G03X1237619Y725623I-5452J-15682D01*
G01X1231994D01*
Y692211D01*
X1234994D01*
Y677211D01*
X1243513D01*
G03X1250836Y673772I10287J12389D01*
G01Y645258D01*
G03X1243794Y631998I8963J-13260D01*
G01Y619498D01*
G03X1261156Y603549I16006J0D01*
G02X1261590Y603151I34J-398D01*
G01Y574523D01*
X1301796D01*
Y584713D01*
G03X1304829Y598106I-12690J9914D01*
G02X1305219Y598592I390J86D01*
G01X1308534D01*
Y599311D01*
X1312000D01*
G03X1321715Y602571I0J16106D01*
G01X1321768Y602611D01*
X1323596D01*
X1323613Y602608D01*
G03X1328511Y602498I2811J16059D01*
G01X1328524Y602500D01*
X1339399D01*
Y580386D01*
X1344035Y575750D01*
X1342999Y574714D01*
Y549688D01*
G03X1341490Y545299I14317J-7376D01*
G03X1330663Y534583I4567J-15442D01*
G03X1328072Y532900I7436J-14284D01*
G03X1321509Y529409I4077J-15579D01*
G01X1316170D01*
Y524028D01*
X1314979D01*
Y489516D01*
X1321431D01*
G03X1325263Y483125I14678J4457D01*
G01X1332642Y475746D01*
Y430142D01*
X1328500Y426000D01*
X1322909D01*
X1322863Y426026D01*
G03X1264716Y409802I-20993J-37072D01*
G01X1264659Y409700D01*
X1260500D01*
X1258058Y412142D01*
Y426364D01*
X1268444Y436750D01*
X1268475Y436765D01*
G03X1276235Y444525I-6975J14735D01*
G01X1276250Y444556D01*
X1280725Y449031D01*
G03X1285218Y459878I-10847J10847D01*
G01Y481915D01*
X1286584D01*
Y520927D01*
X1274998D01*
Y524156D01*
X1271732D01*
X1271673Y524224D01*
G03X1269567Y526228I-12247J-10761D01*
G01Y529569D01*
X1264290D01*
G03X1252364Y533668I-10779J-11963D01*
G03X1224181Y529538I-13002J-9500D01*
G01X1222488D01*
G02X1222111Y530070I0J400D01*
G03X1224493Y544116I-40221J14046D01*
G01Y567717D01*
G03X1192941Y608862I-42603J0D01*
G01Y618934D01*
G03X1160756Y619869I-16106J0D01*
G01X1160752Y619793D01*
X1151659Y610700D01*
X1143700D01*
X1140137Y614263D01*
Y691899D01*
X1186614D01*
X1190948Y696233D01*
X1191038Y696227D01*
G03X1192068Y696194I1030J16073D01*
G01X1195668D01*
G03X1201235Y697187I-1J16106D01*
G01X1201268Y697199D01*
X1203314D01*
X1205059Y698944D01*
X1205424D01*
Y699309D01*
X1206450Y700336D01*
X1206454Y700339D01*
G03X1207629Y701514I-10786J11961D01*
G01X1207632Y701518D01*
X1213701Y707586D01*
Y720147D01*
X1213704Y720165D01*
G03X1213974Y723100I-15836J2937D01*
G01Y730300D01*
G37*
G36*
G01X1130894Y864869D02*
X1116573D01*
X1114720Y866722D01*
Y879021D01*
X1116575Y880876D01*
X1130875D01*
X1132747Y879004D01*
Y866722D01*
X1130894Y864869D01*
G37*
G36*
G01X1128628Y886020D02*
X1116749D01*
X1114813Y887956D01*
Y898953D01*
X1117440Y901580D01*
X1128889D01*
X1129595Y900874D01*
Y886987D01*
X1128628Y886020D01*
G37*
G36*
G01X1111147Y901217D02*
X1099747D01*
X1098747Y902217D01*
Y920317D01*
X1100287Y921857D01*
X1111007D01*
X1112347Y920517D01*
Y902417D01*
X1111147Y901217D01*
G37*
G36*
G01X1110954Y927924D02*
X1100340D01*
X1098947Y929317D01*
Y947417D01*
X1100147Y948617D01*
X1111547D01*
X1112547Y947617D01*
Y929517D01*
X1110954Y927924D01*
G37*
G36*
G01X1098446Y1529620D02*
X1089558D01*
X1089163Y1530015D01*
Y1561625D01*
X1090403Y1562865D01*
X1097582D01*
X1099247Y1561201D01*
Y1530421D01*
X1098446Y1529620D01*
G37*
G36*
G01X1140137Y442913D02*
Y494037D01*
X1141200Y495100D01*
X1144080D01*
X1157340Y476787D01*
X1175544Y396444D01*
X1173900Y394800D01*
X1172703D01*
X1166837Y402904D01*
X1158392Y414568D01*
X1157762Y414669D01*
X1150171Y425152D01*
X1139196Y432759D01*
X1139175Y432820D01*
G03X1138217Y435039I-16145J-5654D01*
G03X1140137Y442913I-15186J7874D01*
G37*
G36*
G01X1632048Y1257584D02*
X1632062D01*
Y1296746D01*
X1627968D01*
G03X1625235Y1300459I-13580J-7134D01*
G01X1621847Y1303847D01*
G03X1611000Y1308340I-10847J-10847D01*
G01X1604876D01*
G03X1594029Y1303847I0J-15340D01*
G01X1592425Y1302243D01*
G02X1591749Y1302451I-283J283D01*
G03X1507370Y1296934I-41848J-7986D01*
G01X1507359Y1296746D01*
X1503755D01*
G03X1501022Y1300459I-13580J-7134D01*
G01X1497634Y1303847D01*
G03X1486787Y1308340I-10847J-10847D01*
G01X1480663D01*
G03X1469816Y1303847I0J-15340D01*
G01X1465328Y1299359D01*
G03X1460835Y1288512I10847J-10847D01*
G01Y1271120D01*
G03X1460823Y1260113I15340J-5520D01*
G01X1460835Y1260080D01*
Y1252593D01*
G03X1458057Y1238569I12765J-9816D01*
G01X1455613Y1236125D01*
Y1233187D01*
X1455555Y1233128D01*
G03X1451197Y1218706I11445J-11328D01*
G02X1450805Y1218229I-392J-77D01*
G01X1446644D01*
X1446591Y1218266D01*
G03X1437213Y1221279I-9379J-13093D01*
G01X1429338D01*
X1429318Y1221456D01*
G03X1426009Y1229539I-15999J-1831D01*
G01Y1239729D01*
X1394778D01*
G03X1382812Y1239965I-6278J-14829D01*
G02X1382271Y1240339I-141J374D01*
G01Y1257584D01*
X1383637D01*
Y1296746D01*
X1380523D01*
X1368929Y1308340D01*
X1351644D01*
X1351643Y1308341D01*
X1342151D01*
G03X1259339Y1296934I-40280J-13875D01*
G01X1259328Y1296746D01*
X1255330D01*
G03X1252597Y1300459I-13580J-7134D01*
G01X1249209Y1303847D01*
G03X1238362Y1308340I-10847J-10847D01*
G01X1207913D01*
Y1332870D01*
X1173980Y1366803D01*
X1168689D01*
Y1371799D01*
X1170918D01*
Y1371802D01*
X1227254D01*
Y1371799D01*
X1930906D01*
G02X1931839Y1370866I0J-933D01*
G01Y3937D01*
G02X1930906Y3004I-933J0D01*
G01X1562992D01*
G02X1562059Y3937I0J933D01*
G01Y55118D01*
G03X1555118Y62059I-6941J0D01*
G01X1554074D01*
Y82056D01*
X1549377D01*
G03X1549189Y84569I-16503J29D01*
G01Y85251D01*
X1581046D01*
X1604440Y108645D01*
Y140721D01*
G03Y151761I-15340J5520D01*
G01Y232895D01*
G02X1605123Y233177I400J-1D01*
G01X1621700Y216600D01*
Y204400D01*
X1611700Y194400D01*
Y166600D01*
X1616700Y161600D01*
Y156600D01*
X1621800Y151500D01*
Y146500D01*
X1626700Y141600D01*
Y136600D01*
X1631800Y131500D01*
Y121100D01*
X1639800Y113100D01*
X1658200D01*
X1681600Y136500D01*
Y141500D01*
X1683200Y143100D01*
X1703200D01*
X1726600Y166500D01*
Y289500D01*
X1698200Y317900D01*
X1683200D01*
X1681600Y319500D01*
Y324500D01*
X1668200Y337900D01*
X1638200D01*
X1631700Y331400D01*
Y289400D01*
X1630200Y287900D01*
X1619200D01*
X1605123Y273823D01*
G02X1604440Y274105I-283J283D01*
G01Y293104D01*
X1570219Y327325D01*
G02X1570311Y327959I283J283D01*
G03X1589822Y350478I-20410J37395D01*
G02X1590480Y350621I375J-140D01*
G01X1594348Y346753D01*
G03X1605195Y342260I10847J10847D01*
G01X1610719D01*
G03X1621566Y346753I0J15340D01*
G01X1625354Y350541D01*
G03X1626695Y352073I-10847J10847D01*
G01X1632062D01*
Y391235D01*
X1630696D01*
Y481494D01*
X1632513D01*
Y520506D01*
X1626654D01*
G03X1622351Y523317I-10847J-11906D01*
G01X1622232Y523370D01*
Y524111D01*
X1620143D01*
X1620117Y524118D01*
G03X1618663Y524451I-4319J-15516D01*
G03X1616801Y526183I-12001J-11035D01*
G01Y529524D01*
X1611524D01*
G03X1595014Y532610I-10779J-11963D01*
G03X1594802Y532579I2224J-15949D01*
G03X1582081Y534180I-8205J-13856D01*
G02X1581642Y534796I-113J384D01*
G03X1584098Y548101I-13142J9305D01*
G03X1552402Y544499I-16098J399D01*
G03X1567052Y528062I16098J-399D01*
G01Y524112D01*
X1565861D01*
Y489600D01*
X1572848D01*
G03X1581067Y482992I13444J8306D01*
G01Y478220D01*
X1581055Y478187D01*
G03X1581067Y467180I15352J-5487D01*
G01Y449650D01*
G02X1580372Y449380I-400J0D01*
G03X1553778Y431976I-11872J-10880D01*
G02X1553380Y431415I-366J-162D01*
G03X1512473Y409304I-3478J-42461D01*
G01X1512416Y409200D01*
X1509000D01*
X1506483Y411717D01*
Y414580D01*
X1506495Y414613D01*
G03X1506483Y425620I-15352J5487D01*
G01Y481494D01*
X1508300D01*
Y499634D01*
G02X1508727Y500033I400J0D01*
G03X1523068Y506975I1073J16067D01*
G03X1527751Y526596I-9868J12725D01*
G03X1528295Y527505I-13452J8668D01*
G01X1531303D01*
Y574523D01*
X1550221D01*
Y584713D01*
G03X1553254Y598106I-12690J9914D01*
G02X1553644Y598592I390J86D01*
G01X1556959D01*
Y599311D01*
X1560425D01*
G03X1570139Y602571I-1J16105D01*
G01X1570193Y602611D01*
X1572230D01*
X1572247Y602608D01*
G03X1577788Y602594I2811J16059D01*
G03X1580276Y602610I1141J16063D01*
G01X1580284Y602611D01*
X1586531D01*
Y604463D01*
G03X1595019Y619211I-7605J14194D01*
G02X1595523Y619611I400J14D01*
G03X1615844Y621927I7233J26846D01*
G02X1616432Y621574I188J-353D01*
G01Y619498D01*
G03X1633794Y603549I16006J0D01*
G02X1634228Y603151I34J-398D01*
G01Y574523D01*
X1674434D01*
Y584713D01*
G03X1677467Y598106I-12690J9914D01*
G02X1677857Y598592I390J86D01*
G01X1681172D01*
Y599311D01*
X1684638D01*
G03X1694352Y602571I-1J16105D01*
G01X1694406Y602611D01*
X1696961D01*
X1696978Y602608D01*
G03X1702598I2810J16059D01*
G01X1702615Y602611D01*
X1703771D01*
X1703779Y602610D01*
G03X1706221I1221J16057D01*
G01X1706229Y602611D01*
X1710744D01*
Y603623D01*
G03X1718354Y609667I-5743J15044D01*
G02X1719001Y609689I331J-223D01*
G03X1743682Y608942I12649J9809D01*
G01X1754934D01*
Y609920D01*
X1758440D01*
Y574523D01*
X1798646D01*
Y584713D01*
G03X1801679Y598106I-12690J9914D01*
G02X1802069Y598592I390J86D01*
G01X1805384D01*
Y599311D01*
X1808850D01*
G03X1818564Y602571I-1J16105D01*
G01X1818618Y602611D01*
X1820716D01*
X1820733Y602608D01*
G03X1824390Y602386I2810J16059D01*
G02X1824811Y601987I21J-400D01*
G01Y598425D01*
X1826753D01*
G03X1854793Y598136I14102J7775D01*
G03X1855132Y598385I-9364J13104D01*
G01X1855185Y598425D01*
X1857688D01*
X1857696Y598424D01*
G03X1860138I1221J16057D01*
G01X1860146Y598425D01*
X1871523D01*
Y604461D01*
G03X1872509Y605845I-12604J10023D01*
G03X1882219Y603549I8355J13653D01*
G02X1882653Y603151I34J-398D01*
G01Y574523D01*
X1926843D01*
Y1239800D01*
X1879121D01*
Y1257584D01*
X1880487D01*
Y1296746D01*
X1875124D01*
G03X1873647Y1298459I-12325J-9133D01*
G01X1870559Y1301547D01*
G03X1859712Y1306040I-10847J-10847D01*
G01X1853388D01*
G03X1842541Y1301547I0J-15340D01*
G01X1840844Y1299850D01*
G02X1840164Y1300080I-283J282D01*
G03X1755402Y1296934I-42231J-5616D01*
G01X1755391Y1296746D01*
X1752180D01*
G03X1749447Y1300459I-13580J-7134D01*
G01X1746059Y1303847D01*
G03X1735212Y1308340I-10847J-10847D01*
G01X1723110D01*
G03X1712263Y1303847I0J-15340D01*
G01X1707270Y1298854D01*
G03X1702777Y1288007I10847J-10847D01*
G01Y1280340D01*
X1702765Y1280307D01*
G03X1702777Y1269300I15352J-5487D01*
G01Y1245495D01*
G03X1694672Y1229179I7840J-14066D01*
G03X1687827Y1221130I8166J-13879D01*
G03X1685645Y1221279I-2186J-15957D01*
G01X1677763D01*
X1677743Y1221456D01*
G03X1674434Y1229539I-15999J-1831D01*
G01Y1239729D01*
X1638340D01*
Y1246554D01*
X1631367Y1253527D01*
G03X1631649Y1257170I-16011J3072D01*
G02X1632048Y1257584I400J14D01*
G37*
G36*
G01X1196048Y87775D02*
X1197641Y89368D01*
X1213068D01*
X1214268Y88168D01*
Y47718D01*
X1205868Y39318D01*
X1196005D01*
X1195820Y39503D01*
Y62496D01*
X1196048Y62724D01*
Y87775D01*
G37*
G36*
G01X1232200Y220600D02*
X1231100Y221700D01*
Y223039D01*
G03Y227211I-2158J2086D01*
G01Y231600D01*
X1231500Y232000D01*
X1237198D01*
Y231698D01*
X1242702D01*
X1243100Y231300D01*
Y222600D01*
X1241100Y220600D01*
X1232200D01*
G37*
G36*
G01X1197100Y712200D02*
X1187100D01*
X1185300Y714000D01*
Y719585D01*
X1186389Y720674D01*
Y734289D01*
X1187900Y735800D01*
X1196100D01*
X1198700Y733200D01*
Y713800D01*
X1197100Y712200D01*
G37*
G36*
G01X1284082Y916678D02*
X1284094Y916711D01*
G03Y927685I-15352J5487D01*
G01X1284082Y927718D01*
Y934080D01*
X1285448D01*
Y940501D01*
G03X1295455Y968566I-753J16085D01*
G02X1295486Y969187I267J298D01*
G03X1283260Y998068I-9486J13013D01*
G03X1282341Y998629I-8845J-13456D01*
G03X1265991Y1006533I-13963J-8021D01*
G03X1248496Y996142I-2373J-15927D01*
G03X1247708Y995871I4841J-15358D01*
G03X1239637Y991631I2776J-15087D01*
G01X1237506Y989500D01*
X1228270D01*
Y1008500D01*
X1235534D01*
X1235560Y1008493D01*
G03X1252267Y1013686I4341J15507D01*
G03X1272093Y1027106I3875J15630D01*
G01X1272117Y1027279D01*
X1301796D01*
Y1038701D01*
G03X1305057Y1050892I-12682J9924D01*
G02X1305453Y1051348I396J56D01*
G01X1308534D01*
Y1052067D01*
X1309600D01*
G03X1311717Y1052207I-2J16106D01*
G03X1341263Y1029327I31984J10785D01*
G02X1341442Y1028586I-29J-399D01*
G03X1365705Y1012148I8387J-13746D01*
G03X1371815Y1013416I-155J16102D01*
G02X1372282Y1012796I156J-368D01*
G03X1376528Y988850I12518J-10130D01*
G02X1376366Y988110I-206J-343D01*
G03X1365315Y981889I1736J-16009D01*
G01X1365255Y981811D01*
X1364583D01*
X1364526Y981862D01*
G03X1350008Y985545I-10764J-11976D01*
G03X1344284Y984946I-1213J-16057D01*
G03X1329238Y982088I-4879J-15346D01*
G03X1328195Y981934I1829J-15998D01*
G01X1328177Y981931D01*
X1318699D01*
Y976909D01*
X1317480D01*
Y974728D01*
X1317449Y974679D01*
G03X1317480Y957452I13621J-8589D01*
G01Y942397D01*
X1323271D01*
Y931889D01*
G03X1327764Y921042I15340J0D01*
G01X1331050Y917756D01*
G03X1332372Y915454I14752J6941D01*
G03X1336642Y893957I13708J-8450D01*
G01Y867553D01*
G02X1335922Y867312I-400J-1D01*
G03X1326213Y876674I-34054J-25600D01*
G03X1296737Y884003I-13446J8861D01*
G03X1264357Y861905I5133J-42293D01*
G01X1264301Y861800D01*
X1259800D01*
X1258058Y863542D01*
Y876364D01*
X1279589Y897895D01*
G03X1284082Y908742I-10847J10847D01*
G01Y916678D01*
G37*
G36*
G01X1309609Y114688D02*
X1308945Y115352D01*
Y120839D01*
X1310405Y122299D01*
X1319882D01*
X1320486Y121696D01*
X1322496D01*
X1323262Y120930D01*
Y118335D01*
G03X1323835Y116801I2340J0D01*
G01Y115463D01*
X1323060Y114688D01*
X1319989D01*
G03X1315321I-2334J-1887D01*
G01X1309609D01*
G37*
G36*
G01X1313000Y203661D02*
X1305500D01*
X1304500Y204661D01*
Y247161D01*
X1298000Y253661D01*
X1284500D01*
X1283500Y254661D01*
Y261161D01*
X1284500Y262161D01*
X1302500D01*
X1305000Y259661D01*
X1312000D01*
X1314000Y257661D01*
Y204661D01*
X1313000Y203661D01*
G37*
G36*
G01X1326000Y198161D02*
X1325000Y199161D01*
Y217661D01*
X1326000Y218661D01*
X1335000D01*
X1335660Y218000D01*
Y198822D01*
X1335000Y198161D01*
X1326000D01*
G37*
G36*
G01X1301500Y236161D02*
X1297000D01*
X1296000Y237161D01*
Y247161D01*
X1294500Y248661D01*
X1284500D01*
X1283500Y249661D01*
Y251161D01*
X1284500Y252161D01*
X1297500D01*
X1302500Y247161D01*
Y237161D01*
X1301500Y236161D01*
G37*
G36*
G01X1335000Y250161D02*
X1317500D01*
X1316500Y251161D01*
Y267161D01*
X1314694Y268967D01*
Y280078D01*
X1311411Y283361D01*
X1284167D01*
X1283500Y284028D01*
Y291161D01*
X1284500Y292161D01*
X1300000D01*
X1302000Y290161D01*
X1332500D01*
X1336000Y286661D01*
Y251161D01*
X1335000Y250161D01*
G37*
G36*
G01X1317500Y222161D02*
X1315500Y224161D01*
Y237661D01*
X1316500Y238661D01*
X1329500D01*
X1330500Y237661D01*
Y229661D01*
X1331000Y229161D01*
X1332500D01*
X1332908Y228753D01*
X1332902Y228663D01*
G03X1332898Y228561I1598J-114D01*
G01Y226961D01*
G03X1332909Y226776I1602J2D01*
G01X1332910Y226765D01*
Y224557D01*
X1332909Y224546D01*
G03X1332898Y224361I1591J-187D01*
G01Y222961D01*
G03X1332920Y222699I1602J3D01*
G01X1332937Y222598D01*
X1332500Y222161D01*
X1317500D01*
G37*
G36*
G01X1304207Y268954D02*
X1300933Y272228D01*
X1300954Y272334D01*
G03X1298234Y275054I-2254J466D01*
G01X1298128Y275033D01*
X1294500Y278661D01*
X1284500D01*
X1283500Y279661D01*
Y281161D01*
X1284498Y282160D01*
X1310873D01*
X1313471Y279561D01*
Y269429D01*
X1312996Y268954D01*
X1304207D01*
G37*
G36*
G01X1301500Y688917D02*
X1297000D01*
X1296000Y689917D01*
Y699917D01*
X1294500Y701417D01*
X1284500D01*
X1283500Y702417D01*
Y703917D01*
X1284500Y704917D01*
X1297500D01*
X1302500Y699917D01*
Y689917D01*
X1301500Y688917D01*
G37*
G36*
G01X1313000Y656417D02*
X1305500D01*
X1304500Y657417D01*
Y699917D01*
X1298000Y706417D01*
X1284500D01*
X1283500Y707417D01*
Y713917D01*
X1284500Y714917D01*
X1302500D01*
X1305000Y712417D01*
X1312000D01*
X1314000Y710417D01*
Y657417D01*
X1313000Y656417D01*
G37*
G36*
G01X1317500Y674917D02*
X1315500Y676917D01*
Y690417D01*
X1316500Y691417D01*
X1329500D01*
X1330500Y690417D01*
Y682417D01*
X1331000Y681917D01*
X1332500D01*
X1332908Y681509D01*
X1332902Y681419D01*
G03X1332898Y681317I1598J-114D01*
G01Y679717D01*
G03X1332909Y679532I1602J2D01*
G01X1332910Y679521D01*
Y677313D01*
X1332909Y677302D01*
G03X1332898Y677117I1591J-187D01*
G01Y675717D01*
G03X1332920Y675455I1602J3D01*
G01X1332937Y675354D01*
X1332500Y674917D01*
X1317500D01*
G37*
G36*
G01X1325054Y650917D02*
X1323995Y651976D01*
Y670446D01*
X1324966Y671417D01*
X1335347D01*
X1335660Y671104D01*
Y651696D01*
X1334881Y650917D01*
X1325054D01*
G37*
G36*
G01X1304207Y721710D02*
X1294500Y731417D01*
X1284500D01*
X1283500Y732417D01*
Y733917D01*
X1284498Y734916D01*
X1310873D01*
X1313471Y732317D01*
Y722185D01*
X1312996Y721710D01*
X1304207D01*
G37*
G36*
G01X1335000Y702917D02*
X1317500D01*
X1316500Y703917D01*
Y719917D01*
X1314694Y721723D01*
Y732834D01*
X1311411Y736117D01*
X1284167D01*
X1283500Y736784D01*
Y743917D01*
X1284500Y744917D01*
X1300000D01*
X1302000Y742917D01*
X1332500D01*
X1336000Y739417D01*
Y703917D01*
X1335000Y702917D01*
G37*
G36*
G01X1305500Y1109173D02*
X1304500Y1110173D01*
Y1152673D01*
X1298000Y1159173D01*
X1284500D01*
X1283500Y1160173D01*
Y1166673D01*
X1284500Y1167673D01*
X1302500D01*
X1305000Y1165173D01*
X1311654D01*
X1311918Y1164909D01*
G03X1313372Y1163762I2032J1081D01*
G01X1313425Y1163748D01*
X1314000Y1163173D01*
Y1110173D01*
X1313000Y1109173D01*
X1305500D01*
G37*
G36*
G01X1317500Y1127673D02*
X1315500Y1129673D01*
Y1143173D01*
X1316500Y1144173D01*
X1329500D01*
X1330500Y1143173D01*
Y1135173D01*
X1331000Y1134673D01*
X1332500D01*
X1332908Y1134265D01*
X1332902Y1134175D01*
G03X1332898Y1134073I1598J-114D01*
G01Y1132473D01*
G03X1332909Y1132288I1602J2D01*
G01X1332910Y1132277D01*
Y1130069D01*
X1332909Y1130058D01*
G03X1332898Y1129873I1591J-187D01*
G01Y1128473D01*
G03X1332920Y1128211I1602J3D01*
G01X1332937Y1128110D01*
X1332500Y1127673D01*
X1317500D01*
G37*
G36*
G01X1335000Y1103673D02*
X1326000D01*
X1325000Y1104673D01*
Y1123173D01*
X1326000Y1124173D01*
X1335000D01*
X1336000Y1123173D01*
Y1104673D01*
X1335000Y1103673D01*
G37*
G36*
G01X1312996Y1174466D02*
X1304207D01*
X1294500Y1184173D01*
X1284500D01*
X1283500Y1185173D01*
Y1186673D01*
X1284500Y1187673D01*
X1310871D01*
X1313471Y1185073D01*
Y1174941D01*
X1312996Y1174466D01*
G37*
G36*
G01X1301500Y1141673D02*
X1297000D01*
X1296000Y1142673D01*
Y1152673D01*
X1294500Y1154173D01*
X1284500D01*
X1283500Y1155173D01*
Y1156673D01*
X1284500Y1157673D01*
X1297500D01*
X1302500Y1152673D01*
Y1142673D01*
X1301500Y1141673D01*
G37*
G36*
G01X1317500Y1155673D02*
X1316500Y1156673D01*
Y1172673D01*
X1314694Y1174479D01*
Y1185590D01*
X1311411Y1188873D01*
X1311370D01*
X1311369Y1188874D01*
X1284166D01*
X1283500Y1189540D01*
Y1196673D01*
X1284500Y1197673D01*
X1300000D01*
X1302000Y1195673D01*
X1332500D01*
X1336000Y1192173D01*
Y1156673D01*
X1335000Y1155673D01*
X1317500D01*
G37*
G36*
G01X1356770Y342260D02*
X1362294D01*
G03X1373141Y346753I0J15340D01*
G01X1376929Y350541D01*
G03X1378270Y352073I-10847J10847D01*
G01X1383637D01*
Y391235D01*
X1382271D01*
Y397380D01*
X1382283Y397413D01*
G03X1382740Y398917I-15352J5486D01*
G03X1388597Y423041I-7040J14482D01*
G02X1389072Y423650I320J240D01*
G03X1401646Y423700I6228J14850D01*
G02X1402201Y423293I157J-368D01*
G03X1405988Y411233I16024J-1593D01*
G02X1405907Y410641I-304J-260D01*
G03X1430168Y392205I8975J-13370D01*
G02X1430824Y392368I379J-126D01*
G03X1451775Y391216I11146J11622D01*
G03X1456854Y388723I9525J12984D01*
G01Y381533D01*
G03X1451295Y378774I4245J-15533D01*
G03X1428612Y375073I-9525J-12984D01*
G03X1424251Y345145I3297J-15762D01*
G03X1426022Y341274I15403J4706D01*
G02X1425684Y340661I-338J-213D01*
G01X1337354D01*
G02X1337024Y341287I0J400D01*
G03X1341685Y350194I-35153J24069D01*
G02X1342341Y350335I374J-142D01*
G01X1345923Y346753D01*
G03X1356770Y342260I10847J10847D01*
G37*
G36*
G01X1359600Y545900D02*
X1358000Y547500D01*
Y568500D01*
X1359800Y570300D01*
X1378800D01*
X1380000Y571500D01*
Y575471D01*
X1380358Y575829D01*
X1389448D01*
Y573648D01*
X1389622D01*
Y569870D01*
X1389840Y569652D01*
X1397348D01*
X1398000Y569000D01*
Y547000D01*
X1396900Y545900D01*
X1359600D01*
G37*
G36*
G01X1387000Y544300D02*
X1388000Y543300D01*
Y529437D01*
X1387016Y528453D01*
X1363619D01*
X1362800Y529272D01*
Y541304D01*
X1362803Y541322D01*
G03X1362819Y541430I-1575J289D01*
G03Y543192I-2341J881D01*
G03X1362803Y543300I-1591J-181D01*
G01X1362800Y543318D01*
Y543619D01*
X1363481Y544300D01*
X1387000D01*
G37*
G36*
G01X1364000Y586000D02*
X1355000D01*
X1354400Y586600D01*
Y602600D01*
X1355400Y603600D01*
X1363800D01*
X1364700Y602700D01*
Y586700D01*
X1364000Y586000D01*
G37*
G36*
G01X1369212Y577288D02*
X1368000Y578500D01*
Y584341D01*
X1368702Y585043D01*
Y601702D01*
X1370500Y603500D01*
X1389887D01*
X1392253Y601134D01*
Y585820D01*
X1389514Y583081D01*
Y579552D01*
X1389448D01*
Y577506D01*
X1389231Y577288D01*
X1369212D01*
G37*
G36*
G01X1353365Y764848D02*
G03X1354650Y773716I-14665J6652D01*
G03X1336448Y792072I-15921J2415D01*
G02X1336071Y792706I-56J396D01*
G03X1341685Y802949I-34200J25405D01*
G02X1342341Y803090I374J-142D01*
G01X1345923Y799508D01*
G03X1356770Y795015I10847J10847D01*
G01X1362294D01*
G03X1373141Y799508I0J15340D01*
G01X1376929Y803296D01*
G03X1378270Y804828I-10847J10847D01*
G01X1383637D01*
Y843990D01*
X1382271D01*
Y873333D01*
G02X1382906Y873657I400J0D01*
G03Y899735I9449J13039D01*
G02X1382271Y900059I-235J324D01*
G01Y914217D01*
X1382444Y914240D01*
G03X1388701Y916462I-2145J15960D01*
G03X1384646Y947196I2299J15938D01*
G02X1384088Y947564I-158J368D01*
G01Y957152D01*
G03X1386372Y985916I-5988J14948D01*
G02X1386534Y986656I206J343D01*
G03X1378536Y1017500I-1734J16009D01*
G02X1378069Y1018120I-156J368D01*
G03X1371620Y1043166I-12518J10130D01*
G02X1371442Y1043764I151J370D01*
G03X1376974Y1057321I-27741J19227D01*
G02X1377530Y1057620I394J-67D01*
G03X1385369Y1056305I6485J14634D01*
G02X1385803Y1055907I34J-398D01*
G01Y1027279D01*
X1426009D01*
Y1037469D01*
G03X1429042Y1050862I-12690J9914D01*
G02X1429432Y1051348I390J86D01*
G01X1432747D01*
Y1052067D01*
X1433776D01*
X1433836Y1051995D01*
G03X1460750Y1055367I12377J10305D01*
G01X1462319D01*
Y1064173D01*
X1462321Y1064188D01*
G03X1462503Y1067351I-16108J2514D01*
G02X1462903Y1067767I400J16D01*
G01X1466819D01*
Y1076667D01*
X1473719D01*
Y1090343D01*
G03X1475473Y1093250I-13006J9830D01*
G03X1478733Y1098592I-11189J10494D01*
G02X1479267Y1098826I377J-134D01*
G03X1496518Y1101784I6341J14802D01*
G01X1496575Y1101837D01*
X1499261D01*
Y1098014D01*
G03X1492219Y1084754I8963J-13260D01*
G01Y1072254D01*
G03X1509581Y1056305I16006J0D01*
G02X1510015Y1055907I34J-398D01*
G01Y1027279D01*
X1550221D01*
Y1037469D01*
G03X1553254Y1050862I-12690J9914D01*
G02X1553644Y1051348I390J86D01*
G01X1556959D01*
Y1052067D01*
X1557747D01*
X1557807Y1051991D01*
G03X1585102Y1055367I12618J10009D01*
G01X1586531D01*
Y1065073D01*
X1586533Y1065088D01*
G03X1586728Y1067666I-16108J2515D01*
G01Y1067867D01*
X1591031D01*
Y1070367D01*
X1607031D01*
Y1079323D01*
G03X1613020Y1083026I-4857J14551D01*
G01X1615766Y1085772D01*
G02X1616448Y1085471I282J-283D01*
G03X1616432Y1084754I15990J-715D01*
G01Y1072254D01*
G03X1633794Y1056305I16006J0D01*
G02X1634228Y1055907I34J-398D01*
G01Y1042030D01*
G02X1633494Y1041809I-400J-1D01*
G03X1604142Y1035374I-13435J-8877D01*
G03X1586592Y1022433I-1742J-16008D01*
G02X1586058Y1022135I-393J76D01*
G03X1572010Y993310I-5676J-15069D01*
G02X1571870Y992574I-208J-342D01*
G03X1565905Y963131I2706J-15874D01*
G01Y942481D01*
X1571756D01*
X1571774Y942301D01*
G03X1576189Y932998I15262J1544D01*
G01X1577378Y931809D01*
X1577393Y931778D01*
G03X1580493Y927333I14736J6974D01*
G02X1580382Y926693I-286J-280D01*
G03X1572472Y906160I7018J-14494D01*
G03X1571240Y904486I12326J-10362D01*
G03X1554860Y884565I-740J-16086D01*
G02X1554429Y884072I-388J-95D01*
G03X1510136Y857000I-4528J-42362D01*
G01X1506483D01*
Y858080D01*
X1506495Y858113D01*
G03X1506483Y869120I-15352J5487D01*
G01Y914308D01*
G03X1511362Y915252I-583J16092D01*
G03X1515738Y943148I9838J12748D01*
G03X1508300Y946323I-9838J-12748D01*
G01Y952842D01*
G03X1498280Y983449I-4906J15338D01*
G02X1497810Y984034I-127J379D01*
G03X1495666Y1003415I-13810J8281D01*
G03X1491624Y1008281I-14167J-7656D01*
G03X1493989Y1020299I-13430J8885D01*
G03X1465734Y1027367I-12460J10201D01*
G03X1462107Y1017880I12460J-10201D01*
G02X1461467Y1017578I-400J18D01*
G03X1464703Y995066I-9667J-12878D01*
G02X1465423Y994849I321J-239D01*
G03X1468859Y985782I16077J908D01*
G02X1468654Y985149I-314J-248D01*
G03X1467688Y984845I4349J-15505D01*
G03X1462215Y985307I-4071J-15580D01*
G03X1448759Y981989I-3248J-15772D01*
G01X1442911D01*
Y976867D01*
X1441692D01*
Y942355D01*
X1447483D01*
Y940721D01*
G03X1447500Y940005I15340J6D01*
G01Y926095D01*
G03X1432132Y907258I500J-16095D01*
G03X1424434Y894584I8368J-13758D01*
G03X1435191Y866597I10866J-11884D01*
G03X1463963Y839143I27801J332D01*
G02X1464377Y838744I14J-400D01*
G01Y815383D01*
G03X1468870Y804536I15340J0D01*
G01X1472753Y800653D01*
G03X1475231Y798645I10844J10849D01*
G02X1475293Y798025I-219J-335D01*
G03X1470575Y784980I11307J-11465D01*
G02X1470211Y784543I-398J-39D01*
G03X1455706Y765963I1397J-16043D01*
G02X1455311Y765500I-395J-63D01*
G01X1446607D01*
G03X1437214Y768523I-9394J-13083D01*
G01X1426009D01*
Y786973D01*
X1385803D01*
Y777093D01*
G03X1384135Y774629I12444J-10220D01*
G02X1383536Y774509I-350J193D01*
G03X1357856Y765638I-10017J-12609D01*
G03X1353903Y764323I3064J-15809D01*
G02X1353365Y764848I-174J360D01*
G37*
G36*
G01X1425713Y236161D02*
X1421213D01*
X1420213Y237161D01*
Y247161D01*
X1418713Y248661D01*
X1408713D01*
X1407713Y249661D01*
Y251161D01*
X1408713Y252161D01*
X1421713D01*
X1426713Y247161D01*
Y237161D01*
X1425713Y236161D01*
G37*
G36*
G01X1437213Y203661D02*
X1429713D01*
X1428713Y204661D01*
Y247161D01*
X1422213Y253661D01*
X1408713D01*
X1407713Y254661D01*
Y261161D01*
X1408713Y262161D01*
X1426713D01*
X1429213Y259661D01*
X1436213D01*
X1438213Y257661D01*
Y204661D01*
X1437213Y203661D01*
G37*
G36*
G01X1428420Y268954D02*
X1418713Y278661D01*
X1408713D01*
X1407713Y279661D01*
Y281161D01*
X1408712Y282160D01*
X1435086D01*
X1437684Y279561D01*
Y269429D01*
X1437209Y268954D01*
X1428420D01*
G37*
G36*
G01X1459213Y250161D02*
X1441713D01*
X1440713Y251161D01*
Y267161D01*
X1438907Y268967D01*
Y280078D01*
X1435624Y283361D01*
X1408380D01*
X1407713Y284028D01*
Y291161D01*
X1408713Y292161D01*
X1424213D01*
X1426213Y290161D01*
X1456713D01*
X1460213Y286661D01*
Y251161D01*
X1459213Y250161D01*
G37*
G36*
G01X1434056Y418753D02*
G03X1411879Y436500I-15831J2947D01*
G02X1411324Y436907I-157J368D01*
G03X1382977Y448866I-16024J1593D01*
G02X1382271Y449123I-306J257D01*
G01Y495854D01*
X1381588Y496537D01*
Y513452D01*
X1393230D01*
X1397580Y517802D01*
G02X1398263Y517519I283J-283D01*
G01Y504351D01*
X1405863D01*
Y500951D01*
X1409713D01*
Y499751D01*
X1424961D01*
X1429103Y495609D01*
X1432320D01*
Y489365D01*
X1434680D01*
G03X1444762Y480116I14896J6118D01*
G01X1444809Y480101D01*
X1456854Y468056D01*
Y454020D01*
G03Y442980I15340J-5520D01*
G01Y419677D01*
G03X1451495Y416974I4445J-15477D01*
G03X1434632Y418324I-9525J-12984D01*
G02X1434056Y418753I-183J356D01*
G37*
G36*
G01X1405152Y534200D02*
X1390800D01*
X1389500Y535500D01*
Y544000D01*
X1390181Y544681D01*
X1405719D01*
X1406152Y544248D01*
Y535200D01*
X1405152Y534200D01*
G37*
G36*
G01X1408500Y547088D02*
X1400000D01*
X1399336Y547752D01*
Y552836D01*
X1400000Y553500D01*
X1408500D01*
X1409500Y552500D01*
Y548088D01*
X1408500Y547088D01*
G37*
G36*
G01X1425713Y688917D02*
X1421213D01*
X1420213Y689917D01*
Y699917D01*
X1418713Y701417D01*
X1408713D01*
X1407713Y702417D01*
Y703917D01*
X1408713Y704917D01*
X1421713D01*
X1426713Y699917D01*
Y689917D01*
X1425713Y688917D01*
G37*
G36*
G01X1437209Y721710D02*
X1428420D01*
X1418713Y731417D01*
X1408713D01*
X1407713Y732417D01*
Y733917D01*
X1408713Y734917D01*
X1435084D01*
X1437684Y732317D01*
Y722185D01*
X1437209Y721710D01*
G37*
G36*
G01X1441713Y702917D02*
X1440713Y703917D01*
Y719917D01*
X1438907Y721723D01*
Y732834D01*
X1435624Y736117D01*
X1435583D01*
X1435582Y736118D01*
X1408378D01*
X1407713Y736784D01*
Y743917D01*
X1408713Y744917D01*
X1424213D01*
X1426213Y742917D01*
X1456713D01*
X1460213Y739417D01*
Y703917D01*
X1459213Y702917D01*
X1441713D01*
G37*
G36*
G01X1429713Y656417D02*
X1428713Y657417D01*
Y699917D01*
X1422213Y706417D01*
X1408713D01*
X1407713Y707417D01*
Y713917D01*
X1408713Y714917D01*
X1426713D01*
X1429213Y712417D01*
X1436213D01*
X1436218Y712412D01*
G03X1436743Y711887I1869J1344D01*
G01X1438213Y710417D01*
Y657417D01*
X1437213Y656417D01*
X1429713D01*
G37*
G36*
G01X1437209Y1174466D02*
X1428420D01*
X1418713Y1184173D01*
X1408713D01*
X1407713Y1185173D01*
Y1186673D01*
X1408713Y1187673D01*
X1435084D01*
X1437684Y1185073D01*
Y1174941D01*
X1437209Y1174466D01*
G37*
G36*
G01X1425713Y1141673D02*
X1421213D01*
X1420213Y1142673D01*
Y1152673D01*
X1418713Y1154173D01*
X1408713D01*
X1407713Y1155173D01*
Y1156673D01*
X1408713Y1157673D01*
X1421713D01*
X1426713Y1152673D01*
Y1142673D01*
X1425713Y1141673D01*
G37*
G36*
G01X1437213Y1109173D02*
X1429713D01*
X1428713Y1110173D01*
Y1152673D01*
X1422213Y1159173D01*
X1408713D01*
X1407713Y1160173D01*
Y1166673D01*
X1408713Y1167673D01*
X1426713D01*
X1429213Y1165173D01*
X1436213D01*
X1438213Y1163173D01*
Y1110173D01*
X1437213Y1109173D01*
G37*
G36*
G01X1441713Y1155673D02*
X1440713Y1156673D01*
Y1172673D01*
X1438907Y1174479D01*
Y1185590D01*
X1435624Y1188873D01*
X1435583D01*
X1435582Y1188874D01*
X1408378D01*
X1407713Y1189540D01*
Y1196673D01*
X1408713Y1197673D01*
X1424213D01*
X1426213Y1195673D01*
X1456713D01*
X1460213Y1192173D01*
Y1156673D01*
X1459213Y1155673D01*
X1441713D01*
G37*
G36*
G01X1477553Y196159D02*
Y220911D01*
G03X1475969Y227700I-15341J0D01*
G01Y272417D01*
X1475214D01*
Y292875D01*
X1462927Y305162D01*
X1454981D01*
G03X1454969Y305213I-15681J-3663D01*
G01Y309981D01*
X1481685D01*
Y278920D01*
G03X1480723Y273173I15340J-5522D01*
G02X1480519Y272818I-400J-6D01*
G01Y239355D01*
X1482701D01*
G02X1483094Y238879I0J-400D01*
G03X1483510Y231061I15806J-3079D01*
G01X1483519Y231032D01*
Y224355D01*
X1487572D01*
X1487630Y224298D01*
G03X1499059Y219698I11270J11502D01*
G02X1499261Y219498I2J-200D01*
G01Y197275D01*
G03X1494388Y168177I3689J-15575D01*
G03X1497897Y162806I14238J5470D01*
G01Y156186D01*
X1510015D01*
Y154326D01*
X1510005Y154296D01*
G03X1509271Y148259I15331J-4927D01*
G02X1508872Y147832I-399J-27D01*
G01X1477001D01*
G03X1465196Y154648I-13198J-9227D01*
G02X1465016Y155384I34J398D01*
G03X1472381Y170712I-8643J13586D01*
G02X1472779Y171155I398J43D01*
G01X1473719D01*
Y184831D01*
G03X1476488Y190544I-13005J9831D01*
G03X1477553Y196159I-14275J5616D01*
G37*
G36*
G01X1450213Y198161D02*
X1449213Y199161D01*
Y217661D01*
X1450213Y218661D01*
X1459213D01*
X1459874Y218000D01*
Y198822D01*
X1459213Y198161D01*
X1450213D01*
G37*
G36*
G01X1441713Y222161D02*
X1439713Y224161D01*
Y237661D01*
X1440713Y238661D01*
X1453713D01*
X1454713Y237661D01*
Y229661D01*
X1455213Y229161D01*
X1456713D01*
X1457121Y228753D01*
X1457115Y228663D01*
G03X1457112Y228561I1598J-98D01*
G01Y226961D01*
G03X1457122Y226776I1601J-6D01*
G01X1457124Y226765D01*
Y224557D01*
X1457122Y224546D01*
G03X1457112Y224361I1591J-179D01*
G01Y222961D01*
G03X1457133Y222699I1601J-3D01*
G01X1457150Y222598D01*
X1456713Y222161D01*
X1441713D01*
G37*
G36*
G01X1435317Y510610D02*
X1433500Y512427D01*
Y519100D01*
X1433900Y519500D01*
X1434435D01*
G03X1434500Y519498I82J1599D01*
G01X1435900D01*
G03X1435965Y519500I-17J1601D01*
G01X1438335D01*
G03X1438400Y519498I82J1599D01*
G01X1440000D01*
G03X1440065Y519500I-17J1601D01*
G01X1440700D01*
X1441500Y520300D01*
Y520538D01*
X1441511Y520570D01*
G03X1441602Y521100I-1511J532D01*
G01Y521302D01*
X1441800Y521500D01*
X1445600D01*
X1445960Y521141D01*
Y521034D01*
G03X1445996Y520696I1601J0D01*
G01X1446000Y520675D01*
Y520200D01*
X1446700Y519500D01*
X1447100D01*
X1447127Y519493D01*
G03X1447561Y519432I438J1540D01*
G01X1448961D01*
G03X1449395Y519493I-4J1601D01*
G01X1449422Y519500D01*
X1451335D01*
G03X1451400Y519498I82J1599D01*
G01X1453000D01*
G03X1453065Y519500I-17J1601D01*
G01X1455403D01*
X1455423Y519496D01*
G03X1455739Y519464I319J1570D01*
G01X1457139D01*
G03X1457455Y519496I-3J1602D01*
G01X1457475Y519500D01*
X1459335D01*
G03X1459400Y519498I82J1599D01*
G01X1461000D01*
G03X1461065Y519500I-17J1601D01*
G01X1464835D01*
G03X1464900Y519498I82J1599D01*
G01X1466500D01*
G03X1466565Y519500I-17J1601D01*
G01X1467400D01*
X1467800Y519100D01*
Y514000D01*
X1467832Y513968D01*
Y511896D01*
X1466546Y510610D01*
X1435317D01*
G37*
G36*
G01X1445391Y570609D02*
X1450707Y565293D01*
X1450579Y565152D01*
G03X1450878Y561774I1700J-1552D01*
G01Y557800D01*
X1449752D01*
Y557892D01*
X1448626D01*
X1439503Y567014D01*
X1439499Y567090D01*
G03X1438600Y568441I-1599J-90D01*
G01X1438487Y568495D01*
Y575996D01*
X1439118Y576627D01*
X1444970D01*
X1445391Y576206D01*
Y570609D01*
G37*
G36*
G01X1444023Y578711D02*
X1433989D01*
X1433000Y579700D01*
Y581000D01*
X1433032Y581032D01*
Y588244D01*
X1433046Y588258D01*
Y590911D01*
X1433068Y590934D01*
Y593226D01*
X1434024Y594182D01*
X1443687D01*
X1444500Y593369D01*
Y579188D01*
X1444023Y578711D01*
G37*
G36*
G01X1456149Y585322D02*
X1446022D01*
X1445792Y585552D01*
Y595025D01*
X1446760Y595993D01*
X1456022D01*
X1456759Y595256D01*
Y585932D01*
X1456149Y585322D01*
G37*
G36*
G01X1441713Y674917D02*
X1439713Y676917D01*
Y690417D01*
X1440713Y691417D01*
X1453713D01*
X1454713Y690417D01*
Y682417D01*
X1455213Y681917D01*
X1456713D01*
X1457121Y681509D01*
X1457115Y681419D01*
G03X1457112Y681317I1598J-98D01*
G01Y679717D01*
G03X1457122Y679532I1601J-6D01*
G01X1457124Y679521D01*
Y677313D01*
X1457122Y677302D01*
G03X1457112Y677117I1591J-179D01*
G01Y675717D01*
G03X1457133Y675455I1601J-3D01*
G01X1457150Y675354D01*
X1456713Y674917D01*
X1441713D01*
G37*
G36*
G01X1450213Y650917D02*
X1449213Y651917D01*
Y670417D01*
X1450213Y671417D01*
X1459213D01*
X1459874Y670756D01*
Y651578D01*
X1459213Y650917D01*
X1450213D01*
G37*
G36*
G01X1441713Y1127673D02*
X1439713Y1129673D01*
Y1143173D01*
X1440713Y1144173D01*
X1453713D01*
X1454713Y1143173D01*
Y1135173D01*
X1455213Y1134673D01*
X1456713D01*
X1457121Y1134265D01*
X1457115Y1134175D01*
G03X1457112Y1134073I1598J-98D01*
G01Y1132473D01*
G03X1457122Y1132288I1601J-6D01*
G01X1457124Y1132277D01*
Y1130069D01*
X1457122Y1130058D01*
G03X1457112Y1129873I1591J-179D01*
G01Y1128473D01*
G03X1457133Y1128211I1601J-3D01*
G01X1457150Y1128110D01*
X1456713Y1127673D01*
X1441713D01*
G37*
G36*
G01X1450213Y1103673D02*
X1449213Y1104673D01*
Y1123173D01*
X1450213Y1124173D01*
X1461154D01*
X1461944Y1123383D01*
Y1104713D01*
X1460904Y1103673D01*
X1450213D01*
G37*
G36*
G01X1494870Y759346D02*
G03X1492514Y771066I-15837J2913D01*
G02X1492698Y771655I335J219D01*
G03X1497076Y798788I-6098J14904D01*
G02X1497090Y799407I260J304D01*
G03X1498498Y800653I-9443J12089D01*
G01X1501141Y803296D01*
G03X1502461Y804800I-10845J10849D01*
G01X1509430D01*
G03X1520106Y787659I40470J13311D01*
G02X1519826Y786973I-280J-286D01*
G01X1510015D01*
Y754723D01*
G02X1509334Y754439I-400J0D01*
G03X1495330Y758880I-11334J-11439D01*
G02X1494870Y759346I-66J394D01*
G37*
G36*
G01X1569651Y134147D02*
Y123909D01*
X1569649Y123894D01*
G03X1569456Y121640I16108J-2514D01*
G01X1569453Y121443D01*
X1550221D01*
Y145836D01*
X1556959D01*
Y146555D01*
X1560425D01*
G03X1570140Y149815I0J16106D01*
G01X1570193Y149855D01*
X1572652D01*
X1572669Y149852D01*
G03X1572773Y149834I2832J16055D01*
G02X1573099Y149363I-66J-394D01*
G03X1572962Y143929I16001J-3122D01*
G03X1569651Y134147I12794J-9782D01*
G37*
G36*
G01X1561425Y203661D02*
X1553925D01*
X1552925Y204661D01*
Y247161D01*
X1546425Y253661D01*
X1532925D01*
X1531925Y254661D01*
Y261161D01*
X1532925Y262161D01*
X1550925D01*
X1553425Y259661D01*
X1560425D01*
X1562425Y257661D01*
Y204661D01*
X1561425Y203661D01*
G37*
G36*
G01X1549925Y236161D02*
X1545425D01*
X1544425Y237161D01*
Y247161D01*
X1542925Y248661D01*
X1532925D01*
X1531925Y249661D01*
Y251161D01*
X1532925Y252161D01*
X1545925D01*
X1550925Y247161D01*
Y237161D01*
X1549925Y236161D01*
G37*
G36*
G01X1583425Y250161D02*
X1565925D01*
X1564925Y251161D01*
Y267161D01*
X1563119Y268967D01*
Y280078D01*
X1559836Y283361D01*
X1532592D01*
X1531925Y284028D01*
Y291161D01*
X1532925Y292161D01*
X1548425D01*
X1550425Y290161D01*
X1580925D01*
X1584425Y286661D01*
Y251161D01*
X1583425Y250161D01*
G37*
G36*
G01X1565925Y222161D02*
X1563925Y224161D01*
Y237661D01*
X1564925Y238661D01*
X1577925D01*
X1578925Y237661D01*
Y229661D01*
X1579425Y229161D01*
X1580925D01*
X1581333Y228753D01*
X1581327Y228663D01*
G03X1581324Y228561I1598J-98D01*
G01Y226961D01*
G03X1581334Y226776I1601J-6D01*
G01X1581336Y226765D01*
Y224557D01*
X1581334Y224546D01*
G03X1581324Y224361I1591J-179D01*
G01Y222961D01*
G03X1581345Y222699I1601J-3D01*
G01X1581362Y222598D01*
X1580925Y222161D01*
X1565925D01*
G37*
G36*
G01X1552632Y268954D02*
X1542925Y278661D01*
X1532925D01*
X1531925Y279661D01*
Y281161D01*
X1532924Y282160D01*
X1559298D01*
X1561896Y279561D01*
Y269429D01*
X1561421Y268954D01*
X1552632D01*
G37*
G36*
G01X1549925Y688917D02*
X1545425D01*
X1544425Y689917D01*
Y699917D01*
X1542925Y701417D01*
X1532925D01*
X1531925Y702417D01*
Y703917D01*
X1532925Y704917D01*
X1545925D01*
X1550925Y699917D01*
Y689917D01*
X1549925Y688917D01*
G37*
G36*
G01X1561284Y658391D02*
X1547871D01*
X1547313Y658949D01*
Y673031D01*
X1552925Y678643D01*
Y699917D01*
X1546425Y706417D01*
X1532925D01*
X1531925Y707417D01*
Y713917D01*
X1532925Y714917D01*
X1550925D01*
X1553425Y712417D01*
X1560425D01*
X1562425Y710417D01*
Y659532D01*
X1561284Y658391D01*
G37*
G36*
G01X1565925Y674917D02*
X1563925Y676917D01*
Y690417D01*
X1564925Y691417D01*
X1577925D01*
X1578925Y690417D01*
Y682417D01*
X1579425Y681917D01*
X1580925D01*
X1581333Y681509D01*
X1581327Y681419D01*
G03X1581324Y681317I1598J-98D01*
G01Y679717D01*
G03X1581334Y679532I1601J-6D01*
G01X1581336Y679521D01*
Y677313D01*
X1581334Y677302D01*
G03X1581324Y677117I1591J-179D01*
G01Y676153D01*
X1580087Y674917D01*
X1565925D01*
G37*
G36*
G01X1564589Y650917D02*
X1563843Y651663D01*
Y670623D01*
X1564637Y671417D01*
X1574937D01*
X1575762Y670592D01*
X1573836Y668665D01*
Y652118D01*
G02X1573433Y651718I-400J0D01*
G01X1573095D01*
X1573078Y651721D01*
G03X1572675Y651756I-403J-2303D01*
G01X1568813D01*
X1568780Y651769D01*
G03X1565923Y650917I-854J-2352D01*
G01X1564589D01*
G37*
G36*
G01X1552632Y721710D02*
X1542925Y731417D01*
X1532925D01*
X1531925Y732417D01*
Y733917D01*
X1532923Y734916D01*
X1559298D01*
X1561896Y732317D01*
Y722185D01*
X1561421Y721710D01*
X1552632D01*
G37*
G36*
G01X1583425Y702917D02*
X1565925D01*
X1564925Y703917D01*
Y719917D01*
X1563119Y721723D01*
Y732834D01*
X1559836Y736117D01*
X1532592D01*
X1531925Y736784D01*
Y743917D01*
X1532925Y744917D01*
X1548425D01*
X1550425Y742917D01*
X1580925D01*
X1584425Y739417D01*
Y703917D01*
X1583425Y702917D01*
G37*
G36*
G01X1599426Y725173D02*
Y745631D01*
X1587139Y757918D01*
X1579181D01*
Y765473D01*
X1570856D01*
G03X1561425Y768523I-9431J-13056D01*
G01X1553550D01*
X1553530Y768700D01*
G03X1551461Y774948I-15999J-1831D01*
G02X1551789Y775549I346J201D01*
G03X1589822Y803233I-1888J42561D01*
G02X1590480Y803376I375J-140D01*
G01X1598841Y795015D01*
X1617073D01*
X1625171Y803113D01*
G02X1625803Y803026I283J-282D01*
G03X1638506Y787679I48114J26894D01*
G02X1638249Y786973I-257J-306D01*
G01X1634228D01*
Y746767D01*
X1638747D01*
G03X1641087Y743387I15585J8290D01*
G01X1641137Y743331D01*
Y738588D01*
X1632122D01*
X1632090Y738599D01*
G03X1613982Y733664I-5453J-15682D01*
G03X1606355Y725623I7156J-14426D01*
G01X1604632D01*
Y725173D01*
X1599426D01*
G37*
G36*
G01X1568100Y1097100D02*
X1567000Y1098200D01*
Y1139000D01*
X1565500Y1140500D01*
Y1172846D01*
X1562673Y1175673D01*
Y1184655D01*
X1558155Y1189173D01*
X1532925D01*
X1531925Y1190173D01*
Y1196673D01*
X1532925Y1197673D01*
X1548425D01*
X1549998Y1196100D01*
X1564400D01*
X1575600Y1184900D01*
Y1152911D01*
G03X1578000Y1127642I16526J-11179D01*
G01Y1097900D01*
X1577200Y1097100D01*
X1568100D01*
G37*
G36*
G01X1562425Y1141800D02*
X1565662Y1138562D01*
Y1121462D01*
X1565100Y1120900D01*
X1553425D01*
X1552925Y1121400D01*
Y1128200D01*
X1553996Y1129272D01*
X1554827D01*
X1555156Y1129600D01*
X1556800D01*
X1558500Y1131300D01*
Y1132955D01*
G03X1557301Y1137724I-2269J1965D01*
G01X1554822Y1140203D01*
X1554809Y1140257D01*
G03X1553132Y1141934I-2234J-557D01*
G01X1553078Y1141947D01*
X1552925Y1142100D01*
Y1152673D01*
X1546425Y1159173D01*
X1532925D01*
X1531925Y1160173D01*
Y1166673D01*
X1532925Y1167673D01*
X1550925D01*
X1553425Y1165173D01*
X1560425D01*
X1562425Y1163173D01*
Y1141800D01*
G37*
G36*
G01X1565612Y1098288D02*
X1565000Y1097675D01*
X1548032D01*
X1547440Y1098267D01*
Y1108542D01*
X1547573Y1108675D01*
X1564800D01*
X1565612Y1107863D01*
Y1098288D01*
G37*
G36*
G01X1560511Y1174466D02*
X1552632D01*
X1542925Y1184173D01*
X1532925D01*
X1531925Y1185173D01*
Y1186673D01*
X1532925Y1187673D01*
X1557890D01*
X1561394Y1184169D01*
Y1175349D01*
X1560511Y1174466D01*
G37*
G36*
G01X1549925Y1141673D02*
X1545425D01*
X1544425Y1142673D01*
Y1152673D01*
X1542925Y1154173D01*
X1532925D01*
X1531925Y1155173D01*
Y1156673D01*
X1532925Y1157673D01*
X1545925D01*
X1550925Y1152673D01*
Y1142673D01*
X1549925Y1141673D01*
G37*
G36*
G01X1590601Y1191114D02*
X1584762Y1196953D01*
Y1197544D01*
X1584171D01*
X1579181Y1202534D01*
Y1218229D01*
X1574734D01*
X1574723Y1218417D01*
G03X1567035Y1231173I-16072J-992D01*
G02X1567082Y1231881I208J342D01*
G03X1582067Y1242931I-17181J38985D01*
G01X1582127Y1243000D01*
X1586348D01*
Y1221312D01*
G03X1590308Y1211025I15341J0D01*
G03X1595560Y1204684I14775J6892D01*
G01Y1175750D01*
G02X1595124Y1175352I-400J0D01*
G03X1591014Y1175467I-2997J-33620D01*
G02X1590601Y1175867I-13J400D01*
G01Y1191114D01*
G37*
G36*
G01X1574425Y198161D02*
X1573425Y199161D01*
Y217661D01*
X1574425Y218661D01*
X1583425D01*
X1584086Y218000D01*
Y198822D01*
X1583425Y198161D01*
X1574425D01*
G37*
G36*
G01X1713770Y868000D02*
X1713711Y868062D01*
G03X1662598Y883867I-39794J-38141D01*
G02X1662116Y884258I-82J391D01*
G03X1656941Y896083I-16103J-2D01*
G03X1649917Y902155I-13596J-8629D01*
G03X1647500Y903811I-10272J-12401D01*
G01Y914134D01*
G03X1649647Y934956I-11100J11666D01*
G03X1632930Y952389I-16047J1344D01*
G02X1632513Y952788I-17J400D01*
G01Y959443D01*
G03X1620175Y988587I-3420J15736D01*
G03X1605423Y985744I-4681J-15408D01*
G03X1598433Y985629I-3236J-15774D01*
G03X1591901Y984771I-1213J-16057D01*
G03X1588197Y985290I-4071J-15580D01*
G03X1582947Y990456I-13620J-8591D01*
G02X1583088Y991192I208J342D01*
G03X1596189Y1003999I-2707J15874D01*
G02X1596723Y1004297I393J-76D01*
G03X1618317Y1016924I5677J15069D01*
G03X1635137Y1027279I1742J16008D01*
G01X1663840D01*
G02X1664234Y1026809I0J-400D01*
G03X1663990Y1023551I15853J-2825D01*
G03X1675952Y993813I7432J-14285D01*
G02X1676462Y993475I113J-384D01*
G03X1692761Y978941I16299J1872D01*
G01X1697261D01*
G03X1710417Y985545I0J16406D01*
G03X1712181Y985448I1765J16009D01*
G01X1720683D01*
Y974690D01*
X1721429Y973944D01*
G02X1721146Y973261I-283J-283D01*
G01X1718313D01*
Y934249D01*
X1720288D01*
Y907000D01*
X1717372D01*
X1717313Y907087D01*
G03X1705773Y914014I-13303J-9086D01*
G02X1705484Y914634I44J398D01*
G03X1691020Y939674I-13384J8966D01*
G02X1690727Y940371I-27J399D01*
G03X1690737Y964423I-10715J12030D01*
G03X1660971Y953736I-15923J-2446D01*
G03X1668885Y940752I16085J900D01*
G03X1681093Y936328I11127J11650D01*
G02X1681385Y935630I26J-399D01*
G03X1690338Y907587I10715J-12030D01*
G02X1690626Y906967I-44J-397D01*
G03X1714117Y885456I13384J-8966D01*
G01X1714172Y885500D01*
X1718976D01*
G02X1719375Y885069I0J-400D01*
G03X1720276Y878313I16253J-1271D01*
G01X1720288Y878280D01*
Y868000D01*
X1713770D01*
G37*
G36*
G01X1588900Y1097900D02*
X1587927Y1098873D01*
Y1111000D01*
X1588927Y1112000D01*
X1603300D01*
X1604427Y1110873D01*
Y1099436D01*
X1602891Y1097900D01*
X1588900D01*
G37*
G36*
G01X1674138Y236161D02*
X1669638D01*
X1668638Y237161D01*
Y247161D01*
X1667138Y248661D01*
X1657138D01*
X1656138Y249661D01*
Y251161D01*
X1657138Y252161D01*
X1670138D01*
X1675138Y247161D01*
Y237161D01*
X1674138Y236161D01*
G37*
G36*
G01X1685638Y203661D02*
X1678138D01*
X1677138Y204661D01*
Y247161D01*
X1670638Y253661D01*
X1657138D01*
X1656138Y254661D01*
Y261161D01*
X1657138Y262161D01*
X1675138D01*
X1677638Y259661D01*
X1684638D01*
X1686638Y257661D01*
Y204661D01*
X1685638Y203661D01*
G37*
G36*
G01X1676185Y269614D02*
X1667138Y278661D01*
X1657138D01*
X1656138Y279661D01*
Y281161D01*
X1657136Y282160D01*
X1683511D01*
X1686109Y279561D01*
Y269429D01*
X1685634Y268954D01*
X1677195D01*
G03X1676228Y269599I-1719J-1530D01*
G01X1676185Y269614D01*
G37*
G36*
G01X1707638Y250161D02*
X1690138D01*
X1689138Y251161D01*
Y267161D01*
X1687332Y268967D01*
Y280078D01*
X1684049Y283361D01*
X1656805D01*
X1656138Y284028D01*
Y291161D01*
X1657138Y292161D01*
X1672638D01*
X1674638Y290161D01*
X1705138D01*
X1708638Y286661D01*
Y251161D01*
X1707638Y250161D01*
G37*
G36*
G01X1685634Y721710D02*
X1676845D01*
X1667138Y731417D01*
X1657138D01*
X1656138Y732417D01*
Y733917D01*
X1657138Y734917D01*
X1683509D01*
X1686109Y732317D01*
Y722185D01*
X1685634Y721710D01*
G37*
G36*
G01X1674138Y688917D02*
X1669638D01*
X1668638Y689917D01*
Y699917D01*
X1667138Y701417D01*
X1657138D01*
X1656138Y702417D01*
Y703917D01*
X1657138Y704917D01*
X1670138D01*
X1675138Y699917D01*
Y689917D01*
X1674138Y688917D01*
G37*
G36*
G01X1690138Y702917D02*
X1689138Y703917D01*
Y719917D01*
X1687332Y721723D01*
Y732834D01*
X1684049Y736117D01*
X1684008D01*
X1684007Y736118D01*
X1656803D01*
X1656138Y736784D01*
Y743917D01*
X1657138Y744917D01*
X1672638D01*
X1674638Y742917D01*
X1705138D01*
X1708638Y739417D01*
Y703917D01*
X1707638Y702917D01*
X1690138D01*
G37*
G36*
G01X1685638Y656417D02*
X1678138D01*
X1677138Y657417D01*
Y699917D01*
X1670638Y706417D01*
X1657138D01*
X1656138Y707417D01*
Y713917D01*
X1657138Y714917D01*
X1675138D01*
X1677638Y712417D01*
X1684638D01*
X1686638Y710417D01*
Y657417D01*
X1685638Y656417D01*
G37*
G36*
G01X1674138Y1141673D02*
X1669638D01*
X1668638Y1142673D01*
Y1152673D01*
X1667138Y1154173D01*
X1657138D01*
X1656138Y1155173D01*
Y1156673D01*
X1657138Y1157673D01*
X1670138D01*
X1675138Y1152673D01*
Y1142673D01*
X1674138Y1141673D01*
G37*
G36*
G01X1685638Y1109173D02*
X1678138D01*
X1677138Y1110173D01*
Y1152673D01*
X1670638Y1159173D01*
X1657138D01*
X1656138Y1160173D01*
Y1166673D01*
X1657138Y1167673D01*
X1675138D01*
X1677638Y1165173D01*
X1684638D01*
X1686638Y1163173D01*
Y1110173D01*
X1685638Y1109173D01*
G37*
G36*
G01X1670655Y1180656D02*
X1670666Y1180751D01*
G03X1668125Y1183292I-2288J253D01*
G01X1668030Y1183281D01*
X1667138Y1184173D01*
X1657138D01*
X1656138Y1185173D01*
Y1186673D01*
X1657138Y1187673D01*
X1683509D01*
X1686109Y1185073D01*
Y1174941D01*
X1685634Y1174466D01*
X1676845D01*
X1670655Y1180656D01*
G37*
G36*
G01X1690138Y1155673D02*
X1689138Y1156673D01*
Y1172673D01*
X1687332Y1174479D01*
Y1185590D01*
X1684049Y1188873D01*
X1684008D01*
X1684007Y1188874D01*
X1656804D01*
X1656138Y1189540D01*
Y1196673D01*
X1657138Y1197673D01*
X1672638D01*
X1674638Y1195673D01*
X1705138D01*
X1708638Y1192173D01*
Y1156673D01*
X1707638Y1155673D01*
X1690138D01*
G37*
G36*
G01X1698638Y198161D02*
X1697638Y199161D01*
Y217661D01*
X1698638Y218661D01*
X1707638D01*
X1708298Y218000D01*
Y198822D01*
X1707638Y198161D01*
X1698638D01*
G37*
G36*
G01X1690138Y222161D02*
X1688138Y224161D01*
Y237661D01*
X1689138Y238661D01*
X1702138D01*
X1703138Y237661D01*
Y229661D01*
X1703638Y229161D01*
X1705138D01*
X1705546Y228753D01*
X1705540Y228663D01*
G03X1705536Y228561I1598J-114D01*
G01Y226961D01*
G03X1705547Y226776I1602J2D01*
G01X1705548Y226765D01*
Y224557D01*
X1705547Y224546D01*
G03X1705536Y224361I1591J-187D01*
G01Y222961D01*
G03X1705558Y222699I1602J3D01*
G01X1705575Y222598D01*
X1705138Y222161D01*
X1690138D01*
G37*
G36*
G01X1689128Y673297D02*
X1688138Y674287D01*
Y690417D01*
X1689138Y691417D01*
X1702138D01*
X1703138Y690417D01*
Y682417D01*
X1703638Y681917D01*
X1705138D01*
X1705546Y681509D01*
X1705540Y681419D01*
G03X1705536Y681317I1598J-114D01*
G01Y679717D01*
G03X1705547Y679532I1602J2D01*
G01X1705548Y679521D01*
Y677313D01*
X1705547Y677302D01*
G03X1705536Y677117I1591J-187D01*
G01Y675717D01*
G03X1705627Y675187I1602J2D01*
G01X1705638Y675155D01*
Y674894D01*
X1704041Y673297D01*
X1689128D01*
G37*
G36*
G01X1698638Y650917D02*
X1697638Y651917D01*
Y670417D01*
X1698638Y671417D01*
X1707638D01*
X1707714Y671342D01*
Y650992D01*
X1707638Y650917D01*
X1698638D01*
G37*
G36*
G01X1677763Y768523D02*
X1677743Y768700D01*
G03X1676044Y774272I-15998J-1833D01*
G02X1676382Y774856I355J184D01*
G03X1722939Y804719I-2465J55065D01*
G01X1722995Y804828D01*
X1724589D01*
X1733122Y796295D01*
X1736660D01*
Y770469D01*
X1734646Y768455D01*
Y745762D01*
X1743694Y736714D01*
Y732706D01*
X1743494D01*
Y724810D01*
G03X1740218Y716947I11965J-9599D01*
G03X1740107Y705673I15241J-5788D01*
G01X1740119Y705640D01*
Y703354D01*
G03X1744612Y692507I15340J0D01*
G01X1747686Y689433D01*
Y656576D01*
X1738174D01*
G03X1725393Y663004I-12824J-9578D01*
G01Y674252D01*
G03X1724394Y679697I-15340J0D01*
G01Y725173D01*
X1723639D01*
Y745631D01*
X1711352Y757918D01*
X1703394D01*
Y765473D01*
X1695069D01*
G03X1685638Y768523I-9431J-13056D01*
G01X1677763D01*
G37*
G36*
G01X1740644Y1084754D02*
Y1072254D01*
G03X1758006Y1056305I16006J0D01*
G02X1758440Y1055907I34J-398D01*
G01Y1035627D01*
G02X1758035Y1035227I-400J0D01*
G03X1757863Y1035228I-176J-15502D01*
G01X1743263D01*
G03X1733099Y1031431I0J-15502D01*
G01X1727857D01*
Y1026021D01*
X1727818Y1025968D01*
G03X1726834Y1024470I12443J-9246D01*
G03X1711126Y1020762I-4653J-15416D01*
G03X1706659Y1017794I6554J-14709D01*
G03X1704508Y1019066I-9402J-13445D01*
G03X1702200Y1022351I-14227J-7543D01*
G02X1702236Y1022924I296J269D01*
G03X1701186Y1048227I-10465J12239D01*
G02X1701255Y1048916I234J325D01*
G03X1708481Y1055367I-6617J14684D01*
G01X1710744D01*
Y1065073D01*
X1710746Y1065088D01*
G03X1710941Y1067567I-16108J2514D01*
G01Y1067767D01*
X1715244D01*
Y1076667D01*
X1722144D01*
Y1090343D01*
G03X1724913Y1096056I-13005J9831D01*
G03X1725937Y1100546I-14275J5617D01*
G02X1726503Y1100880I399J-29D01*
G03X1744477Y1103964I6743J14623D01*
G01X1744535Y1104021D01*
X1746040D01*
X1746100Y1103940D01*
G03X1747628Y1102158I12956J9563D01*
G01X1747686Y1102100D01*
Y1098014D01*
G03X1740644Y1084754I8963J-13260D01*
G37*
G36*
G01X1690138Y1127673D02*
X1688138Y1129673D01*
Y1143173D01*
X1689138Y1144173D01*
X1702138D01*
X1703138Y1143173D01*
Y1135173D01*
X1703638Y1134673D01*
X1705138D01*
X1705546Y1134265D01*
X1705540Y1134175D01*
G03X1705536Y1134073I1598J-114D01*
G01Y1132473D01*
G03X1705547Y1132288I1602J2D01*
G01X1705548Y1132277D01*
Y1130069D01*
X1705547Y1130058D01*
G03X1705536Y1129873I1591J-187D01*
G01Y1128473D01*
G03X1705558Y1128211I1602J3D01*
G01X1705575Y1128110D01*
X1705138Y1127673D01*
X1690138D01*
G37*
G36*
G01X1698638Y1103673D02*
X1697638Y1104673D01*
Y1123173D01*
X1698638Y1124173D01*
X1707638D01*
X1708298Y1123512D01*
Y1104334D01*
X1707638Y1103673D01*
X1698638D01*
G37*
G36*
G01X1750766Y975125D02*
X1749653Y976238D01*
Y991553D01*
X1751000Y992900D01*
Y997896D01*
G03X1752365Y1000089I-1137J2229D01*
G01X1752368Y1000286D01*
X1763257D01*
X1764000Y999543D01*
Y982026D01*
X1763942D01*
Y975768D01*
X1763300Y975125D01*
X1750766D01*
G37*
G36*
G01X1747042Y976748D02*
X1739840D01*
X1735684Y980904D01*
Y990039D01*
X1736476Y990831D01*
X1747023D01*
X1747452Y990402D01*
Y977158D01*
X1747042Y976748D01*
G37*
G36*
G01X1748463Y1009725D02*
X1746463Y1011725D01*
Y1016525D01*
X1747063Y1017125D01*
X1756363D01*
X1758063Y1015425D01*
Y1013625D01*
X1759763Y1011925D01*
Y1010125D01*
X1759363Y1009725D01*
X1755692D01*
X1755653Y1009742D01*
G03X1755000Y1009882I-655J-1462D01*
G01X1753600D01*
G03X1752947Y1009742I2J-1602D01*
G01X1752908Y1009725D01*
X1751425D01*
X1751393Y1009736D01*
G03X1750863Y1009826I-529J-1511D01*
G01X1749463D01*
G03X1748933Y1009736I-1J-1601D01*
G01X1748901Y1009725D01*
X1748463D01*
G37*
G36*
G01X1798350Y688917D02*
X1793850D01*
X1792850Y689917D01*
Y699917D01*
X1791350Y701417D01*
X1781350D01*
X1780350Y702417D01*
Y703917D01*
X1781350Y704917D01*
X1794350D01*
X1799350Y699917D01*
Y689917D01*
X1798350Y688917D01*
G37*
G36*
G01X1809850Y656417D02*
X1802350D01*
X1801350Y657417D01*
Y699917D01*
X1794850Y706417D01*
X1781350D01*
X1780350Y707417D01*
Y713917D01*
X1781350Y714917D01*
X1799350D01*
X1801850Y712417D01*
X1808850D01*
X1810850Y710417D01*
Y657417D01*
X1809850Y656417D01*
G37*
G36*
G01X1814350Y674917D02*
X1812350Y676917D01*
Y690417D01*
X1813350Y691417D01*
X1826350D01*
X1827350Y690417D01*
Y682417D01*
X1827850Y681917D01*
X1829350D01*
X1829758Y681509D01*
X1829752Y681419D01*
G03X1829748Y681317I1598J-114D01*
G01Y679717D01*
G03X1829759Y679532I1602J2D01*
G01X1829760Y679521D01*
Y677313D01*
X1829759Y677302D01*
G03X1829748Y677117I1591J-187D01*
G01Y675717D01*
G03X1829770Y675455I1602J3D01*
G01X1829787Y675354D01*
X1829350Y674917D01*
X1814350D01*
G37*
G36*
G01X1801057Y721710D02*
X1791350Y731417D01*
X1781350D01*
X1780350Y732417D01*
Y733917D01*
X1781348Y734916D01*
X1807723D01*
X1810321Y732317D01*
Y722185D01*
X1809846Y721710D01*
X1801057D01*
G37*
G36*
G01X1814350Y702917D02*
X1813350Y703917D01*
Y716089D01*
G03Y718757I-1876J1334D01*
G01Y719917D01*
X1811544Y721723D01*
Y732834D01*
X1808261Y736117D01*
X1781017D01*
X1780350Y736784D01*
Y743917D01*
X1781350Y744917D01*
X1796850D01*
X1798850Y742917D01*
X1829350D01*
X1832850Y739417D01*
Y703917D01*
X1831850Y702917D01*
X1814350D01*
G37*
G36*
G01X1801956Y768700D02*
X1801934Y768875D01*
G03X1799876Y774967I-15978J-2004D01*
G02X1800200Y775567I346J201D01*
G03X1835287Y797624I-2267J42543D01*
G02X1835949Y797682I350J-193D01*
G03X1841408Y793322I12542J10105D01*
G03X1860033Y785284I14269J7465D01*
G01X1882653D01*
Y768374D01*
G03X1877025Y765423I4517J-15457D01*
G01X1870463D01*
Y759924D01*
X1852539Y742000D01*
X1847851D01*
Y745631D01*
X1835564Y757918D01*
X1827724D01*
Y765650D01*
X1819399D01*
G03X1809968Y768700I-9431J-13056D01*
G01X1801956D01*
G37*
G36*
G01X1809850Y1109173D02*
X1799572D01*
X1799199Y1109546D01*
Y1123989D01*
X1801350Y1126140D01*
Y1152673D01*
X1794850Y1159173D01*
X1781350D01*
X1780350Y1160173D01*
Y1166673D01*
X1781350Y1167673D01*
X1799350D01*
X1801850Y1165173D01*
X1808850D01*
X1810850Y1163173D01*
Y1110173D01*
X1809850Y1109173D01*
G37*
G36*
G01X1814350Y1127673D02*
X1812350Y1129673D01*
Y1143173D01*
X1813350Y1144173D01*
X1826350D01*
X1827350Y1143173D01*
Y1135173D01*
X1827850Y1134673D01*
X1829350D01*
X1829360Y1134662D01*
Y1134169D01*
X1829359Y1134158D01*
G03X1829348Y1133973I1591J-187D01*
G01Y1132373D01*
G03X1829359Y1132188I1602J2D01*
G01X1829360Y1132177D01*
Y1129869D01*
X1829359Y1129858D01*
G03X1829348Y1129673I1591J-187D01*
G01Y1128273D01*
G03X1829357Y1128113I1601J10D01*
G02X1828959Y1127673I-398J-40D01*
G01X1814350D01*
G37*
G36*
G01X1809846Y1174466D02*
X1801057D01*
X1791350Y1184173D01*
X1781350D01*
X1780350Y1185173D01*
Y1186673D01*
X1781350Y1187673D01*
X1807721D01*
X1810321Y1185073D01*
Y1174941D01*
X1809846Y1174466D01*
G37*
G36*
G01X1798350Y1141673D02*
X1793850D01*
X1792850Y1142673D01*
Y1152673D01*
X1791350Y1154173D01*
X1781350D01*
X1780350Y1155173D01*
Y1156673D01*
X1781350Y1157673D01*
X1794350D01*
X1799350Y1152673D01*
Y1142673D01*
X1798350Y1141673D01*
G37*
G36*
G01X1814350Y1155673D02*
X1813350Y1156673D01*
Y1172673D01*
X1811544Y1174479D01*
Y1185590D01*
X1808261Y1188873D01*
X1808220D01*
X1808219Y1188874D01*
X1781016D01*
X1780350Y1189540D01*
Y1196673D01*
X1781350Y1197673D01*
X1796850D01*
X1798850Y1195673D01*
X1829350D01*
X1832850Y1192173D01*
Y1156673D01*
X1831850Y1155673D01*
X1814350D01*
G37*
G36*
G01X1859669Y693917D02*
X1840169D01*
X1839169Y694917D01*
Y701417D01*
X1840169Y702417D01*
X1845310D01*
X1847077Y704184D01*
Y715323D01*
X1876671Y744917D01*
X1914669D01*
X1915169Y744417D01*
Y737417D01*
X1914669Y736917D01*
X1891169D01*
X1888669Y734417D01*
X1882169D01*
X1863019Y715267D01*
Y715205D01*
X1860669Y712855D01*
Y694917D01*
X1859669Y693917D01*
G37*
G36*
G01X1847669Y665917D02*
X1843669Y669917D01*
X1841169D01*
X1839669Y671417D01*
Y681417D01*
X1840669Y682417D01*
X1853669D01*
X1854669Y681417D01*
Y673476D01*
X1851110Y669917D01*
X1850669D01*
X1850339Y669587D01*
X1850319Y669575D01*
G03X1849800Y669048I851J-1357D01*
G01X1849669Y668917D01*
Y668779D01*
X1849658Y668747D01*
G03X1849568Y668217I1511J-529D01*
G01Y666617D01*
G03X1849580Y666421I1601J0D01*
G01Y666328D01*
X1849169Y665917D01*
X1847669D01*
G37*
G36*
G01X1831850Y650917D02*
X1822850D01*
X1821850Y651917D01*
Y670417D01*
X1822850Y671417D01*
X1831850D01*
X1832850Y670417D01*
Y651917D01*
X1831850Y650917D01*
G37*
G36*
G01X1849406Y1110900D02*
X1847638Y1112668D01*
Y1116883D01*
X1843021Y1121500D01*
X1840369D01*
X1839269Y1122600D01*
Y1131573D01*
X1840269Y1132573D01*
X1854761D01*
X1856227Y1131107D01*
Y1129716D01*
X1855826D01*
Y1120812D01*
X1855938D01*
Y1116604D01*
X1856113Y1116428D01*
G03X1856116Y1116398I1595J144D01*
G01Y1114263D01*
X1852753Y1110900D01*
X1849406D01*
G37*
G36*
G01X1829885Y1103673D02*
X1819899D01*
X1819199Y1104373D01*
Y1123450D01*
X1819922Y1124173D01*
X1829741D01*
X1830677Y1123237D01*
Y1104465D01*
X1829885Y1103673D01*
G37*
G36*
G01X1842101Y1135908D02*
X1841440Y1136570D01*
Y1147236D01*
X1842264Y1148060D01*
X1859379D01*
X1859982Y1148664D01*
X1868120D01*
X1869322Y1149866D01*
X1869389Y1149875D01*
G03X1871100Y1151586I-272J1983D01*
G01X1871109Y1151653D01*
X1871234Y1151778D01*
Y1157926D01*
X1868328Y1160833D01*
Y1184832D01*
X1881169Y1197673D01*
X1914669D01*
X1915169Y1197173D01*
Y1190173D01*
X1914669Y1189673D01*
X1891169D01*
X1888669Y1187173D01*
X1882169D01*
X1879865Y1184869D01*
Y1184393D01*
G03Y1180353I1104J-2020D01*
G01Y1148158D01*
X1873907Y1142200D01*
X1863067D01*
X1863048Y1142182D01*
X1862040D01*
Y1141174D01*
X1856775Y1135908D01*
X1842101D01*
G37*
G36*
G01X1889700Y688900D02*
X1882469D01*
X1881669Y689700D01*
Y694917D01*
X1882169Y695417D01*
X1887169D01*
X1897169Y705417D01*
X1914669D01*
X1915169Y704917D01*
Y701917D01*
X1914669Y701417D01*
X1902217D01*
X1889700Y688900D01*
G37*
G36*
G01X1869169Y675917D02*
X1868169Y676917D01*
Y685917D01*
X1869169Y686917D01*
Y694917D01*
X1871499Y697247D01*
X1871519Y697259D01*
G03X1872038Y697786I-851J1357D01*
G01X1872169Y697917D01*
Y698055D01*
X1872180Y698087D01*
G03X1872270Y698617I-1511J529D01*
G01Y701018D01*
X1873669Y702417D01*
X1875169D01*
X1887669Y714917D01*
X1914669D01*
X1915169Y714417D01*
Y707417D01*
X1914669Y706917D01*
X1894669D01*
X1887169Y699417D01*
X1883669D01*
X1880169Y695917D01*
Y685917D01*
X1882669Y683417D01*
Y676917D01*
X1881669Y675917D01*
X1869169D01*
G37*
G36*
G01X1863724Y651376D02*
X1863169Y651931D01*
Y662917D01*
X1864169Y663917D01*
X1882669D01*
X1883160Y663426D01*
Y651460D01*
X1883077Y651376D01*
X1863724D01*
G37*
G36*
G01X1863955Y702924D02*
X1863276Y703603D01*
Y712731D01*
X1876545Y726000D01*
X1889752D01*
X1889917Y726166D01*
X1889920D01*
Y726168D01*
X1899169Y735417D01*
X1914669D01*
X1915169Y734917D01*
Y731917D01*
X1914669Y731417D01*
X1901669D01*
X1891252Y721000D01*
X1884500D01*
X1871891Y708391D01*
Y703896D01*
X1870919Y702924D01*
X1863955D01*
G37*
G36*
G01X1882644Y1128835D02*
X1881675Y1129804D01*
Y1133845D01*
X1882285Y1134455D01*
X1888875D01*
X1891100Y1136680D01*
Y1146800D01*
X1902473Y1158173D01*
X1914669D01*
X1915169Y1157673D01*
Y1154673D01*
X1914669Y1154173D01*
X1904373D01*
X1901799Y1151599D01*
G03X1901201Y1151001I1301J-1899D01*
G01X1898700Y1148500D01*
Y1140300D01*
X1898622Y1140222D01*
Y1137142D01*
X1890315Y1128835D01*
X1882644D01*
G37*
G36*
G01X1868560Y1114226D02*
X1868230Y1114556D01*
Y1120968D01*
X1870898Y1123635D01*
Y1129066D01*
X1872073Y1130241D01*
X1872155Y1130242D01*
G03X1873750Y1131843I-6J1601D01*
G01Y1134443D01*
G03X1873617Y1135082I-1602J0D01*
G01X1873600Y1135120D01*
Y1140925D01*
X1873674Y1140998D01*
X1874405D01*
X1881066Y1147660D01*
Y1148392D01*
X1887974Y1155298D01*
X1888498D01*
X1888905Y1155706D01*
X1889986D01*
Y1156786D01*
X1890412Y1157213D01*
Y1157738D01*
X1891252Y1158577D01*
Y1165149D01*
X1893776Y1167673D01*
X1914669D01*
X1915169Y1167173D01*
Y1160173D01*
X1914669Y1159673D01*
X1901673D01*
X1889700Y1147700D01*
Y1142400D01*
X1887600Y1140300D01*
X1881800D01*
X1880171Y1138671D01*
Y1130206D01*
X1880474Y1129904D01*
Y1129306D01*
X1881102Y1128678D01*
Y1127972D01*
X1881808D01*
X1882146Y1127634D01*
X1882448D01*
Y1114304D01*
X1882370Y1114226D01*
X1868560D01*
G37*
G36*
G01X1870361Y1090348D02*
X1870359Y1090350D01*
X1863987D01*
X1863518Y1090819D01*
Y1098419D01*
X1863516Y1098421D01*
Y1100879D01*
X1863985Y1101348D01*
X1882485D01*
X1883412Y1100420D01*
Y1091276D01*
X1882485Y1090348D01*
X1870361D01*
G37*
G36*
G01X1882273Y1156500D02*
X1881066Y1157706D01*
Y1177072D01*
X1882750Y1178756D01*
X1889752D01*
X1889918Y1178922D01*
X1889920D01*
Y1178924D01*
X1899169Y1188173D01*
X1914669D01*
X1915169Y1187673D01*
Y1184673D01*
X1914669Y1184173D01*
X1901669D01*
X1891252Y1173756D01*
X1885676D01*
X1884205Y1172285D01*
Y1170947D01*
G03Y1170565I2795J-191D01*
G01Y1166973D01*
X1885716Y1165462D01*
X1887611D01*
X1889211Y1163862D01*
Y1157711D01*
X1888000Y1156500D01*
X1882273D01*
G37*
%LPC*%
G75*
G36*
G01X146450Y23001D02*
G02X142062Y8000I-19187J-2530D01*
G01X72585D01*
Y23001D01*
X72569Y23038D01*
G02X69897Y35473I31073J13181D01*
G02X91352Y67656I10122J16495D01*
G02X137387Y36966I12290J-31436D01*
G02X146450Y23001I-10124J-16494D01*
G37*
G36*
G01X148744Y1351647D02*
X148761Y1351685D01*
Y1351802D01*
G02X178239I14739J-6602D01*
G01Y1351685D01*
X178256Y1351647D01*
G02X148744I-14756J-6447D01*
G37*
G36*
G01X296860Y1319015D02*
G02X283700Y1312194I-13160J9285D01*
G01X279900D01*
G02X271814Y1342229I0J16106D01*
G02X270112Y1351578I14286J7430D01*
G01X270113Y1351590D01*
Y1351802D01*
X270093D01*
G02X301379Y1354892I16007J-2143D01*
G02X305745Y1352502I-5479J-15192D01*
G01X306660Y1351680D01*
G02X311923Y1338092I-10760J-11981D01*
G02X296860Y1319015I-15823J-2992D01*
G37*
G36*
G01X330679Y986876D02*
G03X330864Y987446I-159J367D01*
G02X351157Y980861I13873J8191D01*
G03X350972Y980291I159J-367D01*
G02X337635Y955999I-13872J-8191D01*
G01Y942841D01*
X337804Y942814D01*
G02X321490Y918605I-2504J-15914D01*
G02X300327Y938727I-5891J14995D01*
G02X299984Y940045I15599J4763D01*
G01X299215D01*
Y973465D01*
X305300D01*
G02X318425Y977270I10625J-12110D01*
G02X321899Y977436I2501J-15915D01*
G02X330679Y986876I15201J-5335D01*
G37*
G36*
G01X636305Y8000D02*
G02X621077Y35473I18517J28220D01*
G02X642532Y67656I10124J16494D01*
G02X645680Y68711I12286J-31437D01*
G02X688567Y36967I9142J-32491D01*
G02X697631Y23001I-10123J-16494D01*
G01X697654Y22826D01*
X697655D01*
G02X697633Y17940I-19211J-2357D01*
G01X697631Y17927D01*
Y8125D01*
X697506Y8000D01*
X636305D01*
G37*
G36*
G01X1243238Y23038D02*
G02X1240566Y35475I31073J13181D01*
G02X1262022Y67656I10123J16494D01*
G02X1308056Y36967I12289J-31436D01*
G02X1317097Y23173I-10123J-16495D01*
G01X1317121Y23001D01*
Y8000D01*
X1243254D01*
Y23001D01*
X1243238Y23038D01*
G37*
G36*
G01X930978Y995020D02*
Y994220D01*
X930909Y993863D01*
Y993063D01*
X930109D01*
Y993863D01*
X930178Y994220D01*
Y995020D01*
X930978D01*
G37*
G36*
G01X1926843Y8000D02*
X1903030D01*
G02X1886340I-8345J13654D01*
G01X1794435D01*
Y23001D01*
X1794419Y23038D01*
G02X1791747Y35475I31073J13181D01*
G02X1808130Y70282I10123J16494D01*
G03X1808634Y70801I130J378D01*
G02X1842183Y66073I18066J6799D01*
G03X1842305Y65487I321J-239D01*
G02X1859237Y36967I-16813J-29268D01*
G02X1865577Y30645I-10125J-16493D01*
G03X1866299Y30733I341J210D01*
G02X1911842Y46023I28386J-9079D01*
G01X1926843D01*
Y8000D01*
G37*
G36*
G01X1379911Y1346212D02*
G03X1380304Y1345633I357J-181D01*
G02X1376981Y1314235I1496J-16033D01*
G02X1371261Y1314083I-3281J15765D01*
G02X1356605Y1339609I-1661J16017D01*
G03X1356506Y1340176I-323J236D01*
G02X1349538Y1351802I9046J13323D01*
G01X1349519Y1351981D01*
X1349513D01*
G02X1356465Y1366803I16038J1519D01*
G01X1374637D01*
G02X1381571Y1351802I-9086J-13303D01*
G01X1381565D01*
X1381544Y1351625D01*
G02X1379911Y1346212I-15994J1872D01*
G37*
G36*
G01X1514647Y1351739D02*
G02X1508488Y1327744I-13047J-9439D01*
G02X1479335Y1340939I-13826J8255D01*
G02X1475562Y1351598I12327J10361D01*
G01Y1351802D01*
X1475560D01*
G02X1487282Y1366803I16102J-502D01*
G01X1496042D01*
G02X1506464Y1357658I-4380J-15503D01*
G02X1514609Y1351802I-4864J-15358D01*
G01Y1351791D01*
X1514647Y1351739D01*
G37*
G36*
G01X1911827Y1327786D02*
G02X1889856Y1351802I-3327J19014D01*
G01Y1366803D01*
X1926843D01*
Y1327789D01*
X1911844D01*
X1911827Y1327786D01*
G37*
G36*
G01X1827520Y1351744D02*
X1827540Y1351786D01*
Y1351802D01*
G02X1856460I14460J-7102D01*
G01Y1351786D01*
X1856480Y1351744D01*
G02X1827520I-14480J-7044D01*
G37*
G36*
G01X1724645Y1351751D02*
X1724654Y1351780D01*
Y1351802D01*
G02X1755346I15346J-4902D01*
G01Y1351780D01*
X1755355Y1351751D01*
G02X1724645I-15355J-4851D01*
G37*
G36*
G01X1608615Y1351744D02*
X1608618Y1351761D01*
Y1351802D01*
G02X1640382I15882J-2702D01*
G01Y1351761D01*
X1640385Y1351744D01*
G02X1608615I-15885J-2644D01*
G37*
G36*
G01X1224981Y1351665D02*
X1224935Y1351802D01*
X1224928D01*
G02X1227216Y1366133I15348J4898D01*
G01X1227254Y1366185D01*
Y1366803D01*
X1252824D01*
G02X1255624Y1351802I-12548J-10104D01*
G01X1255617D01*
X1255571Y1351665D01*
G02X1224981I-15295J5035D01*
G37*
G36*
G01X1758006Y150793D02*
G02X1740644Y166742I-1356J15949D01*
G01Y179242D01*
G02X1747686Y192502I16005J0D01*
G01Y207670D01*
G02X1745691Y223797I12800J9770D01*
G03X1745323Y224355I-368J158D01*
G01X1734044D01*
Y230479D01*
G02X1730542Y241763I12556J10082D01*
G02X1731044Y249409I15858J2798D01*
G01Y272767D01*
X1733444D01*
G02X1734913Y274981I14107J-7766D01*
G02X1757234Y285847I15987J-4481D01*
G01X1757271Y285832D01*
X1765349D01*
Y290575D01*
X1765299Y290631D01*
G02X1762959Y294011I13245J11670D01*
G01X1758440D01*
Y334217D01*
X1767858D01*
G03X1768138Y334903I0J400D01*
G02X1757058Y353344I29795J30451D01*
G03X1756274Y353231I-384J-112D01*
G01Y352073D01*
X1751098D01*
X1741285Y342260D01*
X1723053D01*
X1708279Y357034D01*
Y431180D01*
G02Y442220I15340J5520D01*
G01Y470027D01*
X1700610Y477696D01*
G02X1696117Y488543I10847J10847D01*
G01Y489347D01*
X1690326D01*
Y523859D01*
X1691517D01*
Y529240D01*
X1696856D01*
G02X1703734Y532810I10640J-12088D01*
G02X1717226Y533346I7326J-14340D01*
G02X1737745Y529271I7875J-14046D01*
G01X1741266D01*
Y525930D01*
G02X1742893Y524447I-10144J-12763D01*
G02X1745145Y523868I-2874J-15847D01*
G01X1745176Y523858D01*
X1746697D01*
Y523257D01*
X1746813Y523203D01*
G02X1750866Y520506I-6794J-14603D01*
G01X1756725D01*
Y481494D01*
X1754908D01*
Y459020D01*
G02Y447980I-15340J-5520D01*
G01Y416392D01*
X1757400Y413900D01*
X1763397D01*
X1763457Y413982D01*
G02X1822533Y423737I34476J-25028D01*
G01X1822585Y423700D01*
X1826800D01*
X1829492Y426392D01*
Y440880D01*
G02Y451920I15340J5520D01*
G01Y478814D01*
X1824445Y483861D01*
G02X1820873Y489474I10848J10846D01*
G01X1814161D01*
Y523986D01*
X1815352D01*
Y529367D01*
X1820691D01*
G02X1827569Y532937I10640J-12088D01*
G02X1843102Y532453I7327J-14340D01*
G02X1843314Y532484I2436J-15918D01*
G02X1859824Y529398I5731J-15049D01*
G01X1865101D01*
Y525736D01*
G02X1866395Y524560I-10302J-12635D01*
G02X1868968Y523994I-2162J-15960D01*
G01X1868997Y523985D01*
X1870532D01*
Y523424D01*
X1870652Y523371D01*
G02X1875079Y520506I-6419J-14772D01*
G01X1880938D01*
Y501504D01*
G03X1881515Y501145I400J0D01*
G02X1911842Y498777I13168J-26736D01*
G01X1926843D01*
Y450041D01*
X1911842D01*
G02X1879722Y448634I-17158J24368D01*
G03X1879121Y448288I-201J-346D01*
G01Y434720D01*
G02Y423680I-15340J-5520D01*
G01Y391235D01*
X1880487D01*
Y352073D01*
X1875120D01*
G02X1873779Y350541I-12188J9315D01*
G01X1869991Y346753D01*
G02X1859144Y342260I-10847J10847D01*
G01X1853620D01*
G02X1842773Y346753I0J15340D01*
G01X1838618Y350908D01*
G03X1837960Y350762I-282J-283D01*
G02X1800200Y322811I-40027J14592D01*
G03X1799876Y322211I22J-399D01*
G02X1801955Y315944I-13920J-8096D01*
G01X1801975Y315767D01*
X1809850D01*
G02X1819281Y312717I0J-16106D01*
G01X1827606D01*
Y305162D01*
X1835564D01*
X1847851Y292875D01*
Y288932D01*
G03X1848534Y288649I400J0D01*
G01X1867047Y307162D01*
X1869307D01*
X1869366Y307225D01*
G02X1870463Y308284I11720J-11043D01*
G01Y312667D01*
X1882653D01*
Y334217D01*
X1926843D01*
Y121767D01*
X1882653D01*
Y150395D01*
G03X1882219Y150793I-400J0D01*
G02X1872581Y153045I-1356J15949D01*
G02X1871623Y151705I-13562J8683D01*
G01Y145669D01*
X1860246D01*
X1860238Y145668D01*
G02X1857796I-1221J16057D01*
G01X1857788Y145669D01*
X1855375D01*
G02X1826667I-14354J7299D01*
G01X1824911D01*
Y149219D01*
G03X1824497Y149619I-400J0D01*
G02X1821094Y149852I-594J16292D01*
G01X1821077Y149855D01*
X1818618D01*
X1818565Y149815D01*
G02X1808850Y146555I-9715J12846D01*
G01X1805384D01*
Y145836D01*
X1802069D01*
G03X1801679Y145350I0J-400D01*
G02X1798646Y131957I-15723J-3479D01*
G01Y121767D01*
X1758440D01*
Y150395D01*
G03X1758006Y150793I-400J0D01*
G37*
G54D123*
X63128Y89671D03*
X1861177Y91072D03*
G54D127*
X929331Y710629D03*
X1097441D03*
X1115157Y714567D03*
X1123031Y718504D03*
X1097441Y32284D03*
Y24410D03*
X1105315Y28347D03*
Y12599D03*
X1123031Y32284D03*
Y24410D03*
X1115157Y28347D03*
G54D126*
X571400Y1000100D03*
G54D125*
X291601Y418503D03*
X1873500Y1329000D03*
G54D124*
X93737Y288661D03*
X97137D03*
X55437Y215861D03*
X93737Y741417D03*
X97137D03*
X55437Y668617D03*
Y1121373D03*
X93737Y1194173D03*
X97137D03*
X81537Y245461D03*
X84937D03*
Y248861D03*
X81537Y698217D03*
X84937D03*
Y701617D03*
X107263Y1000025D03*
X109463D03*
X111400Y1000080D03*
X113600D03*
X115895Y1000167D03*
X106663Y1002225D03*
X81537Y1150973D03*
X84937D03*
Y1154373D03*
X217949Y288661D03*
X221349D03*
X205749Y245461D03*
X209149D03*
Y248861D03*
X179649Y215861D03*
X173963Y588025D03*
X176163D03*
X178100Y588080D03*
X180300D03*
X182595Y588167D03*
X173363Y589925D03*
Y592125D03*
X217949Y741417D03*
X221349D03*
X205749Y698217D03*
X209149D03*
Y701617D03*
X185599Y668689D03*
X185399Y670489D03*
Y672889D03*
X205749Y1150973D03*
X209149D03*
Y1154373D03*
X185649Y1120673D03*
X185449Y1122473D03*
Y1124873D03*
X217949Y1194173D03*
X221349D03*
X316612Y108531D03*
X319012D03*
X311612Y110531D03*
X315012D03*
X342162Y288661D03*
X345562D03*
X303862Y215861D03*
X342162Y741417D03*
X345562D03*
X303862Y668617D03*
Y1121373D03*
X342162Y1194173D03*
X345562D03*
X329962Y245461D03*
X333362D03*
Y248861D03*
X329962Y698217D03*
X333362D03*
Y701617D03*
X329962Y1150973D03*
X333362D03*
Y1154373D03*
X466374Y288661D03*
X469774D03*
X454174Y245461D03*
X457574D03*
Y248861D03*
X428074Y215861D03*
X466374Y741417D03*
X469774D03*
X454174Y698217D03*
X457574D03*
Y701617D03*
X428074Y668617D03*
X466374Y1194173D03*
X469774D03*
X524174Y1151073D03*
Y1154473D03*
X590587Y288661D03*
X593987D03*
X552287Y215861D03*
X543079Y560431D03*
Y562631D03*
Y565431D03*
Y567631D03*
X582579Y574331D03*
X585979D03*
X591679Y575131D03*
X593879D03*
X570440Y575165D03*
X572640D03*
X578618Y575197D03*
X580818D03*
X561079Y575331D03*
X563479D03*
X566579D03*
X568979D03*
X574579D03*
X576979D03*
X587579D03*
X589979D03*
X590587Y741417D03*
X593987D03*
X552287Y668617D03*
Y1121373D03*
X590587Y1194173D03*
X593987D03*
X578387Y245461D03*
X581787D03*
Y248861D03*
X577029Y508327D03*
Y504927D03*
X578387Y698217D03*
X581787D03*
Y701617D03*
X578387Y1150973D03*
X581787D03*
Y1154373D03*
X636113Y590455D03*
X638313D03*
X714800Y288661D03*
X718200D03*
X702600Y245461D03*
X706000D03*
Y248861D03*
X676500Y215861D03*
X695587Y589395D03*
X697987D03*
X714800Y741417D03*
X718200D03*
X702600Y698217D03*
X706000D03*
Y701617D03*
X677200Y666917D03*
X677000Y668717D03*
Y671117D03*
X702600Y1150973D03*
X706000D03*
Y1154373D03*
X682500Y1118873D03*
Y1121073D03*
X682300Y1122873D03*
Y1125273D03*
X714800Y1194173D03*
X718200D03*
X834808Y35672D03*
Y39072D03*
X825808D03*
X870077Y35534D03*
Y38934D03*
X861077Y35534D03*
Y38934D03*
X930578Y997020D03*
X877573Y806803D03*
X879773D03*
X882300Y806832D03*
X870023Y813480D03*
X868963Y845053D03*
X871363D03*
X863963Y846053D03*
X867363D03*
X890403Y855627D03*
Y857827D03*
X881300Y866168D03*
X883500D03*
X876573Y866203D03*
X878773D03*
X951400Y907200D03*
X953600D03*
X955900D03*
X913500Y907900D03*
X965000Y958200D03*
X933461Y964007D03*
X935761D03*
X937961D03*
X1003294Y977040D03*
X1005594D03*
X922700Y977400D03*
X965100Y978200D03*
X930509Y990063D03*
X942300Y1013700D03*
X944700D03*
X991794Y1014340D03*
X994194D03*
X937300Y1014700D03*
X940700D03*
X986270Y1015507D03*
X989670D03*
X992549Y1026043D03*
X1022400Y1069200D03*
X1024600D03*
X1026900D03*
X1042600D03*
X1067900D03*
X1088100D03*
X1111600Y1069300D03*
X1114100D03*
X1130000D03*
X874663Y1485965D03*
X971855Y1178253D03*
X974255D03*
X959313Y1497124D03*
X1081707Y1560543D03*
Y1562943D03*
X1029712Y-71908D03*
Y-69508D03*
X1053033Y-77447D03*
Y-75047D03*
X1030853Y-43275D03*
X1034873Y826403D03*
X1037073D03*
X1039673D03*
X1041873D03*
X1030363Y861353D03*
X1032763D03*
X1025363Y862353D03*
X1028763D03*
X1029714Y871641D03*
Y873841D03*
X1045703Y877227D03*
X1041001Y881741D03*
X1043201D03*
X1029700Y903100D03*
X1033300Y903900D03*
X1058800D03*
X1014628Y909300D03*
X1063818Y937849D03*
X1066018D03*
X1068818D03*
X1071018D03*
X1022000Y960550D03*
X1020000Y1105600D03*
X1022400D03*
X1110400Y1106400D03*
X1112800D03*
X1015300Y1106500D03*
X1018700D03*
X1067500Y1106600D03*
X1069900D03*
X1108800Y1107400D03*
X1062800Y1107500D03*
X1066200D03*
X1069055Y1118203D03*
X1071255D03*
X1037000Y1122600D03*
X1129900Y1123000D03*
X993900Y1139700D03*
X1053425Y-48450D03*
X1055825D03*
X1233692Y223925D03*
Y226325D03*
X1316455Y117551D03*
X1318855D03*
X1311299Y118625D03*
X1314699D03*
X1300200Y258661D03*
X1296800D03*
Y288161D03*
X1300200D03*
X1330700Y224761D03*
X1330500Y226561D03*
X1300200Y711417D03*
X1296800D03*
X1330700Y677517D03*
X1330500Y679317D03*
X1296800Y740917D03*
X1300200D03*
X1296800Y1164173D03*
X1300200D03*
X1330700Y1130273D03*
X1330500Y1132073D03*
X1296800Y1193673D03*
X1300200D03*
X1365028Y541211D03*
Y543411D03*
X1375043Y579519D03*
X1377443D03*
X1421013Y258661D03*
X1424413D03*
X1421013Y288161D03*
X1424413D03*
X1421013Y740917D03*
X1424413D03*
X1421013Y711417D03*
X1424413D03*
Y1164173D03*
X1421013D03*
Y1193673D03*
X1424413D03*
X1454913Y224761D03*
X1454713Y226561D03*
X1438000Y517100D03*
X1440400D03*
X1451000D03*
X1453400D03*
X1459000D03*
X1461400D03*
X1464500D03*
X1466900D03*
X1447161Y517234D03*
X1449361D03*
X1455339Y517266D03*
X1457539D03*
X1436300Y517300D03*
X1442000Y518100D03*
X1445400D03*
X1452761Y589956D03*
Y586556D03*
X1454913Y677517D03*
X1454713Y679317D03*
X1454913Y1130273D03*
X1454713Y1132073D03*
X1548625Y258661D03*
X1545225D03*
Y288161D03*
X1548625D03*
X1579125Y224761D03*
X1578925Y226561D03*
X1548625Y711417D03*
X1545225D03*
X1579125Y677517D03*
X1578925Y679317D03*
X1545225Y740917D03*
X1548625D03*
X1545225Y1193673D03*
X1548625D03*
X1545225Y1164173D03*
X1548625D03*
X1597200Y1110000D03*
X1599600D03*
X1601100Y1110100D03*
X1603300D03*
X1672838Y258661D03*
X1669438D03*
Y288161D03*
X1672838D03*
X1669438Y740917D03*
X1672838D03*
Y711417D03*
X1669438D03*
X1672838Y1164173D03*
X1669438D03*
Y1193673D03*
X1672838D03*
X1703338Y224761D03*
X1703138Y226561D03*
X1703338Y675317D03*
Y677517D03*
X1703138Y679317D03*
X1703338Y1130273D03*
X1703138Y1132073D03*
X1749063Y1012025D03*
X1751263D03*
X1753200Y1012080D03*
X1755400D03*
X1757695Y1012167D03*
X1748463Y1014225D03*
X1797050Y711417D03*
X1793650D03*
X1827550Y677517D03*
X1827350Y679317D03*
X1793768Y741094D03*
X1797168D03*
X1797050Y1164173D03*
X1793650D03*
X1827150Y1130073D03*
X1826950Y1131973D03*
X1793650Y1193673D03*
X1797050D03*
X1885469Y741417D03*
X1888869D03*
X1847169Y668617D03*
X1853906Y1114394D03*
X1853706Y1116194D03*
Y1118594D03*
X1885469Y1194173D03*
X1888869D03*
X1873269Y698217D03*
X1876669D03*
Y701617D03*
X1874748Y1131443D03*
X1878148D03*
X1874748Y1134843D03*
X1878148D03*
G54D128*
X1110236Y725590D03*
G54D129*
X1620100Y60000D03*
%LPD*%
G75*
G36*
G01X1809850Y203661D02*
X1802350D01*
X1801350Y204661D01*
Y247161D01*
X1794850Y253661D01*
X1781350D01*
X1780350Y254661D01*
Y261161D01*
X1781350Y262161D01*
X1799350D01*
X1801850Y259661D01*
X1808850D01*
X1810850Y257661D01*
Y204661D01*
X1809850Y203661D01*
G37*
G36*
G01X1798350Y236161D02*
X1793850D01*
X1792850Y237161D01*
Y247161D01*
X1791350Y248661D01*
X1781350D01*
X1780350Y249661D01*
Y251161D01*
X1781350Y252161D01*
X1794350D01*
X1799350Y247161D01*
Y237161D01*
X1798350Y236161D01*
G37*
G36*
G01X1814350Y222161D02*
X1812350Y224161D01*
Y237661D01*
X1813350Y238661D01*
X1826350D01*
X1827350Y237661D01*
Y229661D01*
X1827850Y229161D01*
X1829350D01*
X1829758Y228753D01*
X1829752Y228663D01*
G03X1829748Y228561I1598J-114D01*
G01Y226961D01*
G03X1829759Y226776I1602J2D01*
G01X1829760Y226765D01*
Y224557D01*
X1829759Y224546D01*
G03X1829748Y224361I1591J-187D01*
G01Y222961D01*
G03X1829770Y222699I1602J3D01*
G01X1829787Y222598D01*
X1829350Y222161D01*
X1814350D01*
G37*
G36*
G01X1801057Y268954D02*
X1791350Y278661D01*
X1781350D01*
X1780350Y279661D01*
Y281161D01*
X1781348Y282160D01*
X1807723D01*
X1810321Y279561D01*
Y269429D01*
X1809846Y268954D01*
X1801057D01*
G37*
G36*
G01X1831850Y250161D02*
X1814350D01*
X1813350Y251161D01*
Y267161D01*
X1811544Y268967D01*
Y280078D01*
X1808261Y283361D01*
X1781017D01*
X1780350Y284028D01*
Y291161D01*
X1781350Y292161D01*
X1796850D01*
X1798850Y290161D01*
X1829350D01*
X1832850Y286661D01*
Y251161D01*
X1831850Y250161D01*
G37*
G36*
G01X1822850Y198161D02*
X1821850Y199161D01*
Y217661D01*
X1822850Y218661D01*
X1831850D01*
X1832510Y218000D01*
Y198822D01*
X1831850Y198161D01*
X1822850D01*
G37*
G36*
G01X1859669Y241161D02*
X1840169D01*
X1839169Y242161D01*
Y248661D01*
X1840169Y249661D01*
X1848669D01*
X1850669Y251661D01*
Y269569D01*
X1873261Y292161D01*
X1914669D01*
X1915169Y291661D01*
Y284661D01*
X1914669Y284161D01*
X1891169D01*
X1888669Y281661D01*
X1878061D01*
X1865169Y268769D01*
Y250661D01*
X1860669Y246161D01*
Y242161D01*
X1859669Y241161D01*
G37*
G36*
G01X1847669Y213161D02*
X1843669Y217161D01*
X1841169D01*
X1839669Y218661D01*
Y228661D01*
X1840669Y229661D01*
X1853669D01*
X1854669Y228661D01*
Y220720D01*
X1851110Y217161D01*
X1850669D01*
X1850338Y216830D01*
G03X1849800Y216292I831J-1369D01*
G01X1849669Y216161D01*
Y216023D01*
X1849658Y215991D01*
G03X1849568Y215461I1511J-529D01*
G01Y213861D01*
G03X1849580Y213665I1601J0D01*
G01Y213572D01*
X1849169Y213161D01*
X1847669D01*
G37*
G36*
G01X1864169Y200161D02*
X1863169Y201161D01*
Y210161D01*
X1864169Y211161D01*
X1882669D01*
X1883160Y210670D01*
Y200652D01*
X1882669Y200161D01*
X1864169D01*
G37*
G36*
G01X1869169Y251161D02*
X1868669Y251661D01*
Y267169D01*
X1874744Y273244D01*
X1889752D01*
X1889917Y273410D01*
X1889920D01*
Y273412D01*
X1899169Y282661D01*
X1914669D01*
X1915169Y282161D01*
Y279161D01*
X1914669Y278661D01*
X1901669D01*
X1891252Y268244D01*
X1875944D01*
X1874500Y266800D01*
Y251700D01*
X1873961Y251161D01*
X1869169D01*
G37*
G36*
G01X1888400Y236500D02*
X1881769D01*
X1881669Y236600D01*
Y242161D01*
X1882169Y242661D01*
X1887169D01*
X1897169Y252661D01*
X1914669D01*
X1915169Y252161D01*
Y249161D01*
X1914669Y248661D01*
X1900561D01*
X1888400Y236500D01*
G37*
G36*
G01X1869169Y223161D02*
X1868169Y224161D01*
Y233161D01*
X1869169Y234161D01*
Y242161D01*
X1871499Y244491D01*
X1871519Y244503D01*
G03X1872038Y245030I-851J1357D01*
G01X1872169Y245161D01*
Y245299D01*
X1872180Y245331D01*
G03X1872270Y245861I-1511J529D01*
G01Y248262D01*
X1873669Y249661D01*
X1875169D01*
X1887669Y262161D01*
X1914669D01*
X1915169Y261661D01*
Y254661D01*
X1914669Y254161D01*
X1894669D01*
X1887169Y246661D01*
X1883669D01*
X1880169Y243161D01*
Y233161D01*
X1882669Y230661D01*
Y224161D01*
X1881669Y223161D01*
X1869169D01*
G37*
%LPC*%
G75*
G54D124*
X1797050Y258661D03*
X1793650D03*
X1827550Y224761D03*
X1827350Y226561D03*
X1793650Y288161D03*
X1797050D03*
X1885469Y288661D03*
X1888869D03*
X1847169Y215861D03*
X1873269Y245461D03*
X1876669D03*
Y248861D03*
%LPD*%
G75*
G54D100*
X1040055Y1482511D03*
X1035055D03*
X1030055D03*
X1017255D03*
X1012255D03*
X1007255D03*
X1002255D03*
X1072855D03*
X1067855D03*
X1062855D03*
X1057855D03*
X1045055D03*
X1376200Y540900D03*
X1391200D03*
X1386200D03*
X1381200D03*
G54D110*
X1426950Y571600D03*
X1419450Y567725D03*
Y575475D03*
G54D101*
X1023290Y1521346D03*
Y1553748D03*
G54D120*
G01X126709Y174092D02*
X125405D01*
X124880Y173567D01*
X124463D01*
X123963Y174067D01*
Y174992D01*
X123463Y175492D01*
X118209D01*
G01X126709Y171892D02*
X125405D01*
X124880Y172417D01*
X124463D01*
X123963Y171917D01*
Y170992D01*
X123463Y170492D01*
X118209D01*
G01X127988Y185742D02*
Y186917D01*
G03X127488Y187417I-500J0D01*
G01X124463D01*
X123963Y186917D01*
Y185992D01*
X123463Y185492D01*
X118209D01*
G01X127988Y190242D02*
Y189067D01*
G02X127488Y188567I-500J0D01*
G01X124463D01*
X123963Y189067D01*
Y189872D01*
X123343Y190492D01*
X118209D01*
G01X126709Y626848D02*
X125405D01*
X124880Y626323D01*
X124463D01*
X123963Y626823D01*
Y627748D01*
X123463Y628248D01*
X118209D01*
G01X126709Y624648D02*
X125405D01*
X124880Y625173D01*
X124463D01*
X123963Y624673D01*
Y623748D01*
X123463Y623248D01*
X118209D01*
G01X127988Y638498D02*
Y639673D01*
G03X127488Y640173I-500J0D01*
G01X124463D01*
X123963Y639673D01*
Y638748D01*
X123463Y638248D01*
X118209D01*
G01X127988Y642998D02*
Y641823D01*
G02X127488Y641323I-500J0D01*
G01X124463D01*
X123963Y641823D01*
Y642748D01*
X123463Y643248D01*
X118209D01*
G01X126709Y1079604D02*
X125405D01*
X124880Y1079079D01*
X124463D01*
X123963Y1079579D01*
Y1080504D01*
X123463Y1081004D01*
X118209D01*
G01X126709Y1077404D02*
X125405D01*
X124880Y1077929D01*
X124463D01*
X123963Y1077429D01*
Y1076504D01*
X123463Y1076004D01*
X118209D01*
G01X127988Y1091254D02*
Y1092429D01*
G03X127488Y1092929I-500J0D01*
G01X124463D01*
X123963Y1092429D01*
Y1091504D01*
X123463Y1091004D01*
X118209D01*
G01X127988Y1095754D02*
Y1094579D01*
G02X127488Y1094079I-500J0D01*
G01X124463D01*
X123963Y1094579D01*
Y1095504D01*
X123463Y1096004D01*
X118209D01*
G01X128909Y174092D02*
X130713D01*
X131124Y173681D01*
X131911D01*
X133038Y174394D01*
X139117Y183012D01*
X163907Y250212D01*
X231934Y337999D01*
X357142Y417764D01*
X371698Y427039D01*
X658122Y498160D01*
X719570Y549690D01*
X754316Y597717D01*
X772230Y678525D01*
X757801Y737006D01*
X789346Y887417D01*
X820879Y1037775D01*
X917931Y1191163D01*
X947680Y1214604D01*
X1028762Y1242574D01*
X1047414D01*
X1048014Y1243174D01*
X1049514D01*
X1050114Y1242574D01*
X1051614D01*
X1052214Y1243174D01*
X1053714D01*
X1054314Y1242574D01*
X1055814D01*
X1056414Y1243174D01*
X1057914D01*
X1058514Y1242574D01*
X1060014D01*
X1060614Y1243174D01*
X1062114D01*
X1062714Y1242574D01*
X1071925D01*
G03X1072425Y1243074I0J500D01*
G01Y1244795D01*
G03X1071925Y1245295I-500J0D01*
G01X1070750D01*
G01X128909Y171892D02*
X130713D01*
X131352Y172531D01*
X132245D01*
X133846Y173544D01*
X140144Y182472D01*
X164925Y249648D01*
X232721Y337136D01*
X266474Y358639D01*
X300229Y380143D01*
X326500Y396879D01*
X357760Y416794D01*
X372158Y425968D01*
X658658Y497107D01*
X720418Y548900D01*
X755388Y597235D01*
X764396Y637871D01*
X773412Y678539D01*
X758981Y737027D01*
X821963Y1037335D01*
X918798Y1190381D01*
X948239Y1213580D01*
X1028955Y1241424D01*
X1071925D01*
G03X1073575Y1243074I0J1650D01*
G01Y1244795D01*
G02X1074075Y1245295I500J0D01*
G01X1075250D01*
G01X128909Y626848D02*
X130913D01*
X131256Y626505D01*
X133350D01*
X134766Y626819D01*
X137149Y628337D01*
X145777Y641880D01*
X159129Y702113D01*
X159316Y702233D01*
X213596Y787442D01*
X293324Y838290D01*
X373017Y889116D01*
X558182Y926175D01*
X582774Y939975D01*
X607368Y953777D01*
X656554Y981380D01*
X761723Y1040402D01*
X908813Y1272883D01*
X1050101Y1321529D01*
X1050473Y1322291D01*
X1051891Y1322780D01*
X1052654Y1322408D01*
X1054072Y1322896D01*
X1054444Y1323659D01*
X1055862Y1324147D01*
X1056625Y1323775D01*
X1058043Y1324263D01*
X1058415Y1325026D01*
X1059833Y1325514D01*
X1060596Y1325142D01*
X1062014Y1325631D01*
X1062386Y1326393D01*
X1063805Y1326882D01*
X1064567Y1326510D01*
X1064568D01*
X1067775Y1327614D01*
X1071925D01*
G03X1072425Y1328114I0J500D01*
G01Y1329835D01*
G03X1071925Y1330335I-500J0D01*
G01X1070750D01*
G01X128909Y624648D02*
X130913D01*
X131620Y625355D01*
X133476D01*
X135213Y625740D01*
X137982Y627504D01*
X146856Y641433D01*
X160150Y701401D01*
X160151D01*
X214429Y786609D01*
X373454Y888030D01*
X558586Y925083D01*
X583337Y938972D01*
X607931Y952774D01*
X657117Y980377D01*
X762540Y1039541D01*
X909569Y1271927D01*
X1067968Y1326464D01*
X1071925D01*
G03X1073575Y1328114I0J1650D01*
G01Y1329835D01*
G02X1074075Y1330335I500J0D01*
G01X1075250D01*
G01X128909Y1079604D02*
X130513D01*
X130915Y1079202D01*
X133573D01*
X137773Y1081862D01*
X169383Y1167579D01*
X171891Y1171441D01*
X196121Y1208752D01*
X222933Y1250039D01*
X223041Y1250105D01*
Y1250104D01*
X367942Y1338306D01*
X442841Y1353299D01*
X539125Y1333781D01*
X623570Y1350683D01*
X798131Y1315348D01*
X807045Y1317133D01*
X807516Y1317839D01*
X808986Y1318133D01*
X809693Y1317662D01*
X811163Y1317957D01*
X811634Y1318663D01*
X813105Y1318957D01*
X813811Y1318487D01*
X815282Y1318781D01*
X815752Y1319488D01*
X817223Y1319782D01*
X817929Y1319311D01*
X819400Y1319606D01*
X819870Y1320312D01*
X821341Y1320606D01*
X822047Y1320136D01*
X934477Y1342644D01*
X1064436Y1412058D01*
X1071925D01*
G03X1072425Y1412558I0J500D01*
G01Y1414874D01*
G03X1071925Y1415374I-500J0D01*
G01X1070750D01*
G01X128909Y1077404D02*
X130513D01*
X131161Y1078052D01*
X133907D01*
X138718Y1081098D01*
X170418Y1167060D01*
X172856Y1170814D01*
X197086Y1208125D01*
X223755Y1249191D01*
X223757Y1249193D01*
X368367Y1337218D01*
X442840Y1352125D01*
X539124Y1332607D01*
X623569Y1349509D01*
X798130Y1314174D01*
X822272Y1319006D01*
Y1319008D01*
X934869Y1341549D01*
X1064724Y1410908D01*
X1071925D01*
G03X1073575Y1412558I0J1650D01*
G01Y1414874D01*
G02X1074075Y1415374I500J0D01*
G01X1075250D01*
G01X250921Y174092D02*
X249617D01*
X249092Y173567D01*
X248675D01*
X248175Y174067D01*
Y174992D01*
X247675Y175492D01*
X242421D01*
G01X250921Y171892D02*
X249617D01*
X249092Y172417D01*
X248675D01*
X248175Y171917D01*
Y170992D01*
X247675Y170492D01*
X242421D01*
G01X252200Y185742D02*
Y186917D01*
G03X251700Y187417I-500J0D01*
G01X248675D01*
X248175Y186917D01*
Y185992D01*
X247675Y185492D01*
X242421D01*
G01X252200Y190242D02*
Y189067D01*
G02X251700Y188567I-500J0D01*
G01X248813D01*
X248175Y189205D01*
Y189992D01*
X247675Y190492D01*
X242421D01*
G01X1070750Y1238209D02*
X1071925D01*
G02X1072425Y1237709I0J-500D01*
G01Y1235988D01*
G02X1071925Y1235488I-500J0D01*
G01X1062714D01*
X1062114Y1236088D01*
X1060614D01*
X1060014Y1235488D01*
X1058514D01*
X1057914Y1236088D01*
X1056414D01*
X1055814Y1235488D01*
X1054314D01*
X1053714Y1236088D01*
X1052214D01*
X1051614Y1235488D01*
X1050114D01*
X1049514Y1236088D01*
X1048014D01*
X1047414Y1235488D01*
X1027451D01*
X950420Y1208913D01*
X923040Y1187340D01*
X869001Y1101926D01*
X810875Y824945D01*
X833617Y732805D01*
X831895Y725934D01*
Y725933D01*
X828453Y712202D01*
X786656Y650896D01*
X727943Y528831D01*
X720716Y523918D01*
X581575Y429553D01*
X558146Y413663D01*
X550336Y408367D01*
X464236Y349973D01*
X346236Y324150D01*
X327001Y310890D01*
X288150Y251063D01*
X260384Y175742D01*
X257094Y173658D01*
X255359D01*
X254925Y174092D01*
X253121D01*
G01X1075250Y1238209D02*
X1074075D01*
G03X1073575Y1237709I0J-500D01*
G01Y1235988D01*
G02X1071925Y1234338I-1650J0D01*
G01X1027644D01*
X950979Y1207889D01*
X923907Y1186558D01*
X870085Y1101486D01*
X812055Y824966D01*
X834803Y732803D01*
X833011Y725654D01*
X829519Y711723D01*
X787654Y650315D01*
X728846Y528053D01*
X721363Y522966D01*
X582221Y428600D01*
X550982Y407415D01*
Y407414D01*
X464699Y348896D01*
X346703Y323074D01*
X327842Y310072D01*
X289185Y250545D01*
X261329Y174978D01*
X257428Y172508D01*
X255541D01*
X254925Y171892D01*
X253121D01*
G01X250921Y626848D02*
X249617D01*
X249092Y626323D01*
X248675D01*
X248175Y626823D01*
Y627748D01*
X247675Y628248D01*
X242421D01*
G01X250921Y624648D02*
X249617D01*
X249092Y625173D01*
X248675D01*
X248175Y624673D01*
Y623748D01*
X247675Y623248D01*
X242421D01*
G01X252200Y638498D02*
Y639673D01*
G03X251700Y640173I-500J0D01*
G01X248675D01*
X248175Y639673D01*
Y638748D01*
X247675Y638248D01*
X242421D01*
G01X252200Y642998D02*
Y641823D01*
G02X251700Y641323I-500J0D01*
G01X248675D01*
X248175Y641823D01*
Y642748D01*
X247675Y643248D01*
X242421D01*
G01X253121Y626848D02*
X255525D01*
X255888Y626485D01*
X258055D01*
X258750Y626639D01*
X262832Y629240D01*
X267836Y637091D01*
X284076Y710367D01*
X284078D01*
X311479Y777574D01*
X318320Y794352D01*
X341507Y851222D01*
X350570Y865448D01*
X375734Y880861D01*
X559719Y917691D01*
Y917689D01*
X765517Y1033512D01*
X901027Y1247793D01*
X900840Y1248621D01*
X901642Y1249889D01*
X902470Y1250075D01*
X903271Y1251343D01*
X903085Y1252171D01*
X903887Y1253438D01*
X904715Y1253625D01*
X905516Y1254893D01*
X905330Y1255720D01*
X906132Y1256988D01*
X906959Y1257175D01*
X907761Y1258442D01*
X907575Y1259270D01*
X908376Y1260538D01*
X909204Y1260724D01*
X913710Y1267850D01*
X990092Y1294199D01*
X990094Y1294200D01*
X990099Y1294202D01*
X1066418Y1320527D01*
X1071925D01*
G03X1072425Y1321027I0J500D01*
G01Y1322748D01*
G03X1071925Y1323248I-500J0D01*
G01X1070750D01*
G01X253121Y624648D02*
X255525D01*
X256212Y625335D01*
X258181D01*
X259197Y625560D01*
X263665Y628407D01*
X268915Y636644D01*
X285176Y710012D01*
X285181Y710023D01*
X285180D01*
X342533Y850692D01*
X351398Y864605D01*
X376161Y879773D01*
X560123Y916598D01*
Y916596D01*
X766334Y1032652D01*
X914467Y1266894D01*
X990467Y1293111D01*
X990472Y1293113D01*
X990539Y1293136D01*
X990541Y1293137D01*
X1066611Y1319377D01*
X1071925D01*
G03X1073575Y1321027I0J1650D01*
G01Y1322748D01*
G02X1074075Y1323248I500J0D01*
G01X1075250D01*
G01X250921Y1079604D02*
X249617D01*
X249092Y1079079D01*
X248675D01*
X248175Y1079579D01*
Y1080504D01*
X247675Y1081004D01*
X242421D01*
G01X250921Y1077404D02*
X249617D01*
X249092Y1077929D01*
X248675D01*
X248175Y1077429D01*
Y1076504D01*
X247675Y1076004D01*
X242421D01*
G01X253121Y1079604D02*
X255325D01*
X255718Y1079211D01*
X257468D01*
X261463Y1081742D01*
X283271Y1140879D01*
X348934Y1318946D01*
X369728Y1332101D01*
X442865Y1346740D01*
X540283Y1327256D01*
X624309Y1344087D01*
X800002Y1308522D01*
X803790Y1309280D01*
X804260Y1309986D01*
X805731Y1310281D01*
X806437Y1309810D01*
X807908Y1310104D01*
X808379Y1310811D01*
X809849Y1311105D01*
X810555Y1310634D01*
X812026Y1310929D01*
X812497Y1311635D01*
X813968Y1311929D01*
X814674Y1311459D01*
X816145Y1311753D01*
X816615Y1312459D01*
X818086Y1312754D01*
X818792Y1312283D01*
X935649Y1335674D01*
X1066449Y1405555D01*
X1071925D01*
G03X1072425Y1406055I0J500D01*
G01Y1407787D01*
G03X1071925Y1408287I-500J0D01*
G01X1070750D01*
G01X253121Y1077404D02*
X255325D01*
X255982Y1078061D01*
X257802D01*
X262408Y1080978D01*
X349878Y1318182D01*
X370163Y1331015D01*
X442865Y1345567D01*
X540283Y1326083D01*
X624308Y1342913D01*
X800001Y1307348D01*
X804484Y1308245D01*
X804485Y1308246D01*
X818550Y1311061D01*
X936042Y1334579D01*
X1066737Y1404405D01*
X1071925D01*
G03X1073575Y1406055I0J1650D01*
G01Y1407787D01*
G02X1074075Y1408287I500J0D01*
G01X1075250D01*
G01X252200Y1091254D02*
Y1092429D01*
G03X251700Y1092929I-500J0D01*
G01X248675D01*
X248175Y1092429D01*
Y1091504D01*
X247675Y1091004D01*
X242421D01*
G01X252200Y1095754D02*
Y1094579D01*
G02X251700Y1094079I-500J0D01*
G01X248675D01*
X248175Y1094579D01*
Y1095504D01*
X247675Y1096004D01*
X242421D01*
G01X375134Y174092D02*
X373830D01*
X373305Y173567D01*
X372888D01*
X372388Y174067D01*
Y174992D01*
X371888Y175492D01*
X366634D01*
G01X375134Y171892D02*
X373830D01*
X373305Y172417D01*
X372888D01*
X372388Y171917D01*
Y170992D01*
X371888Y170492D01*
X366634D01*
G01X376413Y185742D02*
Y186917D01*
G03X375913Y187417I-500J0D01*
G01X372888D01*
X372388Y186917D01*
Y185992D01*
X371888Y185492D01*
X366634D01*
G01X376413Y190242D02*
Y189067D01*
G02X375913Y188567I-500J0D01*
G01X372888D01*
X372388Y189067D01*
Y189992D01*
X371888Y190492D01*
X366634D01*
G01X1070750Y1231122D02*
X1071925D01*
G02X1072425Y1230622I0J-500D01*
G01Y1228901D01*
G02X1071925Y1228401I-500J0D01*
G01X1062713D01*
X1062113Y1229001D01*
X1060613D01*
X1060013Y1228401D01*
X1058513D01*
X1057913Y1229001D01*
X1056413D01*
X1055813Y1228401D01*
X1054313D01*
X1053713Y1229001D01*
X1052213D01*
X1051613Y1228401D01*
X1050113D01*
X1049513Y1229001D01*
X1048013D01*
X1047413Y1228401D01*
X1026056D01*
X953182Y1203261D01*
X953027Y1203139D01*
X946887Y1198302D01*
X940748Y1193464D01*
X935911Y1189653D01*
X934610Y1188627D01*
X928318Y1183669D01*
X874932Y1099292D01*
X817311Y824712D01*
X839962Y732928D01*
X812949Y625087D01*
X789195Y585465D01*
X777254Y565546D01*
X765441Y545843D01*
X472196Y344692D01*
X461449Y328143D01*
X456138Y319963D01*
X450828Y311787D01*
X422579Y268282D01*
Y268281D01*
X415338Y257130D01*
X385766Y176910D01*
X380713Y173711D01*
X379519D01*
X379138Y174092D01*
X377334D01*
G01X1075250Y1231122D02*
X1074075D01*
G03X1073575Y1230622I0J-500D01*
G01Y1228901D01*
G02X1071925Y1227251I-1650J0D01*
G01X1026249D01*
X953738Y1202235D01*
X941460Y1192560D01*
X929185Y1182887D01*
X876016Y1098852D01*
X818491Y824733D01*
X841148Y732926D01*
X814024Y624642D01*
X790182Y584873D01*
X766299Y545036D01*
X473036Y343873D01*
X467724Y335694D01*
X462414Y327516D01*
X451793Y311160D01*
X423729Y267941D01*
Y267940D01*
X416373Y256612D01*
X386711Y176146D01*
X381047Y172561D01*
X379807D01*
X379138Y171892D01*
X377334D01*
G01X375134Y626848D02*
X373830D01*
X373305Y626323D01*
X372888D01*
X372388Y626823D01*
Y627748D01*
X371888Y628248D01*
X366634D01*
G01X375134Y624648D02*
X373830D01*
X373305Y625173D01*
X372888D01*
X372388Y624673D01*
Y623748D01*
X371888Y623248D01*
X366634D01*
G01X376413Y638498D02*
Y639673D01*
G03X375913Y640173I-500J0D01*
G01X372888D01*
X372388Y639673D01*
Y638748D01*
X371888Y638248D01*
X366634D01*
G01Y643248D02*
X371888D01*
X372388Y642748D01*
Y641823D01*
X372888Y641323D01*
X375913D01*
G03X376413Y641823I0J500D01*
G01Y642998D01*
G01X1070750Y1316161D02*
X1071925D01*
G02X1072425Y1315661I0J-500D01*
G01Y1314301D01*
G02X1071564Y1313440I-861J0D01*
G01X1068363D01*
X986947Y1285357D01*
X986185Y1285728D01*
X984767Y1285239D01*
X984395Y1284476D01*
X982977Y1283987D01*
X982214Y1284359D01*
X980796Y1283870D01*
X980425Y1283107D01*
X979007Y1282618D01*
X978244Y1282989D01*
X976826Y1282500D01*
X976454Y1281737D01*
X975036Y1281248D01*
X974273Y1281619D01*
X972855Y1281130D01*
X972484Y1280367D01*
X944908Y1270856D01*
X916953Y1261212D01*
X767435Y1024920D01*
X569168Y913351D01*
X569169Y913350D01*
X568731Y913104D01*
X541939Y907383D01*
X490651Y896442D01*
X488514Y895986D01*
X486378Y895530D01*
X479965Y894162D01*
X473322Y892745D01*
X454778Y879628D01*
X436495Y842438D01*
X424925Y790206D01*
X401818Y685884D01*
X401817D01*
X390184Y633359D01*
X387572Y629266D01*
X383976Y626976D01*
X382023Y626543D01*
X381604Y626449D01*
X379437D01*
X379038Y626848D01*
X377334D01*
G01X1075250Y1316161D02*
X1074075D01*
G03X1073575Y1315661I0J-500D01*
G01Y1314301D01*
G02X1071564Y1312290I-2011J0D01*
G01X1068556D01*
X987321Y1284269D01*
Y1284267D01*
X917709Y1260256D01*
X768252Y1024060D01*
X753004Y1015479D01*
X571054Y913092D01*
X571056Y913090D01*
X569142Y912015D01*
X542179Y906258D01*
X488754Y894861D01*
X486618Y894405D01*
X473794Y891669D01*
X455681Y878858D01*
X437589Y842054D01*
X426048Y789957D01*
X402742Y684734D01*
X402741D01*
X391263Y632912D01*
X388405Y628432D01*
X384423Y625897D01*
X383632Y625721D01*
X381731Y625299D01*
X379453D01*
X378802Y624648D01*
X377334D01*
G01X375134Y1079604D02*
X373830D01*
X373305Y1079079D01*
X372888D01*
X372388Y1079579D01*
Y1080504D01*
X371888Y1081004D01*
X366634D01*
G01X375134Y1077404D02*
X373830D01*
X373305Y1077929D01*
X372888D01*
X372388Y1077429D01*
Y1076504D01*
X371888Y1076004D01*
X366634D01*
G01X377334Y1079604D02*
X379238D01*
X379595Y1079247D01*
X381060D01*
X382219Y1079983D01*
X399142Y1125859D01*
X395638Y1143090D01*
X416637Y1190857D01*
X417777Y1193451D01*
X595117Y1331413D01*
X625849Y1337564D01*
X801686Y1301966D01*
X805849Y1302800D01*
X806319Y1303506D01*
X807790Y1303801D01*
X808496Y1303330D01*
X809967Y1303625D01*
X810438Y1304331D01*
X811908Y1304625D01*
X812614Y1304155D01*
X814085Y1304449D01*
X814556Y1305155D01*
X816027Y1305450D01*
X816733Y1304979D01*
X818204Y1305274D01*
X818674Y1305980D01*
X820145Y1306274D01*
X820851Y1305804D01*
X935660Y1328790D01*
X1066104Y1398480D01*
X1071925D01*
G03X1072425Y1398980I0J500D01*
G01Y1400701D01*
G03X1071925Y1401201I-500J0D01*
G01X1070750D01*
G01X377334Y1077404D02*
X379238D01*
X379931Y1078097D01*
X381395D01*
X383164Y1079220D01*
X400335Y1125768D01*
X398587Y1134363D01*
Y1134364D01*
X396838Y1142961D01*
X417690Y1190394D01*
X418713Y1192722D01*
X595609Y1330338D01*
X625848Y1336390D01*
X801685Y1300792D01*
X936053Y1327695D01*
X1066392Y1397330D01*
X1071925D01*
G03X1073575Y1398980I0J1650D01*
G01Y1400701D01*
G02X1074075Y1401201I500J0D01*
G01X1075250D01*
G01X376413Y1091254D02*
Y1092429D01*
G03X375913Y1092929I-500J0D01*
G01X372888D01*
X372388Y1092429D01*
Y1091504D01*
X371888Y1091004D01*
X366634D01*
G01Y1096004D02*
X371888D01*
X372388Y1095504D01*
Y1094579D01*
X372888Y1094079D01*
X375913D01*
G03X376413Y1094579I0J500D01*
G01Y1095754D01*
G01X499346Y174092D02*
X498042D01*
X497517Y173567D01*
X497100D01*
X496600Y174067D01*
Y174992D01*
X496100Y175492D01*
X490846D01*
G01X499346Y171892D02*
X498042D01*
X497517Y172417D01*
X497100D01*
X496600Y171917D01*
Y170992D01*
X496100Y170492D01*
X490846D01*
G01X500625Y185742D02*
Y186917D01*
G03X500125Y187417I-500J0D01*
G01X497100D01*
X496600Y186917D01*
Y185992D01*
X496100Y185492D01*
X490846D01*
G01X500625Y190242D02*
Y189067D01*
G02X500125Y188567I-500J0D01*
G01X497100D01*
X496600Y189067D01*
Y189992D01*
X496100Y190492D01*
X490846D01*
G01X1070750Y1224035D02*
X1071925D01*
G02X1072425Y1223535I0J-500D01*
G01Y1221814D01*
G02X1071925Y1221314I-500J0D01*
G01X1062712D01*
X1062112Y1221914D01*
X1060612D01*
X1060012Y1221314D01*
X1058512D01*
X1057912Y1221914D01*
X1056412D01*
X1055812Y1221314D01*
X1054312D01*
X1053712Y1221914D01*
X1052212D01*
X1051612Y1221314D01*
X1050112D01*
X1049512Y1221914D01*
X1048012D01*
X1047412Y1221314D01*
X1024156D01*
X956599Y1198009D01*
X933136Y1179519D01*
X881313Y1097613D01*
X866337Y1026256D01*
X851594Y956016D01*
X851593D01*
X823935Y824249D01*
X829572Y801412D01*
X833768Y784412D01*
X840061Y758909D01*
X840062D01*
X846357Y733404D01*
X818624Y622720D01*
X764884Y533083D01*
X606716Y424584D01*
X603734Y420096D01*
X603021Y419022D01*
X603020Y419021D01*
X600875Y415792D01*
X600876D01*
X597301Y410409D01*
X595085Y407073D01*
X509757Y175668D01*
X506639Y173693D01*
X503849D01*
X503450Y174092D01*
X501546D01*
G01X1075250Y1224035D02*
X1074075D01*
G03X1073575Y1223535I0J-500D01*
G01Y1221814D01*
G02X1071925Y1220164I-1650J0D01*
G01X1024349D01*
X957158Y1196985D01*
X934003Y1178738D01*
X882397Y1097173D01*
X852528Y954866D01*
X852527D01*
X825115Y824270D01*
X832787Y793187D01*
X834885Y784688D01*
X847543Y733402D01*
X819699Y622275D01*
X765742Y532276D01*
X607551Y423761D01*
X604693Y419459D01*
X602856Y416693D01*
X596118Y406548D01*
X510702Y174904D01*
X506973Y172543D01*
X503821D01*
X503170Y171892D01*
X501546D01*
G01X499346Y626848D02*
X498042D01*
X497517Y626323D01*
X497100D01*
X496600Y626823D01*
Y627748D01*
X496100Y628248D01*
X490846D01*
G01X499346Y624648D02*
X498042D01*
X497517Y625173D01*
X497100D01*
X496600Y624673D01*
Y623748D01*
X496100Y623248D01*
X490846D01*
G01X500625Y638498D02*
Y639673D01*
G03X500125Y640173I-500J0D01*
G01X497100D01*
X496600Y639673D01*
Y638748D01*
X496100Y638248D01*
X490846D01*
G01X500625Y642998D02*
Y641823D01*
G02X500125Y641323I-500J0D01*
G01X497100D01*
X496600Y641823D01*
Y642748D01*
X496100Y643248D01*
X490846D01*
G01X501546Y626848D02*
X502998D01*
X503363Y626483D01*
X505197D01*
X506994Y626882D01*
X510857Y629344D01*
X518968Y642076D01*
X549468Y779654D01*
X663533Y958710D01*
X689918Y973567D01*
X739999Y1001767D01*
X772334Y1019973D01*
X902978Y1226486D01*
X902792Y1227314D01*
X903594Y1228582D01*
X904421Y1228768D01*
X905223Y1230036D01*
X905037Y1230864D01*
X905839Y1232131D01*
X906667Y1232318D01*
X907469Y1233585D01*
X907283Y1234413D01*
X908084Y1235681D01*
X908912Y1235867D01*
X909714Y1237135D01*
X909528Y1237962D01*
X910330Y1239230D01*
X911157Y1239416D01*
X921929Y1256443D01*
X1066631Y1306354D01*
X1071925D01*
G03X1072425Y1306854I0J500D01*
G01Y1308575D01*
G03X1071925Y1309075I-500J0D01*
G01X1070750D01*
G01X501546Y624648D02*
X502864D01*
X503549Y625333D01*
X505324D01*
X507441Y625803D01*
X511690Y628511D01*
X520047Y641629D01*
X550547Y779207D01*
X664349Y957849D01*
X740564Y1000764D01*
X773151Y1019113D01*
X922686Y1255487D01*
X1066824Y1305204D01*
X1071925D01*
G03X1073575Y1306854I0J1650D01*
G01Y1308575D01*
G02X1074075Y1309075I500J0D01*
G01X1075250D01*
G01X499346Y1079604D02*
X498042D01*
X497517Y1079079D01*
X497100D01*
X496600Y1079579D01*
Y1080504D01*
X496100Y1081004D01*
X490846D01*
G01X499346Y1077404D02*
X498042D01*
X497517Y1077929D01*
X497100D01*
X496600Y1077429D01*
Y1076504D01*
X496100Y1076004D01*
X490846D01*
G01X501546Y1079604D02*
X503450D01*
X503789Y1079265D01*
X505019D01*
X533430Y1097385D01*
X537337Y1103509D01*
X540003Y1115522D01*
X536274Y1132349D01*
X539360Y1146267D01*
X536606Y1158686D01*
X544376Y1193740D01*
X544328Y1193958D01*
X577124Y1245442D01*
X590551Y1305995D01*
X600407Y1321468D01*
X611663Y1328329D01*
X626294Y1331258D01*
X804465Y1295186D01*
X805936Y1295480D01*
X806406Y1296187D01*
X807877Y1296481D01*
X808583Y1296011D01*
X810054Y1296305D01*
X810525Y1297011D01*
X811995Y1297306D01*
X812702Y1296835D01*
X814172Y1297130D01*
X814643Y1297836D01*
X816114Y1298130D01*
X816820Y1297660D01*
X818291Y1297954D01*
X818761Y1298660D01*
X820232Y1298955D01*
X820938Y1298484D01*
X934402Y1321203D01*
X1065804Y1391393D01*
X1071925D01*
G03X1072425Y1391893I0J500D01*
G01Y1393614D01*
G03X1071925Y1394114I-500J0D01*
G01X1070750D01*
G01X501546Y1077404D02*
X503450D01*
X504161Y1078115D01*
X505355D01*
X534263Y1096552D01*
X538416Y1103062D01*
X541181Y1115522D01*
X537452Y1132349D01*
X540538Y1146267D01*
X537784Y1158686D01*
X545554Y1193739D01*
Y1193741D01*
X578203Y1244993D01*
X591630Y1305548D01*
X601234Y1320625D01*
X612088Y1327241D01*
X626293Y1330084D01*
X804464Y1294012D01*
X934794Y1320108D01*
X934795D01*
X1066092Y1390243D01*
X1071925D01*
G03X1073575Y1391893I0J1650D01*
G01Y1393614D01*
G02X1074075Y1394114I500J0D01*
G01X1075250D01*
G01X500625Y1091254D02*
Y1092429D01*
G03X500125Y1092929I-500J0D01*
G01X497100D01*
X496600Y1092429D01*
Y1091504D01*
X496100Y1091004D01*
X490846D01*
G01X500625Y1095754D02*
Y1094579D01*
G02X500125Y1094079I-500J0D01*
G01X497226D01*
X496600Y1094705D01*
Y1095416D01*
X496012Y1096004D01*
X490846D01*
G01X623559Y174092D02*
X622255D01*
X621730Y173567D01*
X621313D01*
X620813Y174067D01*
Y174992D01*
X620313Y175492D01*
X615059D01*
G01X623559Y171892D02*
X622255D01*
X621730Y172417D01*
X621313D01*
X620813Y171917D01*
Y170992D01*
X620313Y170492D01*
X615059D01*
G01X624838Y185742D02*
Y186917D01*
G03X624338Y187417I-500J0D01*
G01X621313D01*
X620813Y186917D01*
Y185992D01*
X620313Y185492D01*
X615059D01*
G01X624838Y190242D02*
Y189067D01*
G02X624338Y188567I-500J0D01*
G01X621383D01*
X620813Y189137D01*
Y189992D01*
X620313Y190492D01*
X615059D01*
G01X1070750Y1216949D02*
X1071925D01*
G02X1072425Y1216449I0J-500D01*
G01Y1214728D01*
G02X1071925Y1214228I-500J0D01*
G01X1062606D01*
X1062006Y1214828D01*
X1060506D01*
X1059906Y1214228D01*
X1058406D01*
X1057806Y1214828D01*
X1056306D01*
X1055706Y1214228D01*
X1054206D01*
X1053606Y1214828D01*
X1052106D01*
X1051506Y1214228D01*
X1050006D01*
X1049406Y1214828D01*
X1047906D01*
X1047306Y1214228D01*
X1022458D01*
X959346Y1192458D01*
X938749Y1176228D01*
X938747Y1176226D01*
X888171Y1096285D01*
X830802Y822780D01*
X852756Y733848D01*
X824321Y620422D01*
X790130Y561774D01*
Y561773D01*
X755939Y503126D01*
X635887Y177557D01*
X629715Y173648D01*
X627807D01*
X627363Y174092D01*
X625759D01*
G01X1075250Y1216949D02*
X1074075D01*
G03X1073575Y1216449I0J-500D01*
G01Y1214728D01*
G02X1071925Y1213078I-1650J0D01*
G01X1022651D01*
X959905Y1191434D01*
X939616Y1175447D01*
X889255Y1095845D01*
X831982Y822801D01*
X853942Y733846D01*
X825397Y619984D01*
X756984Y502633D01*
X636832Y176793D01*
X630049Y172498D01*
X627969D01*
X627363Y171892D01*
X625759D01*
G01X623559Y626848D02*
X622255D01*
X621730Y626323D01*
X621313D01*
X620813Y626823D01*
Y627748D01*
X620313Y628248D01*
X615059D01*
G01X623559Y624648D02*
X622255D01*
X621730Y625173D01*
X621313D01*
X620813Y624673D01*
Y623748D01*
X620313Y623248D01*
X615059D01*
G01Y638248D02*
X620313D01*
X620813Y638748D01*
Y639673D01*
X621313Y640173D01*
X624338D01*
G02X624838Y639673I0J-500D01*
G01Y638498D01*
G01X615059Y643248D02*
X620313D01*
X620813Y642748D01*
Y641908D01*
X621398Y641323D01*
X624338D01*
G03X624838Y641823I0J500D01*
G01Y642998D01*
G01X625759Y626848D02*
X627763D01*
X628147Y626464D01*
X629948D01*
X631656Y626843D01*
X636804Y630123D01*
X641424Y637374D01*
X650126Y676629D01*
X649671Y677345D01*
X649995Y678809D01*
X650711Y679265D01*
X651036Y680730D01*
X650580Y681445D01*
X650904Y682910D01*
X651620Y683366D01*
X651945Y684830D01*
X651489Y685546D01*
X651813Y687010D01*
X652529Y687466D01*
X652854Y688931D01*
X652398Y689646D01*
X652722Y691111D01*
X653438Y691567D01*
X655017Y698689D01*
X655018D01*
X767891Y854012D01*
X810862Y1049622D01*
X941394Y1255891D01*
X1065823Y1298842D01*
X1071925D01*
G03X1072425Y1299342I0J500D01*
G01Y1301488D01*
G03X1071925Y1301988I-500J0D01*
G01X1070750D01*
G01X625759Y624648D02*
X627763D01*
X628429Y625314D01*
X630075D01*
X632103Y625764D01*
X637637Y629290D01*
X642503Y636927D01*
X656088Y698205D01*
X768963Y853530D01*
X811942Y1049178D01*
X942150Y1254935D01*
X1066016Y1297692D01*
X1071925D01*
G03X1073575Y1299342I0J1650D01*
G01Y1301488D01*
G02X1074075Y1301988I500J0D01*
G01X1075250D01*
G01X623559Y1079604D02*
X622255D01*
X621730Y1079079D01*
X621313D01*
X620813Y1079579D01*
Y1080504D01*
X620313Y1081004D01*
X615059D01*
G01X623559Y1077404D02*
X622255D01*
X621730Y1077929D01*
X621313D01*
X620813Y1077429D01*
Y1076504D01*
X620313Y1076004D01*
X615059D01*
G01X625759Y1079604D02*
X627563D01*
X627910Y1079257D01*
X630760D01*
X634875Y1081862D01*
X666781Y1168390D01*
X698627Y1217425D01*
X719332Y1230870D01*
X916769Y1307293D01*
X917112Y1308069D01*
X918511Y1308611D01*
X919287Y1308268D01*
X920686Y1308809D01*
X921029Y1309585D01*
X922428Y1310127D01*
X923204Y1309784D01*
X924603Y1310325D01*
X924946Y1311102D01*
X926345Y1311643D01*
X927121Y1311300D01*
X928520Y1311842D01*
X928863Y1312618D01*
X930262Y1313159D01*
X931038Y1312816D01*
X932962Y1313561D01*
X1064922Y1384055D01*
X1071925D01*
G03X1072425Y1384555I0J500D01*
G01Y1386528D01*
G03X1071925Y1387028I-500J0D01*
G01X1070750D01*
G01X625759Y1077404D02*
X627563D01*
X628266Y1078107D01*
X631094D01*
X635820Y1081098D01*
X667816Y1167871D01*
X699459Y1216593D01*
X719844Y1229831D01*
X933443Y1312513D01*
X1065210Y1382905D01*
X1071925D01*
G03X1073575Y1384555I0J1650D01*
G01Y1386528D01*
G02X1074075Y1387028I500J0D01*
G01X1075250D01*
G01X624838Y1091254D02*
Y1092429D01*
G03X624338Y1092929I-500J0D01*
G01X621313D01*
X620813Y1092429D01*
Y1091504D01*
X620313Y1091004D01*
X615059D01*
G01X624838Y1095754D02*
Y1094579D01*
G02X624338Y1094079I-500J0D01*
G01X621313D01*
X620813Y1094579D01*
Y1095504D01*
X620313Y1096004D01*
X615059D01*
G01X747772Y174092D02*
X746468D01*
X745943Y173567D01*
X745526D01*
X745026Y174067D01*
Y174992D01*
X744526Y175492D01*
X739272D01*
G01X747772Y171892D02*
X746468D01*
X745943Y172417D01*
X745526D01*
X745026Y171917D01*
Y170992D01*
X744526Y170492D01*
X739272D01*
G01X749051Y185742D02*
Y186917D01*
G03X748551Y187417I-500J0D01*
G01X745526D01*
X745026Y186917D01*
Y185992D01*
X744526Y185492D01*
X739272D01*
G01X749051Y190242D02*
Y189067D01*
G02X748551Y188567I-500J0D01*
G01X745526D01*
X745026Y189067D01*
Y189872D01*
X744406Y190492D01*
X739272D01*
G01X747772Y626848D02*
X746468D01*
X745943Y626323D01*
X745526D01*
X745026Y626823D01*
Y627748D01*
X744526Y628248D01*
X739272D01*
G01X747772Y624648D02*
X746468D01*
X745943Y625173D01*
X745526D01*
X745026Y624673D01*
Y623748D01*
X744526Y623248D01*
X739272D01*
G01X749051Y638498D02*
Y639673D01*
G03X748551Y640173I-500J0D01*
G01X745526D01*
X745026Y639673D01*
Y638748D01*
X744526Y638248D01*
X739272D01*
G01X749051Y642998D02*
Y641823D01*
G02X748551Y641323I-500J0D01*
G01X745526D01*
X745026Y641823D01*
Y642748D01*
X744526Y643248D01*
X739272D01*
G01X747772Y1079604D02*
X746468D01*
X745943Y1079079D01*
X745526D01*
X745026Y1079579D01*
Y1080504D01*
X744526Y1081004D01*
X739272D01*
G01X747772Y1077404D02*
X746468D01*
X745943Y1077929D01*
X745526D01*
X745026Y1077429D01*
Y1076504D01*
X744526Y1076004D01*
X739272D01*
G01X749051Y1091254D02*
Y1092429D01*
G03X748551Y1092929I-500J0D01*
G01X745526D01*
X745026Y1092429D01*
Y1091504D01*
X744526Y1091004D01*
X739272D01*
G01X749051Y1095754D02*
Y1094579D01*
G02X748551Y1094079I-500J0D01*
G01X745526D01*
X745026Y1094579D01*
Y1095504D01*
X744526Y1096004D01*
X739272D01*
G01X1070750Y1209862D02*
X1071925D01*
G02X1072425Y1209362I0J-500D01*
G01Y1207641D01*
G02X1071925Y1207141I-500J0D01*
G01X1063368D01*
X1062768Y1207741D01*
X1061268D01*
X1060668Y1207141D01*
X1059168D01*
X1058568Y1207741D01*
X1057068D01*
X1056468Y1207141D01*
X1054968D01*
X1054368Y1207741D01*
X1052868D01*
X1052268Y1207141D01*
X1050768D01*
X1050168Y1207741D01*
X1048668D01*
X1048068Y1207141D01*
X1020971D01*
X962175Y1186857D01*
X962022Y1186737D01*
X962023D01*
X952925Y1179568D01*
X943673Y1172278D01*
X896881Y1098324D01*
X896838Y1098120D01*
X896839D01*
X838351Y819407D01*
X859408Y734106D01*
X749726Y297920D01*
X772068Y207404D01*
X770392Y199427D01*
Y199426D01*
X768717Y191451D01*
X758749Y176531D01*
X754266Y173693D01*
X752175D01*
X751776Y174092D01*
X749972D01*
G01X1075250Y1209862D02*
X1074075D01*
G03X1073575Y1209362I0J-500D01*
G01Y1207641D01*
G02X1071925Y1205991I-1650J0D01*
G01X1021164D01*
X962734Y1185833D01*
X944540Y1171496D01*
X897965Y1097884D01*
X839531Y819428D01*
X849997Y777032D01*
X860594Y734103D01*
X750912Y297917D01*
X773248Y207425D01*
X769797Y190997D01*
X759571Y175689D01*
X754600Y172543D01*
X752147D01*
X751496Y171892D01*
X749972D01*
G01Y626848D02*
X751876D01*
X752266Y626458D01*
X753689D01*
X754437Y626931D01*
X765307Y678697D01*
X749778Y741608D01*
X815675Y1042613D01*
X946903Y1250019D01*
X948321Y1250508D01*
X948693Y1251271D01*
X950111Y1251760D01*
X950873Y1251389D01*
X952291Y1251878D01*
X952663Y1252641D01*
X954081Y1253130D01*
X954844Y1252758D01*
X956262Y1253247D01*
X956633Y1254010D01*
X958051Y1254499D01*
X958814Y1254128D01*
X960232Y1254617D01*
X960604Y1255380D01*
X962022Y1255869D01*
X962785Y1255497D01*
X1069164Y1292190D01*
X1071925D01*
G03X1072425Y1292690I0J500D01*
G01Y1294402D01*
G03X1071925Y1294902I-500J0D01*
G01X1070750D01*
G01X749972Y624648D02*
X751876D01*
X752536Y625308D01*
X754023D01*
X755463Y626219D01*
X766487Y678718D01*
X758723Y710170D01*
Y710171D01*
X750959Y741624D01*
X816756Y1042169D01*
X947661Y1249063D01*
X1069357Y1291040D01*
X1071925D01*
G03X1073575Y1292690I0J1650D01*
G01Y1294402D01*
G02X1074075Y1294902I500J0D01*
G01X1075250D01*
G01X749972Y1079604D02*
X751676D01*
X752043Y1079237D01*
X754139D01*
X761411Y1083847D01*
X886737Y1281934D01*
X890994Y1284207D01*
X891240Y1285019D01*
X892563Y1285726D01*
X893375Y1285479D01*
X894698Y1286186D01*
X894945Y1286998D01*
X896268Y1287704D01*
X897080Y1287458D01*
X898403Y1288164D01*
X898650Y1288976D01*
X899973Y1289683D01*
X900785Y1289436D01*
X902108Y1290143D01*
X902354Y1290955D01*
X903678Y1291662D01*
X904490Y1291415D01*
X1065157Y1377220D01*
X1071925D01*
G03X1072425Y1377720I0J500D01*
G01Y1379441D01*
G03X1071925Y1379941I-500J0D01*
G01X1070750D01*
G01X749972Y1077404D02*
X751676D01*
X752359Y1078087D01*
X754473D01*
X762245Y1083014D01*
X887547Y1281062D01*
X889540Y1282126D01*
X889541Y1282127D01*
X905032Y1290400D01*
X905031D01*
X1065445Y1376070D01*
X1071925D01*
G03X1073575Y1377720I0J1650D01*
G01Y1379441D01*
G02X1074075Y1379941I500J0D01*
G01X1075250D01*
G01X1267378Y174092D02*
X1269282D01*
X1269807Y173567D01*
G01D02*
X1282624D01*
X1283124Y174067D01*
Y174992D01*
X1283624Y175492D01*
X1288878D01*
G01X1267378Y171892D02*
X1269282D01*
X1269807Y172417D01*
G01D02*
X1282624D01*
X1283124Y171917D01*
Y170992D01*
X1283624Y170492D01*
X1288878D01*
G01X1274900Y182823D02*
X1274194D01*
G02X1273225Y183792I0J969D01*
G01Y185419D01*
X1275223Y187417D01*
G01D02*
X1282390D01*
X1283124Y186683D01*
Y186028D01*
X1283660Y185492D01*
X1288878D01*
G01X1270400Y182823D02*
X1271106D01*
G03X1272075Y183792I0J969D01*
G01Y185896D01*
X1274746Y188567D01*
G01D02*
X1282624D01*
X1283124Y189067D01*
Y189992D01*
X1283624Y190492D01*
X1288878D01*
G01X1265178Y174092D02*
X1264540D01*
X1263881Y173433D01*
X1259983D01*
X1258425Y171875D01*
Y168708D01*
G02X1257540Y167823I-885J0D01*
G01X1256750D01*
G01X1265178Y171892D02*
X1264283D01*
X1263892Y172283D01*
X1260460D01*
X1259575Y171398D01*
Y168708D01*
G03X1260460Y167823I885J0D01*
G01X1261250D01*
G01X1267378Y626848D02*
X1269182D01*
X1269707Y626323D01*
X1282624D01*
X1283124Y626823D01*
Y627748D01*
X1283624Y628248D01*
X1288878D01*
G01X1267378Y624648D02*
X1269182D01*
X1269707Y625173D01*
X1282624D01*
X1283124Y624673D01*
Y623748D01*
X1283624Y623248D01*
X1288878D01*
G01X1278500Y638498D02*
Y639672D01*
G02X1279001Y640173I501J0D01*
G01X1282624D01*
X1283124Y639673D01*
Y638748D01*
X1283624Y638248D01*
X1288878D01*
G01X1278500Y642998D02*
Y641824D01*
G03X1279001Y641323I501J0D01*
G01X1282516D01*
X1283124Y641931D01*
Y642526D01*
X1283846Y643248D01*
X1288878D01*
G01X1259800Y627998D02*
Y626824D01*
X1260301Y626323D01*
X1263349D01*
X1263874Y626848D01*
X1265178D01*
G01X1259800Y623498D02*
Y624672D01*
X1260301Y625173D01*
X1263349D01*
X1263874Y624648D01*
X1265178D01*
G01X1267378Y1079604D02*
X1269482D01*
X1270007Y1079079D01*
X1282624D01*
X1283124Y1079579D01*
Y1080504D01*
X1283624Y1081004D01*
X1288878D01*
G01X1267378Y1077404D02*
X1269482D01*
X1270007Y1077929D01*
X1282624D01*
X1283124Y1077429D01*
Y1076504D01*
X1283624Y1076004D01*
X1288878D01*
G01X1259800Y1080754D02*
Y1079647D01*
G03X1259946Y1079294I500J0D01*
G01X1260015Y1079225D01*
G03X1260368Y1079079I353J354D01*
G01X1263349D01*
X1263874Y1079604D01*
X1265178D01*
G01X1259800Y1076254D02*
Y1077362D01*
G02X1259946Y1077715I500J0D01*
G01X1260014Y1077783D01*
G02X1260367Y1077929I353J-354D01*
G01X1263349D01*
X1263874Y1077404D01*
X1265178D01*
G01X1278500Y1091254D02*
Y1092428D01*
G02X1279001Y1092929I501J0D01*
G01X1282624D01*
X1283124Y1092429D01*
Y1091504D01*
X1283624Y1091004D01*
X1288878D01*
G01X1278500Y1095754D02*
Y1094580D01*
G03X1279001Y1094079I501J0D01*
G01X1282560D01*
X1283124Y1094643D01*
Y1095300D01*
X1283828Y1096004D01*
X1288878D01*
G01X1391591Y174092D02*
X1393195D01*
X1393720Y173567D01*
X1406837D01*
X1407337Y174067D01*
Y174992D01*
X1407837Y175492D01*
X1413091D01*
G01X1391591Y171892D02*
X1393195D01*
X1393720Y172417D01*
X1406837D01*
X1407337Y171917D01*
Y170992D01*
X1407837Y170492D01*
X1413091D01*
G01X1402713Y185742D02*
Y186917D01*
G02X1403213Y187417I500J0D01*
G01X1406837D01*
X1407337Y186917D01*
Y185992D01*
X1407837Y185492D01*
X1413091D01*
G01X1402713Y190242D02*
Y189067D01*
G03X1403213Y188567I500J0D01*
G01X1406837D01*
X1407337Y189067D01*
Y189992D01*
X1407837Y190492D01*
X1413091D01*
G01X1389391Y174092D02*
X1387487D01*
X1386925Y173530D01*
X1384293D01*
X1382743Y171980D01*
Y168323D01*
G02X1382243Y167823I-500J0D01*
G01X1380963D01*
G01X1389391Y171892D02*
X1387487D01*
X1386999Y172380D01*
X1384770D01*
X1383893Y171503D01*
Y168323D01*
G03X1384393Y167823I500J0D01*
G01X1385463D01*
G01X1391591Y626848D02*
X1393695D01*
X1394220Y626323D01*
X1406837D01*
X1407337Y626823D01*
Y627748D01*
X1407837Y628248D01*
X1413091D01*
G01X1391591Y624648D02*
X1393695D01*
X1394220Y625173D01*
X1406837D01*
X1407337Y624673D01*
Y623748D01*
X1407837Y623248D01*
X1413091D01*
G01X1402713Y638498D02*
Y639672D01*
G02X1403214Y640173I501J0D01*
G01X1406837D01*
X1407337Y639673D01*
Y638748D01*
X1407837Y638248D01*
X1413091D01*
G01X1402713Y642998D02*
Y641824D01*
G03X1403214Y641323I501J0D01*
G01X1406767D01*
X1407337Y641893D01*
Y642566D01*
X1408019Y643248D01*
X1413091D01*
G01X1384013Y627998D02*
Y626864D01*
G03X1384159Y626511I500J0D01*
G01X1384201Y626469D01*
G03X1384554Y626323I353J354D01*
G01X1387562D01*
X1388087Y626848D01*
X1389391D01*
G01X1384013Y623498D02*
Y624621D01*
G02X1384159Y624974I500J0D01*
G01X1384212Y625027D01*
G02X1384565Y625173I353J-354D01*
G01X1387562D01*
X1388087Y624648D01*
X1389391D01*
G01X1391591Y1079604D02*
X1393795D01*
X1394320Y1079079D01*
X1406837D01*
X1407337Y1079579D01*
Y1080504D01*
X1407837Y1081004D01*
X1413091D01*
G01X1391591Y1077404D02*
X1393795D01*
X1394320Y1077929D01*
X1406837D01*
X1407337Y1077429D01*
Y1076504D01*
X1407837Y1076004D01*
X1413091D01*
G01X1384013Y1080754D02*
Y1079648D01*
G03X1384159Y1079295I500J0D01*
G01X1384229Y1079225D01*
G03X1384582Y1079079I353J354D01*
G01X1387562D01*
X1388087Y1079604D01*
X1389391D01*
G01X1384013Y1076254D02*
Y1077359D01*
G02X1384159Y1077712I500J0D01*
G01X1384230Y1077783D01*
G02X1384583Y1077929I353J-354D01*
G01X1387562D01*
X1388087Y1077404D01*
X1389391D01*
G01X1402713Y1091254D02*
Y1092428D01*
G02X1403214Y1092929I501J0D01*
G01X1406837D01*
X1407337Y1092429D01*
Y1091504D01*
X1407837Y1091004D01*
X1413091D01*
G01X1402713Y1095754D02*
Y1094580D01*
G03X1403214Y1094079I501J0D01*
G01X1406787D01*
X1407337Y1094629D01*
Y1095286D01*
X1408055Y1096004D01*
X1413091D01*
G01X1515803Y174092D02*
X1517607D01*
X1518132Y173567D01*
X1531049D01*
X1531549Y174067D01*
Y174992D01*
X1532049Y175492D01*
X1537303D01*
G01X1515803Y171892D02*
X1517607D01*
X1518132Y172417D01*
X1531049D01*
X1531549Y171917D01*
Y170992D01*
X1532049Y170492D01*
X1537303D01*
G01X1511450Y181700D02*
X1510283D01*
G03X1509930Y181554I0J-500D01*
G01X1509921Y181545D01*
G03X1509775Y181192I354J-353D01*
G01Y174125D01*
X1510333Y173567D01*
X1511774D01*
X1512299Y174092D01*
X1513603D01*
G01X1506950Y181700D02*
X1508087D01*
G02X1508440Y181554I0J-500D01*
G01X1508479Y181515D01*
G02X1508625Y181162I-354J-353D01*
G01Y173648D01*
X1509856Y172417D01*
X1511774D01*
X1512299Y171892D01*
X1513603D01*
G01X1515803Y626848D02*
X1517407D01*
X1517932Y626323D01*
X1531049D01*
X1531549Y626823D01*
Y627748D01*
X1532049Y628248D01*
X1537303D01*
G01X1515803Y624648D02*
X1517407D01*
X1517932Y625173D01*
X1531049D01*
X1531549Y624673D01*
Y623748D01*
X1532049Y623248D01*
X1537303D01*
G01X1508225Y627998D02*
Y626887D01*
G03X1508371Y626534I500J0D01*
G01X1508436Y626469D01*
G03X1508789Y626323I353J354D01*
G01X1511774D01*
X1512299Y626848D01*
X1513603D01*
G01X1508225Y623498D02*
Y624608D01*
G02X1508371Y624961I500J0D01*
G01X1508437Y625027D01*
G02X1508790Y625173I353J-354D01*
G01X1511774D01*
X1512299Y624648D01*
X1513603D01*
G01X1515803Y1079604D02*
X1517707D01*
X1518232Y1079079D01*
X1531049D01*
X1531549Y1079579D01*
Y1080504D01*
X1532049Y1081004D01*
X1537303D01*
G01X1515803Y1077404D02*
X1517707D01*
X1518232Y1077929D01*
X1531049D01*
X1531549Y1077429D01*
Y1076504D01*
X1532049Y1076004D01*
X1537303D01*
G01X1508225Y1080754D02*
Y1079636D01*
G03X1508371Y1079283I500J0D01*
G01X1508429Y1079225D01*
G03X1508782Y1079079I353J354D01*
G01X1511774D01*
X1512299Y1079604D01*
X1513603D01*
G01X1508225Y1076254D02*
Y1077391D01*
G02X1508371Y1077744I500J0D01*
G01X1508410Y1077783D01*
G02X1508763Y1077929I353J-354D01*
G01X1511774D01*
X1512299Y1077404D01*
X1513603D01*
G01X1526925Y185742D02*
Y186916D01*
G02X1527426Y187417I501J0D01*
G01X1531049D01*
X1531549Y186917D01*
Y185992D01*
X1532049Y185492D01*
X1537303D01*
G01X1526925Y190242D02*
Y189068D01*
G03X1527426Y188567I501J0D01*
G01X1531049D01*
X1531549Y189067D01*
Y189816D01*
X1532225Y190492D01*
X1537303D01*
G01X1526925Y638498D02*
Y639672D01*
G02X1527426Y640173I501J0D01*
G01X1531049D01*
X1531549Y639673D01*
Y638748D01*
X1532049Y638248D01*
X1537303D01*
G01X1526925Y642998D02*
Y641824D01*
G03X1527426Y641323I501J0D01*
G01X1530945D01*
X1531549Y641927D01*
Y642568D01*
X1532229Y643248D01*
X1537303D01*
G01X1526925Y1091254D02*
Y1092428D01*
G02X1527426Y1092929I501J0D01*
G01X1531049D01*
X1531549Y1092429D01*
Y1091504D01*
X1532049Y1091004D01*
X1537303D01*
G01X1526925Y1095754D02*
Y1094580D01*
G03X1527426Y1094079I501J0D01*
G01X1530991D01*
X1531549Y1094637D01*
Y1095314D01*
X1532239Y1096004D01*
X1537303D01*
G01X1640016Y174092D02*
X1642020D01*
X1642545Y173567D01*
X1655262D01*
X1655762Y174067D01*
Y174992D01*
X1656262Y175492D01*
X1661516D01*
G01X1640016Y171892D02*
X1642020D01*
X1642545Y172417D01*
X1655262D01*
X1655762Y171917D01*
Y170992D01*
X1656262Y170492D01*
X1661516D01*
G01X1651138Y185742D02*
Y186916D01*
G02X1651639Y187417I501J0D01*
G01X1655262D01*
X1655762Y186917D01*
Y185992D01*
X1656262Y185492D01*
X1661516D01*
G01X1651138Y190242D02*
Y189068D01*
G03X1651639Y188567I501J0D01*
G01X1655190D01*
X1655762Y189139D01*
Y189880D01*
X1656374Y190492D01*
X1661516D01*
G01X1632438Y175242D02*
Y174213D01*
G03X1632584Y173860I500J0D01*
G01X1632731Y173713D01*
G03X1633084Y173567I353J354D01*
G01X1635987D01*
X1636512Y174092D01*
X1637816D01*
G01X1632438Y170742D02*
Y171861D01*
G02X1632584Y172214I500J0D01*
G01X1632641Y172271D01*
G02X1632994Y172417I353J-354D01*
G01X1635987D01*
X1636512Y171892D01*
X1637816D01*
G01X1640016Y626848D02*
X1641720D01*
X1642245Y626323D01*
X1655262D01*
X1655762Y626823D01*
Y627748D01*
X1656262Y628248D01*
X1661516D01*
G01X1640016Y624648D02*
X1641720D01*
X1642245Y625173D01*
X1655262D01*
X1655762Y624673D01*
Y623748D01*
X1656262Y623248D01*
X1661516D01*
G01X1651138Y638498D02*
Y639672D01*
G02X1651639Y640173I501J0D01*
G01X1655262D01*
X1655762Y639673D01*
Y638748D01*
X1656262Y638248D01*
X1661516D01*
G01X1651138Y642998D02*
Y641824D01*
G03X1651639Y641323I501J0D01*
G01X1655102D01*
X1655762Y641983D01*
Y642686D01*
X1656324Y643248D01*
X1661516D01*
G01X1632438Y627998D02*
Y626926D01*
G03X1632584Y626573I500J0D01*
G01X1632688Y626469D01*
G03X1633041Y626323I353J354D01*
G01X1635987D01*
X1636512Y626848D01*
X1637816D01*
G01X1632438Y623498D02*
Y624640D01*
G02X1632584Y624993I500J0D01*
G01X1632618Y625027D01*
G02X1632971Y625173I353J-354D01*
G01X1635987D01*
X1636512Y624648D01*
X1637816D01*
G01X1640016Y1079604D02*
X1642220D01*
X1642745Y1079079D01*
X1655262D01*
X1655762Y1079579D01*
Y1080504D01*
X1656262Y1081004D01*
X1661516D01*
G01X1640016Y1077404D02*
X1642220D01*
X1642745Y1077929D01*
X1655262D01*
X1655762Y1077429D01*
Y1076504D01*
X1656262Y1076004D01*
X1661516D01*
G01X1632438Y1080754D02*
Y1079677D01*
G03X1632584Y1079324I500J0D01*
G01X1632683Y1079225D01*
G03X1633036Y1079079I353J354D01*
G01X1635987D01*
X1636512Y1079604D01*
X1637816D01*
G01X1632438Y1076254D02*
Y1077387D01*
G02X1632584Y1077740I500J0D01*
G01X1632627Y1077783D01*
G02X1632980Y1077929I353J-354D01*
G01X1635987D01*
X1636512Y1077404D01*
X1637816D01*
G01X1651138Y1091254D02*
Y1092428D01*
G02X1651639Y1092929I501J0D01*
G01X1655262D01*
X1655762Y1092429D01*
Y1091504D01*
X1656262Y1091004D01*
X1661516D01*
G01X1651138Y1095754D02*
Y1094580D01*
G03X1651639Y1094079I501J0D01*
G01X1655132D01*
X1655762Y1094709D01*
Y1095224D01*
X1656542Y1096004D01*
X1661516D01*
G01X1764228Y174092D02*
X1766232D01*
X1766757Y173567D01*
X1779474D01*
X1779974Y174067D01*
Y174992D01*
X1780474Y175492D01*
X1785728D01*
G01X1764228Y171892D02*
X1766232D01*
X1766757Y172417D01*
X1779474D01*
X1779974Y171917D01*
Y170992D01*
X1780474Y170492D01*
X1785728D01*
G01X1756650Y175242D02*
Y174229D01*
G03X1756796Y173876I500J0D01*
G01X1756959Y173713D01*
G03X1757312Y173567I353J354D01*
G01X1760199D01*
X1760724Y174092D01*
X1762028D01*
G01X1756650Y170742D02*
Y171868D01*
G02X1756796Y172221I500J0D01*
G01X1756846Y172271D01*
G02X1757199Y172417I353J-354D01*
G01X1760199D01*
X1760724Y171892D01*
X1762028D01*
G01X1785728Y628248D02*
X1780474D01*
X1779974Y627748D01*
Y626823D01*
X1779474Y626323D01*
X1741557D01*
X1741032Y626848D01*
X1739228D01*
G01X1785728Y623248D02*
X1780474D01*
X1779974Y623748D01*
Y624673D01*
X1779474Y625173D01*
X1741557D01*
X1741032Y624648D01*
X1739228D01*
G01X1785728Y638248D02*
X1780474D01*
X1779974Y638748D01*
Y639673D01*
X1779474Y640173D01*
X1725934D01*
G03X1725350Y639589I0J-584D01*
G01Y638498D01*
G01X1785728Y643248D02*
X1780596D01*
X1779974Y642626D01*
Y641891D01*
X1779406Y641323D01*
X1725934D01*
G02X1725350Y641907I0J584D01*
G01Y642998D01*
G01X1737028Y626848D02*
X1735724D01*
X1735199Y626323D01*
X1732244D01*
G02X1731891Y626469I0J500D01*
G01X1731796Y626564D01*
G02X1731650Y626917I354J353D01*
G01Y627998D01*
G01X1737028Y624648D02*
X1735724D01*
X1735199Y625173D01*
X1732204D01*
G03X1731851Y625027I0J-500D01*
G01X1731796Y624972D01*
G03X1731650Y624619I354J-353D01*
G01Y623498D01*
G01X1764228Y1079604D02*
X1766132D01*
X1766657Y1079079D01*
X1779474D01*
X1779974Y1079579D01*
Y1080504D01*
X1780474Y1081004D01*
X1785728D01*
G01X1764228Y1077404D02*
X1766132D01*
X1766657Y1077929D01*
X1779474D01*
X1779974Y1077429D01*
Y1076504D01*
X1780474Y1076004D01*
X1785728D01*
G01X1756650Y1080754D02*
Y1079677D01*
G03X1756796Y1079324I500J0D01*
G01X1756895Y1079225D01*
G03X1757248Y1079079I353J354D01*
G01X1760199D01*
X1760724Y1079604D01*
X1762028D01*
G01X1756650Y1076254D02*
Y1077276D01*
G02X1756796Y1077629I500J0D01*
G01X1756950Y1077783D01*
G02X1757303Y1077929I353J-354D01*
G01X1760199D01*
X1760724Y1077404D01*
X1762028D01*
G01X1775350Y185742D02*
Y186787D01*
G02X1775980Y187417I630J0D01*
G01X1779474D01*
X1779974Y186917D01*
Y185992D01*
X1780474Y185492D01*
X1785728D01*
G01X1775350Y190242D02*
Y189197D01*
G03X1775980Y188567I630J0D01*
G01X1779418D01*
X1779974Y189123D01*
Y189772D01*
X1780694Y190492D01*
X1785728D01*
G01X1775350Y1091254D02*
Y1092298D01*
G02X1775981Y1092929I631J0D01*
G01X1779474D01*
X1779974Y1092429D01*
Y1091504D01*
X1780474Y1091004D01*
X1785728D01*
G01X1775350Y1095754D02*
Y1094710D01*
G03X1775981Y1094079I631J0D01*
G01X1779336D01*
X1779974Y1094717D01*
Y1095234D01*
X1780744Y1096004D01*
X1785728D01*
G01X1888441Y174092D02*
X1890445D01*
X1890970Y173567D01*
X1903687D01*
X1904187Y174067D01*
Y174992D01*
X1904687Y175492D01*
X1909941D01*
G01X1888441Y171892D02*
X1890445D01*
X1890970Y172417D01*
X1903687D01*
X1904187Y171917D01*
Y170992D01*
X1904687Y170492D01*
X1909941D01*
G01X1899563Y185742D02*
Y186804D01*
G02X1900176Y187417I613J0D01*
G01X1903687D01*
X1904187Y186917D01*
Y185992D01*
X1904687Y185492D01*
X1909941D01*
G01Y190492D02*
X1904921D01*
X1904187Y189758D01*
Y189099D01*
X1903655Y188567D01*
X1900176D01*
G02X1899563Y189180I0J613D01*
G01Y190242D01*
G01X1880863Y175242D02*
Y174174D01*
G03X1881009Y173821I500J0D01*
G01X1881117Y173713D01*
G03X1881470Y173567I353J354D01*
G01X1884412D01*
X1884937Y174092D01*
X1886241D01*
G01X1880863Y170742D02*
Y171871D01*
G02X1881009Y172224I500J0D01*
G01X1881056Y172271D01*
G02X1881409Y172417I353J-354D01*
G01X1884412D01*
X1884937Y171892D01*
X1886241D01*
G01X1888441Y626848D02*
X1890745D01*
X1891270Y626323D01*
X1903687D01*
X1904187Y626823D01*
Y627748D01*
X1904687Y628248D01*
X1909941D01*
G01X1888441Y624648D02*
X1890745D01*
X1891270Y625173D01*
X1903687D01*
X1904187Y624673D01*
Y623748D01*
X1904687Y623248D01*
X1909941D01*
G01X1899563Y638498D02*
Y639505D01*
G02X1900231Y640173I668J0D01*
G01X1903687D01*
X1904187Y639673D01*
Y638748D01*
X1904687Y638248D01*
X1909941D01*
G01X1899563Y642998D02*
Y641991D01*
G03X1900231Y641323I668J0D01*
G01X1903549D01*
X1904187Y641961D01*
Y642618D01*
X1904817Y643248D01*
X1909941D01*
G01X1880863Y627998D02*
Y626862D01*
G03X1881009Y626509I500J0D01*
G01X1881049Y626469D01*
G03X1881402Y626323I353J354D01*
G01X1884412D01*
X1884937Y626848D01*
X1886241D01*
G01X1880863Y623498D02*
Y624562D01*
G02X1881009Y624915I500J0D01*
G01X1881121Y625027D01*
G02X1881474Y625173I353J-354D01*
G01X1884412D01*
X1884937Y624648D01*
X1886241D01*
G01X1888441Y1079604D02*
X1890545D01*
X1891070Y1079079D01*
X1903687D01*
X1904187Y1079579D01*
Y1080504D01*
X1904687Y1081004D01*
X1909941D01*
G01X1888441Y1077404D02*
X1890545D01*
X1891070Y1077929D01*
X1903687D01*
X1904187Y1077429D01*
Y1076504D01*
X1904687Y1076004D01*
X1909941D01*
G01X1880863Y1080754D02*
Y1079664D01*
G03X1881009Y1079311I500J0D01*
G01X1881095Y1079225D01*
G03X1881448Y1079079I353J354D01*
G01X1884412D01*
X1884937Y1079604D01*
X1886241D01*
G01X1880863Y1076254D02*
Y1077381D01*
G02X1881009Y1077734I500J0D01*
G01X1881058Y1077783D01*
G02X1881411Y1077929I353J-354D01*
G01X1884412D01*
X1884937Y1077404D01*
X1886241D01*
G01X1899563Y1091254D02*
Y1092428D01*
G02X1900064Y1092929I501J0D01*
G01X1903687D01*
X1904187Y1092429D01*
Y1091504D01*
X1904687Y1091004D01*
X1909941D01*
G01X1899563Y1095754D02*
Y1094580D01*
G03X1900064Y1094079I501J0D01*
G01X1903595D01*
X1904187Y1094671D01*
Y1095280D01*
X1904911Y1096004D01*
X1909941D01*
G54D102*
X1007010Y1521346D03*
Y1553748D03*
G54D111*
X1500540Y528169D03*
X1502540Y533769D03*
X1498540D03*
G54D121*
G01X954921Y427165D02*
X952081Y425744D01*
G02X951329Y425868I-290J581D01*
G01Y425897D01*
X950579Y426930D01*
G02Y428144I607J607D01*
G01X953829Y431394D01*
X955710D01*
X958023Y429866D01*
Y429864D01*
X958024Y429860D01*
X963747Y404601D01*
X963408Y404063D01*
X963839Y402161D01*
X964377Y401822D01*
X964808Y399920D01*
X964468Y399382D01*
X964899Y397480D01*
X965438Y397140D01*
X965869Y395239D01*
X965529Y394700D01*
X965960Y392799D01*
X966498Y392459D01*
X966928Y390561D01*
X966929Y390557D01*
X966590Y390019D01*
X967021Y388117D01*
X967559Y387778D01*
X968032Y385689D01*
X965901Y378493D01*
X964346Y377226D01*
X962531Y376514D01*
X961947Y376769D01*
X960132Y376057D01*
X959877Y375474D01*
X958062Y374763D01*
X957478Y375017D01*
X955663Y374306D01*
X955408Y373722D01*
X953593Y373011D01*
X953009Y373265D01*
X951194Y372554D01*
X950939Y371971D01*
X949124Y371259D01*
X948541Y371514D01*
X946725Y370802D01*
X946470Y370219D01*
X928966Y363357D01*
X928383Y363612D01*
X926567Y362900D01*
X926313Y362317D01*
X924497Y361605D01*
X923914Y361860D01*
X922098Y361148D01*
X921844Y360565D01*
X920028Y359853D01*
X919445Y360108D01*
X917629Y359396D01*
X917375Y358813D01*
X913964Y357476D01*
X912916Y355832D01*
X912295Y355694D01*
X911246Y354050D01*
X911384Y353428D01*
X910336Y351784D01*
X909715Y351646D01*
X908666Y350002D01*
X908804Y349381D01*
X907756Y347736D01*
X907135Y347599D01*
X906087Y345954D01*
X906224Y345333D01*
X905176Y343689D01*
X904555Y343551D01*
X903507Y341907D01*
X903644Y341285D01*
X892894Y324420D01*
X892273Y324282D01*
X891225Y322638D01*
X891363Y322017D01*
X890314Y320372D01*
X889693Y320235D01*
X888645Y318590D01*
X888783Y317969D01*
X820379Y210647D01*
X820378D01*
X804837Y186263D01*
X789297Y161882D01*
X737925Y128521D01*
X718152Y124629D01*
X666225Y135220D01*
X616849Y125505D01*
X566232Y135830D01*
X562261Y135049D01*
X536039Y129890D01*
X526127Y127940D01*
X495102Y134268D01*
X463222Y127994D01*
X461039Y124978D01*
Y117394D01*
X461040Y117393D01*
Y115620D01*
G02X459578Y114158I-1462J0D01*
G01X458571D01*
G02X458071Y114658I0J500D01*
G01Y116339D01*
G01X947047Y423228D02*
X949889Y424650D01*
G03X950179Y425522I-291J581D01*
G01X949685Y426201D01*
G02X949764Y428957I1500J1336D01*
G01X949765D01*
X953352Y432544D01*
X956056D01*
X959043Y430571D01*
X965930Y400176D01*
X965931Y400172D01*
X966560Y397397D01*
X966561Y397393D01*
X966991Y395495D01*
X966992Y395491D01*
X967621Y392716D01*
X967622Y392712D01*
X968052Y390814D01*
X968053Y390810D01*
X968577Y388497D01*
X968576D01*
X969220Y385650D01*
X966903Y377826D01*
X964934Y376220D01*
X914733Y356541D01*
X790133Y161053D01*
X738365Y127435D01*
X718148Y123456D01*
X666221Y134047D01*
X616845Y124332D01*
X566228Y134657D01*
X526123Y126767D01*
X495098Y133095D01*
X463888Y126952D01*
X463889D01*
X462190Y124606D01*
Y115620D01*
G02X459578Y113008I-2612J0D01*
G01X458571D01*
G03X458071Y112508I0J-500D01*
G01Y110827D01*
G01X937205Y541338D02*
X934363Y542760D01*
G02X934073Y543632I291J581D01*
G01Y543633D01*
X934699Y544494D01*
G02X935104Y544700I404J-294D01*
G01X948576D01*
X952513Y540763D01*
X957736D01*
X960106Y538393D01*
X963392Y523958D01*
X963023Y523372D01*
X963456Y521470D01*
X964043Y521101D01*
X964475Y519200D01*
X964106Y518613D01*
X964539Y516712D01*
X965126Y516343D01*
X965559Y514442D01*
X965190Y513855D01*
X965622Y511954D01*
X966209Y511585D01*
X986795Y421156D01*
X973743Y376661D01*
X968021Y372002D01*
X920495Y353242D01*
X920344Y352895D01*
X793755Y157348D01*
X739774Y122289D01*
X738839Y122106D01*
Y122105D01*
X717313Y117867D01*
X665284Y128478D01*
X616875Y118956D01*
X566454Y129241D01*
X562707Y128503D01*
X560251Y125106D01*
Y119557D01*
G03X562863Y116945I2612J0D01*
G01X563870D01*
G02X564370Y116445I0J-500D01*
G01Y114764D01*
G01X929331Y545275D02*
X932171Y543854D01*
G03X932923Y543978I290J581D01*
G01Y544007D01*
X933768Y545171D01*
G02X935104Y545850I1334J-971D01*
G01X949053D01*
X952990Y541913D01*
X958213D01*
X961154Y538972D01*
X987983Y421119D01*
X974747Y375994D01*
X968609Y370997D01*
X921361Y352347D01*
X794587Y156517D01*
X740214Y121203D01*
X717309Y116694D01*
X665280Y127305D01*
X616871Y117783D01*
X566450Y128068D01*
X563374Y127462D01*
X561401Y124733D01*
Y119557D01*
G03X562863Y118095I1462J0D01*
G01X563870D01*
G03X564370Y118595I0J500D01*
G01Y120276D01*
G01X1113530Y1038198D02*
X1115211D01*
G02X1115711Y1037698I0J-500D01*
G01Y1036015D01*
G02X1114925Y1035229I-786J0D01*
G01X1086921D01*
X1034186Y1000508D01*
X860108Y711204D01*
X838775Y625863D01*
X856069Y540886D01*
X892070Y474547D01*
X913799Y461609D01*
X913800D01*
X913956Y460992D01*
X915632Y459994D01*
X916248Y460151D01*
X917924Y459153D01*
X918080Y458536D01*
X919756Y457539D01*
X920373Y457695D01*
X926328Y454149D01*
X931397D01*
X933768Y451778D01*
G02Y450683I-548J-547D01*
G01X932923Y449519D01*
Y449490D01*
G02X932171Y449366I-462J457D01*
G01X929331Y450787D01*
G01X1119042Y1038198D02*
X1117361D01*
G03X1116861Y1037698I0J-500D01*
G01Y1036015D01*
G02X1114925Y1034079I-1936J0D01*
G01X1087266D01*
X1084756Y1032426D01*
X1061150Y1016884D01*
X1035037Y999691D01*
X861182Y710758D01*
X839954Y625837D01*
X857162Y541284D01*
X892931Y475374D01*
X926645Y455299D01*
X931874D01*
X934582Y452592D01*
G02X934658Y449950I-1361J-1361D01*
G01X934391Y449582D01*
X934073Y449145D01*
Y449144D01*
G03X934363Y448272I581J-291D01*
G01X937205Y446850D01*
G01X884069Y529987D02*
X886971Y532889D01*
X931084D01*
X935021Y528952D01*
X949590D01*
X950858Y530220D01*
X952298Y531659D01*
G03X952374Y534301I-1361J1361D01*
G01X952107Y534669D01*
X951789Y535106D01*
Y535107D01*
G02X952079Y535979I581J291D01*
G01X954921Y537401D01*
G01X884069Y536587D02*
X886617Y534039D01*
X931561D01*
X935498Y530102D01*
X949113D01*
X951484Y532473D01*
G03Y533568I-547J548D01*
G01X950639Y534732D01*
Y534761D01*
G03X949887Y534885I-462J-457D01*
G01X947047Y533464D01*
G01X929331Y71654D02*
X932171Y70233D01*
G03X932923Y70357I290J581D01*
G01Y70386D01*
X933768Y71550D01*
G02X935104Y72229I1334J-971D01*
G01X949114D01*
X953051Y76166D01*
X1002950D01*
X1005898Y79114D01*
G01X937205Y67717D02*
X934363Y69139D01*
G02X934073Y70011I291J581D01*
G01Y70012D01*
X934699Y70873D01*
G02X935104Y71079I404J-294D01*
G01X949591D01*
X953528Y75016D01*
X1003396D01*
X1005898Y72514D01*
G01X1072132Y64668D02*
X1074606Y67142D01*
X1099542D01*
G03X1100878Y67821I2J1650D01*
G01X1101723Y68985D01*
Y69014D01*
G02X1102475Y69138I462J-457D01*
G01X1105315Y67717D01*
G01X1072132Y70368D02*
X1074208Y68292D01*
X1099542D01*
G03X1099947Y68498I1J500D01*
G01X1100573Y69359D01*
Y69360D01*
G03X1100283Y70232I-581J291D01*
G01X1097441Y71654D01*
G01X1123031Y537401D02*
X1120189Y535979D01*
G03X1119899Y535107I291J-581D01*
G01Y535106D01*
X1120217Y534669D01*
X1120484Y534301D01*
G02X1120408Y531659I-1437J-1281D01*
G01X1118968Y530220D01*
X1117700Y528952D01*
X1102848D01*
X1098911Y532889D01*
X1072884D01*
X1071569Y534204D01*
X1054594D01*
X1051869Y531479D01*
G01X1115157Y533464D02*
X1117997Y534885D01*
G02X1118749Y534761I290J-581D01*
G01Y534732D01*
X1119594Y533568D01*
G02Y532473I-548J-547D01*
G01X1117223Y530102D01*
X1103325D01*
X1099388Y534039D01*
X1073361D01*
X1072046Y535354D01*
X1054594D01*
X1051869Y538079D01*
G01X1426575Y116339D02*
Y114658D01*
G02X1426075Y114158I-500J0D01*
G01X1425068D01*
G02X1423606Y115620I0J1462D01*
G01Y122812D01*
X1420125Y126293D01*
X1391085D01*
X1341642Y145885D01*
X1324806Y148369D01*
X1310578Y142356D01*
X1299094Y127349D01*
X1266665D01*
X1254885Y134247D01*
X1209174Y206042D01*
X1199010Y250891D01*
X1208128Y298555D01*
X1201396Y328270D01*
X1159185Y386569D01*
X1159285Y387197D01*
X1158142Y388776D01*
X1157513Y388877D01*
X1156370Y390456D01*
X1156470Y391085D01*
X1155327Y392664D01*
X1154698Y392765D01*
X1153555Y394344D01*
X1153655Y394973D01*
X1152512Y396552D01*
X1151883Y396653D01*
X1150740Y398232D01*
X1150840Y398861D01*
X1149697Y400440D01*
X1149068Y400541D01*
X1139290Y414045D01*
X1125212Y423803D01*
X1120930D01*
G02X1120525Y424009I-1J500D01*
G01X1119899Y424870D01*
Y424871D01*
G02X1120189Y425743I581J291D01*
G01X1123031Y427165D01*
G01X1426575Y110827D02*
Y112508D01*
G03X1426075Y113008I-500J0D01*
G01X1425068D01*
G02X1422456Y115620I0J2612D01*
G01Y122335D01*
X1419648Y125143D01*
X1390865D01*
X1341342Y144766D01*
X1333151Y145975D01*
X1324957Y147184D01*
X1311306Y141415D01*
X1299663Y126199D01*
X1266353D01*
X1254064Y133395D01*
X1208096Y205593D01*
X1202970Y228212D01*
X1197835Y250871D01*
X1200912Y266956D01*
X1203943Y282804D01*
X1206953Y298535D01*
X1200326Y327786D01*
X1138474Y413211D01*
X1138089Y413476D01*
X1137725Y413729D01*
X1137705Y413743D01*
X1124852Y422653D01*
X1120930D01*
G02X1119594Y423332I-2J1650D01*
G01X1118749Y424496D01*
Y424525D01*
G03X1117997Y424649I-462J-457D01*
G01X1115157Y423228D01*
G01X1532874Y120276D02*
Y118595D01*
G02X1532374Y118095I-500J0D01*
G01X1531367D01*
G02X1529905Y119557I0J1462D01*
G01Y124147D01*
X1521547Y132505D01*
X1393719D01*
X1344301Y152082D01*
X1339558Y152931D01*
X1339557Y152932D01*
X1325344Y155475D01*
X1306727Y148004D01*
X1295741Y133667D01*
X1268664D01*
X1259231Y139584D01*
X1215496Y208236D01*
X1205572Y252019D01*
X1214540Y298898D01*
X1172666Y483713D01*
X1172668Y483714D01*
X1172667D01*
X1172665Y483719D01*
X1133933Y537209D01*
X1127147Y541913D01*
X1121276D01*
X1117339Y545850D01*
X1103233D01*
G03X1101861Y545150I0J-1695D01*
G01X1101557Y544730D01*
X1101556Y544729D01*
X1101554Y544726D01*
X1101504Y544657D01*
X1101502Y544654D01*
X1101033Y544007D01*
Y543978D01*
G02X1100281Y543854I-462J457D01*
G01X1097441Y545275D01*
G01X1532874Y114764D02*
Y116445D01*
G03X1532374Y116945I-500J0D01*
G01X1531367D01*
G02X1528755Y119557I0J2612D01*
G01Y123670D01*
X1521070Y131355D01*
X1393499D01*
X1343985Y150970D01*
X1334725Y152627D01*
X1325466Y154284D01*
X1307448Y147054D01*
X1296309Y132517D01*
X1268333D01*
X1258400Y138747D01*
X1247328Y156127D01*
X1236394Y173291D01*
X1214418Y207786D01*
X1206931Y240819D01*
X1204397Y251999D01*
X1213365Y298878D01*
X1171595Y483235D01*
X1144189Y521083D01*
X1143617Y521175D01*
X1142473Y522754D01*
X1142565Y523327D01*
X1141421Y524906D01*
X1140848Y524998D01*
X1139705Y526577D01*
X1139796Y527150D01*
X1138653Y528729D01*
X1138080Y528821D01*
X1136936Y530400D01*
X1137028Y530973D01*
X1135884Y532552D01*
X1135312Y532644D01*
X1134168Y534223D01*
X1134260Y534796D01*
X1133116Y536375D01*
X1126787Y540763D01*
X1120799D01*
X1116862Y544700D01*
X1103233D01*
G03X1102793Y544475I1J-544D01*
G01X1102490Y544056D01*
X1102488Y544053D01*
X1102436Y543981D01*
X1102434Y543980D01*
X1102183Y543634D01*
Y543632D01*
G03X1102473Y542760I581J-291D01*
G01X1105315Y541338D01*
G54D10*
X15157Y21653D03*
Y474409D03*
X904921Y-25591D03*
Y564960D03*
X975787Y-25590D03*
X975786Y564960D03*
X1104527Y1630792D03*
X1894685Y21654D03*
X1894684Y474409D03*
G54D112*
X1493300Y530900D03*
G54D103*
X1065716Y1546420D03*
X1094000D03*
G54D122*
G01X27176Y667518D02*
X22046D01*
X21999Y667471D01*
G01X22947Y674933D02*
X21999Y673985D01*
Y667471D01*
G01X27543Y692869D02*
X22831D01*
X22600Y693100D01*
G01D02*
X22366Y693334D01*
Y699336D01*
X23314Y700284D01*
G01X26756Y1120485D02*
X22041D01*
X21626Y1120900D01*
G01D02*
X21500Y1121026D01*
Y1126480D01*
X22920Y1127900D01*
G01X27123Y1145836D02*
X22464D01*
X22100Y1146200D01*
G01D02*
X21946Y1146354D01*
Y1152303D01*
X22894Y1153251D01*
G01X59937Y187411D02*
X65687D01*
X66437Y188161D01*
G01X59937Y187411D02*
X60187Y187661D01*
Y194161D01*
G01Y210561D02*
Y214661D01*
G01Y194161D02*
Y210561D01*
G01X67987Y209361D02*
Y215711D01*
X73937Y221661D01*
Y227661D01*
G01X67987Y205261D02*
Y209361D01*
G01Y205261D02*
Y199261D01*
G01D02*
X72387Y194861D01*
X77877D01*
G01X60087Y179561D02*
X59937Y179711D01*
Y183911D01*
G01X66437Y179161D02*
X60487D01*
X60087Y179561D01*
G01X72837Y177911D02*
X70187D01*
X68937Y179161D01*
X66437D01*
G01X60187Y214661D02*
X65937Y220411D01*
Y225661D01*
G01X72049Y424200D02*
Y374529D01*
G01X68109Y453300D02*
Y374529D01*
G01X43100Y464100D02*
X55100Y452100D01*
Y368700D01*
X63300Y360500D01*
X68800D01*
X71200Y362900D01*
Y365630D01*
X72049Y366479D01*
Y368779D01*
G01X57963Y457439D02*
Y368949D01*
X64212Y362700D01*
X67888D01*
X69000Y363812D01*
Y365588D01*
X68109Y366479D01*
Y368779D01*
G01X72500Y498000D02*
X72049Y497549D01*
Y424200D01*
G01X67500Y498000D02*
X68109Y497391D01*
Y453300D01*
G01X43728Y499434D02*
Y491600D01*
X43000Y490872D01*
Y467488D01*
X43100Y467388D01*
Y464100D01*
G01X57963Y499397D02*
Y457439D01*
G01X47603Y506934D02*
Y513012D01*
X47607Y513016D01*
G01Y520462D02*
Y513016D01*
G01Y520462D02*
Y527511D01*
G01X61834Y520466D02*
Y527515D01*
G01Y520466D02*
Y513020D01*
G01X61838Y506897D02*
Y512716D01*
X61834Y512720D01*
Y513020D01*
G01X60187Y646917D02*
Y663317D01*
G01Y646917D02*
Y640417D01*
X59937Y640167D01*
G01D02*
X65687D01*
X66437Y640917D01*
G01X77877Y647617D02*
X71987D01*
X67987Y651617D01*
Y651900D01*
G01X66437Y631917D02*
X60487D01*
X60087Y632317D01*
G01X72837Y630667D02*
X70187D01*
X68937Y631917D01*
X66437D01*
G01X60087Y632317D02*
X59937Y632467D01*
Y636667D01*
G01X60187Y667417D02*
X65937Y673167D01*
Y678417D01*
G01X60187Y663317D02*
Y667417D01*
G01X67987Y651900D02*
Y657917D01*
G01Y662017D02*
Y668467D01*
X73937Y674417D01*
Y680417D01*
G01X67987Y657917D02*
Y662017D01*
G01X27143Y663071D02*
X27176Y663104D01*
Y667518D01*
G01X27543Y692869D02*
X27510Y692836D01*
Y688422D01*
G01X26822Y682433D02*
X32333D01*
X39100Y689200D01*
Y701400D01*
X31800Y708700D01*
Y762100D01*
X33900Y764200D01*
G01X27189Y707784D02*
Y709689D01*
X28500Y711000D01*
Y762156D01*
X28400Y762256D01*
Y763600D01*
G01X72049Y821534D02*
Y805149D01*
X33900Y767000D01*
Y764200D01*
G01X68109Y821534D02*
Y804387D01*
X28400Y764678D01*
Y763600D01*
G01X72049Y827284D02*
Y923100D01*
G01X68109Y827284D02*
Y932900D01*
G01X72500Y950755D02*
X72049Y950304D01*
Y923100D01*
G01X67500Y950755D02*
X68109Y950146D01*
Y932900D01*
G01X26756Y1120485D02*
X26723Y1120452D01*
Y1116038D01*
G01X60187Y1099673D02*
Y1116073D01*
G01Y1099673D02*
Y1095950D01*
X59937Y1095700D01*
Y1092923D01*
G01X60187Y1120173D02*
X65937Y1125923D01*
Y1131173D01*
G01X59937Y1092923D02*
X62740D01*
X63490Y1093673D01*
X66437D01*
G01X60187Y1116073D02*
Y1120173D01*
G01X68100Y1104973D02*
X67987D01*
Y1110673D01*
G01X77877Y1100373D02*
X71987D01*
X68100Y1104260D01*
Y1104973D01*
G01X67987Y1114773D02*
Y1121223D01*
X73937Y1127173D01*
Y1133173D01*
G01X67987Y1110673D02*
Y1114773D01*
G01X66437Y1084673D02*
X60387D01*
X59987Y1085073D01*
G01X72837Y1083423D02*
X70187D01*
X68937Y1084673D01*
X66437D01*
G01X59987Y1085073D02*
X59937Y1085123D01*
Y1089423D01*
G01X27090Y1141389D02*
X27123Y1141422D01*
Y1145836D01*
G01X26795Y1135400D02*
X30100D01*
X34196Y1139496D01*
Y1179000D01*
X52600Y1197404D01*
Y1201300D01*
G01X26769Y1160751D02*
Y1175271D01*
X48219Y1196721D01*
G01X25000Y1209100D02*
X27500Y1211600D01*
X29900D01*
X43837Y1225537D01*
Y1282512D01*
X50925Y1289600D01*
X67149D01*
X71209Y1285540D01*
Y1282628D01*
X72049Y1281788D01*
Y1280040D01*
G01X25000Y1201000D02*
Y1209100D01*
G01X68109Y1280040D02*
Y1281872D01*
X69009Y1282772D01*
Y1284628D01*
X66237Y1287400D01*
X51837D01*
X46037Y1281600D01*
Y1223737D01*
X30000Y1207700D01*
Y1206100D01*
G01Y1201000D02*
Y1206100D01*
G01X72049Y1274290D02*
Y1271749D01*
X71009Y1270709D01*
Y1239009D01*
X52600Y1220600D01*
Y1201300D01*
G01X48219Y1196721D02*
Y1220610D01*
X68809Y1241200D01*
Y1271090D01*
X68109Y1271790D01*
Y1274290D01*
G01X80437Y187461D02*
Y184611D01*
X77237Y181411D01*
G01D02*
X72837D01*
G01Y177911D02*
X81437D01*
G01D02*
X82997Y179471D01*
Y187461D01*
G01X88687Y181161D02*
Y176661D01*
G01Y181161D02*
Y183524D01*
X88300Y183911D01*
Y186300D01*
G01X80437Y194861D02*
Y192463D01*
X81739Y191161D01*
X88787D01*
G01X88300Y186300D02*
Y188600D01*
X88787Y189087D01*
Y191161D01*
G01X92187Y176661D02*
X95437D01*
G01X139187Y240661D02*
X139018Y240492D01*
X118209D01*
G01X139937Y270661D02*
X139768Y270492D01*
X118209D01*
G01X77237Y634167D02*
X72837D01*
G01X80437Y640217D02*
Y637367D01*
X77237Y634167D01*
G01X82997Y640217D02*
Y632227D01*
X81437Y630667D01*
G01D02*
X72837D01*
G01X87819Y638950D02*
Y636457D01*
X88687Y635589D01*
Y633917D01*
G01X80437Y647617D02*
Y644863D01*
X81383Y643917D01*
X88787D01*
G01D02*
Y641601D01*
X87819Y640633D01*
Y638950D01*
G01X88687Y633917D02*
Y629672D01*
X88646Y629631D01*
G01X85146D02*
Y625491D01*
G01D02*
Y621637D01*
G01X139187Y693417D02*
X139018Y693248D01*
X118209D01*
G01X139937Y723417D02*
X139768Y723248D01*
X118209D01*
G01X92287Y1082173D02*
X95537D01*
G01X88787D02*
Y1086673D01*
G01X77237Y1086923D02*
X72837D01*
G01X80437Y1092973D02*
Y1090123D01*
X77237Y1086923D01*
G01X82997Y1092973D02*
Y1084983D01*
X81437Y1083423D01*
G01D02*
X72837D01*
G01X88787Y1091673D02*
Y1096673D01*
G01D02*
X81937D01*
X80437Y1098173D01*
Y1100373D01*
G01X88787Y1086673D02*
Y1091673D01*
G01X140100Y1176000D02*
X140096Y1176004D01*
X118209D01*
G01X139187Y1146173D02*
X139018Y1146004D01*
X118209D01*
G01X139187Y244761D02*
Y240661D01*
G01Y244761D02*
Y250161D01*
G01D02*
Y255911D01*
X139437Y256161D01*
G01X145437D02*
Y261100D01*
G01D02*
Y265561D01*
G01X167982Y499392D02*
Y400510D01*
X167992Y400500D01*
G01D02*
Y375708D01*
X186100Y357600D01*
X190300D01*
X195412Y362712D01*
Y365630D01*
X196261Y366479D01*
Y368779D01*
G01X139187Y697517D02*
Y693417D01*
G01X139437Y708917D02*
X139187Y708667D01*
Y702917D01*
G01D02*
Y697517D01*
G01X145951Y725091D02*
Y723144D01*
X150253Y718842D01*
G01D02*
Y714355D01*
G01D02*
Y709713D01*
G01X145955Y740011D02*
X140409D01*
X140372Y739974D01*
G01D02*
Y745273D01*
X140364Y745281D01*
G01X145437Y717617D02*
Y713700D01*
G01D02*
Y708917D01*
G01X149826Y732591D02*
X155391D01*
X159600Y736800D01*
Y758942D01*
G01X140364Y745281D02*
Y749807D01*
G01X159600Y758942D02*
Y773800D01*
X196261Y810461D01*
Y821534D01*
G01X149830Y747511D02*
Y762815D01*
G01D02*
Y769515D01*
X192321Y812006D01*
Y821534D01*
G01X145437Y1165673D02*
Y1161673D01*
G01X150862Y1158233D02*
Y1152723D01*
G01X150869Y1163222D02*
Y1165439D01*
X145966Y1170342D01*
G01X150862Y1158233D02*
X150869Y1158240D01*
Y1163222D01*
G01X139437Y1161673D02*
X139187Y1161423D01*
Y1155673D01*
G01D02*
Y1150273D01*
G01D02*
Y1146173D01*
G01X149841Y1177842D02*
X155214D01*
X157800Y1180428D01*
Y1209818D01*
X165490Y1217508D01*
G01X140166Y1214922D02*
X170449Y1245205D01*
Y1284912D01*
X175137Y1289600D01*
X191361D01*
X195421Y1285540D01*
Y1282628D01*
X196261Y1281788D01*
Y1280040D01*
G01X140166Y1214922D02*
X135422Y1210178D01*
Y1201537D01*
G01X147538Y1213917D02*
X172649Y1239028D01*
Y1284000D01*
X176049Y1287400D01*
X190449D01*
X193221Y1284628D01*
Y1282772D01*
X192321Y1281872D01*
Y1280040D01*
G01X140422Y1201537D02*
Y1206801D01*
X147538Y1213917D01*
G01X146126Y1192724D02*
X144264Y1190862D01*
Y1186512D01*
G01D02*
X144556Y1186220D01*
X150432D01*
G01D02*
Y1184888D01*
X148311Y1182767D01*
G01X196261Y1274290D02*
Y1272261D01*
X195221Y1271221D01*
Y1250921D01*
X165490Y1221190D01*
Y1217508D01*
G01X192321Y1274290D02*
Y1272179D01*
X193021Y1271479D01*
Y1252467D01*
X154473Y1213919D01*
G01D02*
X150001Y1209447D01*
Y1200224D01*
G01X197049Y181411D02*
X201449D01*
G01D02*
X204649Y184611D01*
Y187461D01*
G01X184399Y210561D02*
Y214661D01*
G01Y210561D02*
Y194161D01*
G01X190649Y188161D02*
X189999Y187511D01*
X184149D01*
G01X184399Y194161D02*
X184149Y193911D01*
Y187511D01*
G01X192199Y209061D02*
Y215711D01*
X198149Y221661D01*
Y227661D01*
G01X192199Y204961D02*
Y209061D01*
G01X202089Y194861D02*
X196399D01*
X192199Y199061D01*
G01D02*
Y204961D01*
G01X197049Y177911D02*
X194399D01*
X193149Y179161D01*
X190649D01*
G01X197049Y177911D02*
X205649D01*
G01X184199Y179661D02*
X184699Y179161D01*
X190649D01*
G01X184149Y184011D02*
Y179711D01*
X184199Y179661D01*
G01X205649Y177911D02*
X207209Y179471D01*
Y187461D01*
G01X212999Y191161D02*
X205239D01*
X204649Y191751D01*
Y194861D01*
G01X212999Y181361D02*
Y176661D01*
G01Y181361D02*
Y186161D01*
G01D02*
Y191161D01*
G01X216499Y176661D02*
X219749D01*
G01X184399Y214661D02*
X190149Y220411D01*
Y225661D01*
G01X196261Y374529D02*
Y397500D01*
G01D02*
Y497549D01*
X196712Y498000D01*
G01X192321Y374529D02*
Y406000D01*
G01Y368779D02*
Y362841D01*
X189617Y360137D01*
X187205D01*
X182217Y365125D01*
Y399500D01*
G01D02*
Y499355D01*
G01X192321Y406000D02*
Y497391D01*
X191712Y498000D01*
G01X171861Y512874D02*
X171857Y512870D01*
Y506892D01*
G01X171861Y520420D02*
Y512874D01*
G01Y520420D02*
Y527469D01*
G01X186088Y520424D02*
Y512878D01*
G01D02*
X186092Y512874D01*
Y506855D01*
G01X186088Y520424D02*
Y527473D01*
G01X201052Y620496D02*
Y624401D01*
X202174Y625523D01*
G01X204849Y631217D02*
Y628198D01*
X202174Y625523D01*
G01X194749Y630417D02*
X193999Y629667D01*
X188649D01*
G01X196360Y638400D02*
X188649Y630689D01*
Y629667D01*
G01X190149Y667589D02*
Y650000D01*
X196360Y643789D01*
Y638400D01*
G01X202750Y650000D02*
Y644000D01*
G01X202289Y638617D02*
Y641700D01*
X202750Y642161D01*
Y644000D01*
G01X188649Y621417D02*
Y626167D01*
G01X194749Y621417D02*
X188649D01*
G01X204552Y620496D02*
X202274Y618218D01*
X199279D01*
X196080Y621417D01*
X194749D01*
G01X204552Y620496D02*
X207409Y623353D01*
Y625539D01*
G01D02*
Y631217D01*
G01X212999Y623417D02*
Y618917D01*
G01Y628417D02*
Y623417D01*
G01Y628417D02*
Y633417D01*
G01X204849Y638617D02*
Y635747D01*
X205720Y634876D01*
X209172D01*
X210631Y633417D01*
X212999D01*
G01X216499Y618917D02*
X219749D01*
G01X190149Y671689D02*
Y667589D01*
G01Y678417D02*
Y671689D01*
G01X198000Y650000D02*
X195310D01*
X192870Y652440D01*
Y663830D01*
X198149Y669109D01*
Y680417D01*
G01X198000Y650000D02*
X202750D01*
G01X202534Y917700D02*
Y840534D01*
X196261Y834261D01*
Y827284D01*
G01X192321D02*
Y840521D01*
X198713Y846913D01*
Y917713D01*
X206200Y925200D01*
G01X221712Y950555D02*
X220400Y949243D01*
Y935566D01*
X202534Y917700D01*
G01X206200Y925200D02*
X217560Y936560D01*
Y949707D01*
X216712Y950555D01*
G01X212999Y1082173D02*
Y1086873D01*
G01X216499Y1082173D02*
X219749D01*
G01X201449Y1086923D02*
X197449D01*
G01X204649Y1092973D02*
Y1090123D01*
X201449Y1086923D01*
G01X190651Y1095035D02*
X190410Y1094794D01*
X188738D01*
X184489Y1099043D01*
G01X190199Y1119573D02*
Y1117399D01*
X189400Y1116600D01*
X187500D01*
X183793Y1112893D01*
Y1104177D01*
G01X190149Y1131173D02*
X190199Y1131123D01*
Y1123673D01*
G01D02*
Y1119573D01*
G01X183793Y1104177D02*
Y1099739D01*
X184489Y1099043D01*
G01X202089Y1100373D02*
X195527D01*
X194100Y1101800D01*
G01X198149Y1133173D02*
Y1121749D01*
X191899Y1115499D01*
Y1110473D01*
G01D02*
Y1106373D01*
G01D02*
Y1104001D01*
X194100Y1101800D01*
G01X207209Y1092973D02*
Y1084983D01*
X205649Y1083423D01*
G01D02*
X197449D01*
G01X190651Y1086035D02*
X192597D01*
X195209Y1083423D01*
X197449D01*
G01X190651Y1086035D02*
X187801D01*
X184477Y1089359D01*
Y1094839D01*
G01X180989Y1099043D02*
Y1098327D01*
X184477Y1094839D01*
G01X212999Y1091673D02*
Y1096673D01*
G01D02*
X205627D01*
X204649Y1097651D01*
Y1100373D01*
G01X212999Y1086873D02*
Y1091673D01*
G01X263399Y240661D02*
X263230Y240492D01*
X242421D01*
G01X263399Y244761D02*
Y240661D01*
G01Y244761D02*
Y250161D01*
G01D02*
Y255911D01*
X263649Y256161D01*
G01X264149Y270661D02*
X263980Y270492D01*
X242421D01*
G01X263399Y693417D02*
X263230Y693248D01*
X242421D01*
G01X263399Y697517D02*
Y693417D01*
G01X264149Y723417D02*
X263980Y723248D01*
X242421D01*
G01X263649Y708917D02*
X263399Y708667D01*
Y702917D01*
G01D02*
Y697517D01*
G01X258600Y715500D02*
X266500D01*
X268071Y713929D01*
G01X270222Y739755D02*
X264776D01*
X264739Y739718D01*
G01D02*
X264400Y740057D01*
Y744694D01*
X264731Y745025D01*
G01D02*
Y749551D01*
G01X264200Y1176000D02*
X264196Y1176004D01*
X242421D01*
G01X263649Y1161673D02*
X263399Y1161423D01*
Y1155673D01*
G01D02*
Y1150273D01*
G01Y1146173D02*
X263230Y1146004D01*
X242421D01*
G01X263399Y1150273D02*
Y1146173D01*
G01X259594Y1201368D02*
Y1231695D01*
X284954Y1257055D01*
G01X264594Y1201368D02*
Y1233014D01*
X280888Y1249308D01*
G01X306955Y71929D02*
Y75155D01*
X308500Y76700D01*
X311000D01*
G01X303000Y73500D02*
X304571Y71929D01*
X306955D01*
G01X311000Y76700D02*
X315800D01*
X324841Y85741D01*
Y87515D01*
G01X318909Y125393D02*
X314372D01*
X314370Y125391D01*
G01X314439Y133669D02*
X314417Y133647D01*
Y129711D01*
X314370Y129664D01*
Y125391D01*
G01X308612Y210561D02*
Y214661D01*
G01Y210561D02*
Y194161D01*
G01X314862Y188161D02*
X312500D01*
X311850Y187511D01*
X308362D01*
G01X308612Y194161D02*
Y191300D01*
X308362Y191050D01*
Y187511D01*
G01X308412Y179661D02*
X308912Y179161D01*
X314862D01*
G01X308362Y184011D02*
Y179711D01*
X308412Y179661D01*
G01X308612Y214661D02*
X314362Y220411D01*
Y225661D01*
G01X269649Y260800D02*
Y256161D01*
G01Y266261D02*
Y260800D01*
G01X292153Y499392D02*
Y491834D01*
G01D02*
Y486059D01*
G01X306388Y499355D02*
Y491797D01*
G01D02*
Y486022D01*
G01X296032Y520420D02*
Y527469D01*
G01Y520420D02*
Y512874D01*
G01D02*
X296028Y512870D01*
Y506892D01*
G01X310259Y520424D02*
Y512878D01*
G01X310263Y506855D02*
Y512874D01*
X310259Y512878D01*
G01Y520424D02*
Y527473D01*
G01X308612Y646917D02*
Y663317D01*
G01X314862Y640917D02*
X312917D01*
X312267Y640267D01*
X308262D01*
G01D02*
Y643050D01*
X308612Y643400D01*
Y646917D01*
G01X314862Y631917D02*
X309012D01*
X308512Y632417D01*
G01D02*
X308262Y632667D01*
Y636767D01*
G01X308612Y667417D02*
X314362Y673167D01*
Y678417D01*
G01X308612Y663317D02*
Y667417D01*
G01X269649Y708917D02*
Y712351D01*
X268071Y713929D01*
G01X274520Y718586D02*
Y714099D01*
G01D02*
Y709457D01*
G01X270218Y724835D02*
Y723282D01*
X274520Y718980D01*
Y718586D01*
G01X274093Y732335D02*
X279035D01*
X283516Y736816D01*
Y768434D01*
G01X320474Y821534D02*
Y819374D01*
X319625Y818525D01*
Y816643D01*
X283516Y780534D01*
Y768434D01*
G01X274097Y762119D02*
Y773997D01*
X317425Y817325D01*
Y818343D01*
X316534Y819234D01*
Y821534D01*
G01X274097Y747255D02*
Y762119D01*
G01X308612Y1099673D02*
Y1116073D01*
G01X314862Y1093673D02*
X314212Y1093023D01*
X308262D01*
G01X308612Y1120173D02*
X314362Y1125923D01*
Y1131173D01*
G01X308262Y1093023D02*
Y1095350D01*
X308612Y1095700D01*
Y1099673D01*
G01Y1116073D02*
Y1120173D01*
G01X308262Y1089523D02*
Y1085323D01*
X308412Y1085173D01*
G01D02*
X308912Y1084673D01*
X314862D01*
G01X269649Y1165673D02*
Y1161673D01*
G01X270180Y1170342D02*
X275087Y1165435D01*
Y1163231D01*
G01X275076Y1158233D02*
X275087Y1158244D01*
Y1163231D01*
G01X275385Y1152596D02*
X275076Y1152905D01*
Y1158233D01*
G01X274055Y1177842D02*
X279442D01*
X283377Y1181777D01*
Y1222877D01*
X303376Y1242876D01*
Y1248708D01*
G01X268478Y1186512D02*
X268770Y1186220D01*
X274646D01*
G01X270340Y1192724D02*
X268478Y1190862D01*
Y1186512D01*
G01X274646Y1186220D02*
Y1184318D01*
X273243Y1182915D01*
G01X274215Y1200224D02*
Y1218615D01*
X299500Y1243900D01*
Y1248700D01*
X306015Y1255215D01*
Y1256575D01*
G01X320474Y1280040D02*
Y1281926D01*
X319634Y1282766D01*
Y1285540D01*
X315574Y1289600D01*
X311150D01*
X294662Y1273112D01*
Y1266763D01*
X284954Y1257055D01*
G01X316534Y1280040D02*
Y1282034D01*
X317434Y1282934D01*
Y1284628D01*
X314662Y1287400D01*
X312062D01*
X296862Y1272200D01*
Y1265282D01*
X280888Y1249308D01*
G01X320474Y1274290D02*
Y1272174D01*
X319434Y1271134D01*
Y1267434D01*
X308600Y1256600D01*
Y1253932D01*
X303376Y1248708D01*
G01X316534Y1274290D02*
Y1267646D01*
X306399Y1257511D01*
Y1256959D01*
X306015Y1256575D01*
G01X354100Y62100D02*
X352065Y64135D01*
X345471D01*
G01X361776Y70842D02*
X357629Y66695D01*
X353894D01*
G01D02*
X345471D01*
G01X335081Y109715D02*
Y104081D01*
G01X337641Y87515D02*
Y93610D01*
X339219Y95188D01*
G01X340201Y87515D02*
Y82702D01*
X339914Y82415D01*
G01X342761Y87515D02*
Y83982D01*
X344304Y82439D01*
G01X345321Y87515D02*
Y102400D01*
G01X347647Y95614D02*
Y95465D01*
X347881Y95231D01*
Y87515D01*
G01X353001Y109715D02*
Y114815D01*
G01X350441Y109715D02*
Y117541D01*
G01X347881Y109715D02*
Y114881D01*
G01X350441Y87515D02*
Y94813D01*
X351416Y95788D01*
G01X332521Y87515D02*
Y77579D01*
X335766Y74334D01*
G01D02*
X338971Y71129D01*
Y69255D01*
G01X337641Y109715D02*
Y114910D01*
G01X335081Y87515D02*
Y94471D01*
X334947Y94605D01*
G01X333741Y117531D02*
Y115220D01*
X332521Y114000D01*
Y109715D01*
G01X319171Y72855D02*
Y73771D01*
X322965Y77565D01*
G01X319205Y68379D02*
Y72821D01*
X319171Y72855D01*
G01X322965Y77565D02*
X327401Y82001D01*
Y87515D01*
G01X329529Y72845D02*
Y77300D01*
G01Y68345D02*
Y72845D01*
G01Y77300D02*
Y80029D01*
X329961Y80461D01*
Y87515D01*
G01X328321Y121849D02*
Y119700D01*
X329961Y118060D01*
Y115700D01*
G01D02*
Y109715D01*
G01X327401D02*
Y113806D01*
X325723Y115484D01*
X321122D01*
X319329Y117277D01*
G01X345321Y109715D02*
Y118921D01*
G01X333021Y121905D02*
Y119500D01*
X333741Y118780D01*
Y117531D01*
G01X337721Y121905D02*
X333021D01*
G01X319329Y117277D02*
X318909Y117697D01*
Y121893D01*
G01X323813Y133722D02*
Y125372D01*
G01D02*
X328298D01*
X328321Y125349D01*
G01X321362Y181411D02*
X325662D01*
G01D02*
X328862Y184611D01*
Y187461D01*
G01X316412Y209161D02*
X322362Y215111D01*
Y227661D01*
G01X316412Y205061D02*
Y209161D01*
G01X326302Y194861D02*
X320712D01*
X316412Y199161D01*
G01D02*
Y205061D01*
G01X321362Y177911D02*
X318612D01*
X317362Y179161D01*
X314862D01*
G01X321362Y177911D02*
X329862D01*
G01D02*
X331422Y179471D01*
Y187461D01*
G01X337212Y191161D02*
X330362D01*
X328862Y192661D01*
Y194861D01*
G01X337212Y181161D02*
Y176561D01*
X337312Y176461D01*
G01X337212Y191161D02*
Y186161D01*
G01D02*
Y181161D01*
G01X340812Y176461D02*
X344062D01*
G01X320474Y374529D02*
Y379474D01*
G01X316534Y374529D02*
Y379474D01*
G01X320474Y368779D02*
Y363234D01*
G01X316534Y368779D02*
Y363234D01*
G01X320925Y485385D02*
Y491367D01*
G01D02*
Y498000D01*
G01X315925Y491578D02*
Y498000D01*
G01Y485385D02*
Y491578D01*
G01X325662Y634167D02*
X321262D01*
G01X328862Y640217D02*
Y637367D01*
X325662Y634167D01*
G01X326302Y647617D02*
X320712D01*
X316412Y651917D01*
G01X331422Y640217D02*
Y632227D01*
X329862Y630667D01*
G01D02*
X321262D01*
G01D02*
X318612D01*
X317362Y631917D01*
X314862D01*
G01X336409Y639049D02*
Y636691D01*
X337212Y635888D01*
Y634017D01*
G01X336409Y639049D02*
Y640497D01*
X337212Y641300D01*
Y644017D01*
G01D02*
X330262D01*
X328862Y645417D01*
Y647617D01*
G01X337212Y634017D02*
X337182Y633987D01*
Y629429D01*
G01X333682D02*
Y625711D01*
G01D02*
Y621858D01*
G01X316412Y651917D02*
Y657717D01*
G01Y661917D02*
Y668467D01*
X322362Y674417D01*
Y680417D01*
G01X316412Y657717D02*
Y661917D01*
G01X320474Y827284D02*
Y832229D01*
G01X316534Y827284D02*
Y832229D01*
G01X315600Y933600D02*
Y935688D01*
X317400Y937488D01*
Y942020D01*
X315925Y943495D01*
G01X320925Y950755D02*
Y943284D01*
G01D02*
Y938140D01*
G01X315925Y950755D02*
Y943495D01*
G01X337312Y1082073D02*
Y1086773D01*
G01X340812Y1082073D02*
X344062D01*
G01X325662Y1086923D02*
X321262D01*
G01X328862Y1092973D02*
Y1090123D01*
X325662Y1086923D01*
G01X326302Y1100373D02*
X320375D01*
X317811Y1102937D01*
G01X322362Y1133173D02*
Y1127173D01*
X316412Y1121223D01*
Y1114773D01*
G01D02*
Y1110573D01*
G01D02*
Y1104336D01*
X317811Y1102937D01*
G01X331422Y1092973D02*
Y1084983D01*
X329862Y1083423D01*
G01D02*
X321262D01*
G01D02*
X318612D01*
X317362Y1084673D01*
X314862D01*
G01X337312Y1091773D02*
Y1096773D01*
G01D02*
X330262D01*
X328862Y1098173D01*
Y1100373D01*
G01X337312Y1086773D02*
Y1091773D01*
G01X371619Y84720D02*
X365162D01*
G01X377144D02*
X371619D01*
G01X370390Y95920D02*
X365162D01*
G01X377944Y95929D02*
X377935Y95920D01*
X370390D01*
G01X387612Y240661D02*
X387443Y240492D01*
X366634D01*
G01X387612Y244761D02*
Y240661D01*
G01X387862Y256161D02*
X387612Y255911D01*
Y251061D01*
G01D02*
Y244761D01*
G01X393862Y256161D02*
Y260538D01*
X391986Y262414D01*
G01X388362Y270661D02*
X388193Y270492D01*
X366634D01*
G01X391986Y262414D02*
X390600Y263800D01*
X386800D01*
G01X387612Y693417D02*
X387443Y693248D01*
X366634D01*
G01X387612Y697517D02*
Y693417D01*
G01X388362Y723417D02*
X388193Y723248D01*
X366634D01*
G01X387862Y708917D02*
X387612Y708667D01*
Y702917D01*
G01D02*
Y697517D01*
G01X393862Y714500D02*
Y708917D01*
G01Y719917D02*
Y714500D01*
G01X398677Y718514D02*
Y714027D01*
G01D02*
Y709385D01*
G01X394375Y724763D02*
Y722816D01*
X398677Y718514D01*
G01X388796Y739646D02*
X388788Y739654D01*
Y744953D01*
G01X394379Y739683D02*
X394342Y739646D01*
X388796D01*
G01X398250Y732263D02*
X404063D01*
X407714Y735914D01*
Y756056D01*
G01X388788Y744953D02*
Y749479D01*
G01X407714Y756056D02*
Y761291D01*
G01X398254Y747183D02*
Y757066D01*
G01D02*
Y763517D01*
G01X388200Y1176000D02*
X388196Y1176004D01*
X366634D01*
G01X387612Y1155673D02*
Y1150273D01*
G01X387662Y1161673D02*
X387612Y1161623D01*
Y1155673D01*
G01Y1146173D02*
X387443Y1146004D01*
X366634D01*
G01X387612Y1150273D02*
Y1146173D01*
G01X393662Y1161673D02*
X393679Y1161656D01*
Y1157480D01*
G01X389067Y1169780D02*
X388644Y1170203D01*
X383191D01*
G01X393698Y1166123D02*
X392724D01*
X389067Y1169780D01*
G01X394406Y1171545D02*
Y1166831D01*
X393698Y1166123D01*
G01X398281Y1179045D02*
X401096D01*
X409518Y1187467D01*
Y1211077D01*
X415430Y1216989D01*
G01X393193Y1220531D02*
X418875Y1246213D01*
Y1284912D01*
X423563Y1289600D01*
X439787D01*
X443847Y1285540D01*
Y1282628D01*
X444687Y1281788D01*
Y1280040D01*
G01X393193Y1220531D02*
X383849Y1211187D01*
Y1201242D01*
G01X391827Y1214891D02*
X421075Y1244139D01*
Y1284000D01*
X424475Y1287400D01*
X438875D01*
X441647Y1284628D01*
Y1282772D01*
X440747Y1281872D01*
Y1280040D01*
G01X391827Y1214891D02*
X388849Y1211913D01*
Y1201242D01*
G01X392977Y1185945D02*
X393911Y1185011D01*
X398903D01*
G01D02*
Y1188283D01*
X398527Y1188659D01*
G01X394511Y1192724D02*
X392977Y1191190D01*
Y1185945D01*
G01X403487Y1213549D02*
X398386Y1208448D01*
Y1200224D01*
G01X440747Y1274290D02*
Y1272353D01*
X441447Y1271653D01*
Y1267459D01*
X425200Y1251212D01*
Y1235262D01*
X403487Y1213549D01*
G01X445474Y181411D02*
X449874D01*
G01D02*
X453074Y184611D01*
Y187461D01*
G01X432824Y210561D02*
Y194161D01*
G01X439074Y188161D02*
X436961D01*
X436311Y187511D01*
X432574D01*
G01X432824Y210561D02*
Y214661D01*
G01Y194161D02*
Y189500D01*
X432574Y189250D01*
Y187511D01*
G01X440624Y209161D02*
Y215711D01*
X446574Y221661D01*
Y227661D01*
G01X440624Y205061D02*
Y209161D01*
G01X450514Y194861D02*
X444624D01*
X440624Y198861D01*
Y199100D01*
G01D02*
Y205061D01*
G01X432724Y179661D02*
X432574Y179811D01*
Y184011D01*
G01X439074Y179161D02*
X433224D01*
X432724Y179661D01*
G01X445474Y177911D02*
X442824D01*
X441574Y179161D01*
X439074D01*
G01X455634Y187461D02*
Y179471D01*
X454074Y177911D01*
G01D02*
X445474D01*
G01X461424Y191161D02*
X454574D01*
X453074Y192661D01*
Y194861D01*
G01X432824Y214661D02*
X438574Y220411D01*
Y225661D01*
G01X444687Y379474D02*
Y374529D01*
G01X440747Y379474D02*
Y374529D01*
G01X444687Y368779D02*
Y363234D01*
G01X440747Y368779D02*
Y363234D01*
G01X445138Y487743D02*
Y492299D01*
G01D02*
Y498000D01*
G01X440138Y492173D02*
Y498000D01*
G01Y487743D02*
Y492173D01*
G01X416303Y499355D02*
Y491797D01*
G01D02*
Y486022D01*
G01X430538Y485985D02*
Y491760D01*
G01Y499318D02*
Y491760D01*
G01X420182Y520383D02*
Y527432D01*
G01Y520383D02*
Y512837D01*
G01D02*
X420178Y512833D01*
Y506855D01*
G01X434409Y512841D02*
Y520387D01*
G01X434413Y506818D02*
X434409Y506822D01*
Y512841D01*
G01Y520387D02*
Y527436D01*
G01X449874Y634167D02*
X445474D01*
G01X453074Y640217D02*
Y637367D01*
X449874Y634167D01*
G01X432824Y646917D02*
Y663317D01*
G01Y646917D02*
Y642300D01*
X432574Y642050D01*
Y640167D01*
G01D02*
X435867D01*
X436617Y640917D01*
X439074D01*
G01X450514Y647617D02*
X444783D01*
X441600Y650800D01*
G01X455634Y640217D02*
Y632227D01*
X454074Y630667D01*
G01D02*
X445474D01*
G01X432574Y636667D02*
X432724Y636517D01*
Y632317D01*
G01X445474Y630667D02*
X442824D01*
X441574Y631917D01*
X439074D01*
G01X432724Y632317D02*
X435600D01*
X436000Y631917D01*
X439074D01*
G01X453074Y647617D02*
Y645417D01*
X454574Y643917D01*
X461424D01*
G01X457853Y625956D02*
Y622091D01*
G01Y629682D02*
Y625956D01*
G01X432824Y667417D02*
X438574Y673167D01*
Y678417D01*
G01X432824Y663317D02*
Y667417D01*
G01X441600Y650800D02*
X440724Y651676D01*
Y657817D01*
G01Y661917D02*
Y668567D01*
X446574Y674417D01*
Y680417D01*
G01X440724Y657817D02*
Y661917D01*
G01X444687Y827284D02*
Y832229D01*
G01X440747Y827284D02*
Y832229D01*
G01X444687Y821534D02*
Y816765D01*
G01X440747Y821534D02*
Y816765D01*
G01X445138Y950755D02*
Y943284D01*
G01D02*
Y938140D01*
G01X440138Y950755D02*
Y943495D01*
G01D02*
Y938140D01*
G01X443923Y1082726D02*
Y1091326D01*
G01X453473Y1081266D02*
X445383D01*
X443923Y1082726D01*
G01X452173Y1075476D02*
X457173D01*
G01X442473D02*
X447173D01*
G01X457173D02*
Y1082226D01*
X458773Y1083826D01*
X460873D01*
G01X447173Y1075476D02*
X452173D01*
G01X442473Y1071976D02*
Y1068726D01*
G01X447423Y1086926D02*
Y1091326D01*
G01X453473Y1083826D02*
X450523D01*
X447423Y1086926D01*
G01X453423Y1104326D02*
Y1098476D01*
X454173Y1097726D01*
G01X453424Y1112973D02*
Y1117073D01*
G01Y1112973D02*
Y1108601D01*
X453423Y1108600D01*
G01D02*
Y1104326D01*
G01X462100Y1130200D02*
Y1119900D01*
X459273Y1117073D01*
X453424D01*
G01X449923Y1104326D02*
X447800D01*
X447550Y1104076D01*
X445573D01*
G01X443923Y1091326D02*
Y1093976D01*
X445173Y1095226D01*
Y1097726D01*
G01X445573Y1104076D02*
X445173Y1103676D01*
Y1097726D01*
G01X444687Y1274290D02*
Y1272387D01*
X443647Y1271347D01*
Y1266547D01*
X427400Y1250300D01*
Y1228959D01*
X415430Y1216989D01*
G01X461424Y181161D02*
Y186161D01*
G01Y176461D02*
Y181161D01*
G01Y186161D02*
Y191161D01*
G01X464924Y176461D02*
Y175833D01*
X462200Y173109D01*
G01X511824Y240661D02*
X511655Y240492D01*
X490846D01*
G01X512574Y270661D02*
X512405Y270492D01*
X490846D01*
G01X536900Y528500D02*
X534369Y531031D01*
X497851D01*
X497351Y531531D01*
G01X536891Y532831D02*
X535781Y533941D01*
X502023D01*
X501023Y534941D01*
G01X461353Y629682D02*
X461424Y629753D01*
Y633917D01*
G01Y643917D02*
Y642475D01*
X460521Y641572D01*
Y638901D01*
G01X461424Y633917D02*
Y635346D01*
X460521Y636249D01*
Y638901D01*
G01X511824Y693417D02*
X511655Y693248D01*
X490846D01*
G01X512574Y723417D02*
X512405Y723248D01*
X490846D01*
G01X499824Y1141973D02*
Y1130923D01*
X499874Y1130873D01*
G01X508224Y1110573D02*
Y1105724D01*
X507200Y1104700D01*
X484100D01*
X478600Y1099200D01*
Y1090000D01*
X474986Y1086386D01*
X460873D01*
G01X505874Y1134773D02*
Y1130873D01*
G01X512500Y1176000D02*
X500500D01*
X500496Y1176004D01*
X490846D01*
G01Y1146004D02*
X499793D01*
X499824Y1145973D01*
G01D02*
Y1141973D01*
G01X511824Y244661D02*
Y240661D01*
G01Y244661D02*
Y250161D01*
G01D02*
Y255911D01*
X512074Y256161D01*
G01X518074D02*
Y260500D01*
G01D02*
Y269826D01*
X510700Y277200D01*
G01X539350Y487659D02*
Y491729D01*
G01D02*
Y498000D01*
G01X534350Y491940D02*
Y498000D01*
G01Y487659D02*
Y491940D01*
G01X510621Y499392D02*
Y491834D01*
G01D02*
Y486059D01*
G01X524856Y499355D02*
Y491797D01*
G01Y486022D02*
Y491797D01*
G01X521191Y545078D02*
X525579D01*
Y545031D01*
G01D02*
X525954Y544656D01*
X536871D01*
G01X521191Y545078D02*
Y546209D01*
X518700Y548700D01*
G01X553279Y523331D02*
Y520081D01*
G01D02*
X557279D01*
G01X514500Y520420D02*
Y512874D01*
G01Y520420D02*
Y524469D01*
G01Y512874D02*
X514496Y512870D01*
Y506892D01*
G01X528727Y520424D02*
Y524973D01*
G01Y512878D02*
X528731Y512874D01*
Y506855D01*
G01X528727Y520424D02*
Y512878D01*
G01X560729Y535941D02*
X558289D01*
X553279Y530931D01*
G01X545129Y528531D02*
X548731D01*
X551131Y530931D01*
X553279D01*
G01Y537910D02*
X561029D01*
G01X545129Y532831D02*
X548200D01*
X553279Y537910D01*
G01X541629Y528531D02*
X536931D01*
X536900Y528500D01*
G01X541629Y532831D02*
X536891D01*
G01X547629Y566531D02*
X552379D01*
G01X563889Y552881D02*
X562129D01*
X552379Y562631D01*
Y566531D01*
G01X511824Y697417D02*
Y693417D01*
G01X512074Y708917D02*
X511824Y708667D01*
Y702917D01*
G01D02*
Y697417D01*
G01X509996Y716996D02*
X513104D01*
X515025Y715075D01*
G01X518074Y708917D02*
Y712026D01*
X515025Y715075D01*
G01X518471Y725016D02*
Y723229D01*
X522773Y718927D01*
Y718767D01*
G01D02*
Y714280D01*
G01D02*
Y709638D01*
G01X512892Y739899D02*
X512884Y739907D01*
Y745206D01*
G01X518475Y739936D02*
X518438Y739899D01*
X512892D01*
G01X522346Y732516D02*
X527061D01*
X531810Y737265D01*
Y755383D01*
G01X512884Y745206D02*
Y749732D01*
G01X568899Y821534D02*
X567539Y820174D01*
Y817604D01*
X557043Y807108D01*
Y801467D01*
X531810Y776234D01*
Y755383D01*
G01X522350Y756393D02*
Y747436D01*
G01X564959Y821534D02*
Y817888D01*
X555018Y807947D01*
Y802306D01*
X522350Y769638D01*
Y756393D01*
G01X514474Y1133073D02*
Y1126674D01*
X509300Y1121500D01*
G01D02*
X508224Y1120424D01*
Y1114573D01*
G01D02*
Y1110573D01*
G01X518773Y1172616D02*
Y1167312D01*
X518975Y1167110D01*
G01X523001Y1163084D02*
Y1161058D01*
X524828Y1159231D01*
G01X518975Y1167110D02*
X523001Y1163084D01*
G01X544486Y1266486D02*
X508103Y1230103D01*
Y1201157D01*
G01X534733Y1252634D02*
X513103Y1231004D01*
Y1201157D01*
G01X517342Y1185651D02*
X521852D01*
X522867Y1186666D01*
G01D02*
Y1190284D01*
G01X518638Y1192682D02*
X517342Y1191386D01*
Y1185651D01*
G01X522648Y1180116D02*
X530116D01*
X531347Y1181347D01*
Y1216747D01*
X547100Y1232500D01*
G01X522513Y1200182D02*
Y1218526D01*
X554772Y1250785D01*
G01X568899Y1280040D02*
Y1282001D01*
X568059Y1282841D01*
Y1285540D01*
X566049Y1287550D01*
X561538D01*
X552843Y1278855D01*
Y1274843D01*
X544486Y1266486D01*
G01X564959Y1280040D02*
Y1281959D01*
X565859Y1282859D01*
Y1284628D01*
X565137Y1285350D01*
X562450D01*
X555043Y1277943D01*
Y1272944D01*
X534733Y1252634D01*
G01X547100Y1232500D02*
Y1239700D01*
X567859Y1260459D01*
Y1270950D01*
X568899Y1271990D01*
Y1274290D01*
G01X554772Y1250785D02*
X565659Y1261672D01*
Y1271090D01*
X564959Y1271790D01*
Y1274290D01*
G01X564370Y100591D02*
X661909D01*
X663500Y99000D01*
X819332D01*
X836500Y81832D01*
Y57000D01*
X844865Y48635D01*
X876290D01*
X878412Y46513D01*
Y36208D01*
X881378Y33242D01*
X905285D01*
X934223Y4304D01*
X1006664D01*
X1019638Y17278D01*
Y70462D01*
X966160Y123940D01*
Y325932D01*
X1011422Y371194D01*
Y545207D01*
G01X564370Y106103D02*
X565900Y107633D01*
X616903D01*
G01X569687Y181411D02*
X574087D01*
G01D02*
X577287Y184611D01*
Y187461D01*
G01X556787Y187411D02*
X562537D01*
X563287Y188161D01*
G01X556787Y187411D02*
X557037Y187661D01*
Y194161D01*
G01Y210661D02*
Y214661D01*
G01Y194161D02*
Y210661D01*
G01X564937Y204861D02*
Y198802D01*
X566160Y197579D01*
G01X564937Y209161D02*
Y204861D01*
G01X570787Y227661D02*
Y216387D01*
X564937Y210537D01*
Y209161D01*
G01X566160Y197579D02*
X568878Y194861D01*
X574727D01*
G01X579847Y187461D02*
Y179471D01*
X578287Y177911D01*
G01X556837Y179561D02*
X557237Y179161D01*
X563287D01*
G01X569687Y177911D02*
X567037D01*
X565787Y179161D01*
X563287D01*
G01X556787Y183911D02*
X556837Y183861D01*
Y179561D01*
G01X578287Y177911D02*
X569687D01*
G01X585637Y191161D02*
X578139D01*
X577287Y192013D01*
Y194861D01*
G01X585637Y181361D02*
Y186161D01*
G01Y176661D02*
Y181361D01*
G01Y186161D02*
Y191161D01*
G01X589137Y176661D02*
X590261D01*
X592767Y179167D01*
Y179277D01*
G01X557037Y214661D02*
X562787Y220411D01*
Y225661D01*
G01X568899Y379474D02*
Y374529D01*
G01X564959Y379474D02*
Y374529D01*
G01X568899Y368779D02*
Y363234D01*
G01X564959Y368779D02*
Y363234D01*
G01X580829Y549721D02*
X582305D01*
X592040Y559456D01*
X601979D01*
G01X580529Y547752D02*
X583200D01*
X591722Y556274D01*
X593779D01*
G01X569795Y533081D02*
Y524947D01*
X569347Y524499D01*
G01D02*
X568779Y523931D01*
Y520081D01*
G01D02*
X572229D01*
G01X564388Y526640D02*
X563279Y525531D01*
Y519131D01*
G01X565858Y533081D02*
Y528110D01*
X564388Y526640D01*
G01X557279Y520081D02*
X558229Y519131D01*
X563279D01*
G01X557279Y563581D02*
Y560621D01*
X559300Y558600D01*
X560500D01*
G01X565858Y552581D02*
Y556242D01*
X563500Y558600D01*
X560500D01*
G01X607460Y560774D02*
X606142Y559456D01*
X601979D01*
G01X607460Y556274D02*
X593779D01*
G01X574087Y634167D02*
X569687D01*
G01X577287Y640217D02*
Y637367D01*
X574087Y634167D01*
G01X557037Y646917D02*
Y663417D01*
G01Y646917D02*
Y640417D01*
X556787Y640167D01*
G01D02*
X562537D01*
X563287Y640917D01*
G01X574727Y647617D02*
X569237D01*
X564937Y651917D01*
G01X579847Y640217D02*
Y632227D01*
X578287Y630667D01*
G01D02*
X569687D01*
G01X556787Y636667D02*
X556937Y636517D01*
Y632317D01*
G01X569687Y630667D02*
X567037D01*
X565787Y631917D01*
X563287D01*
G01X556937Y632317D02*
X557337Y631917D01*
X563287D01*
G01X585637Y629417D02*
Y634017D01*
G01Y638917D02*
Y643917D01*
G01D02*
X578787D01*
X577287Y645417D01*
Y647617D01*
G01X585637Y634017D02*
Y638917D01*
G01X589137Y629417D02*
X592387D01*
G01X557037Y667417D02*
X562787Y673167D01*
Y678417D01*
G01X557037Y663417D02*
Y667417D01*
G01X564937Y651917D02*
Y657717D01*
G01Y661917D02*
Y668567D01*
X570787Y674417D01*
Y680417D01*
G01X564937Y657717D02*
Y661917D01*
G01X568899Y827284D02*
Y832229D01*
G01X564959Y827284D02*
Y832229D01*
G01X569350Y950755D02*
Y945784D01*
G01D02*
Y941640D01*
G01X564350Y945995D02*
Y941640D01*
G01Y950755D02*
Y945995D01*
G01X585637Y1086873D02*
Y1082173D01*
G01X589137D02*
X592387D01*
G01X574087Y1086923D02*
X569687D01*
G01X577287Y1092973D02*
Y1090123D01*
X574087Y1086923D01*
G01X557037Y1099673D02*
Y1116173D01*
G01Y1099673D02*
Y1097050D01*
X556787Y1096800D01*
Y1093023D01*
G01X557037Y1120173D02*
X562787Y1125923D01*
Y1131173D01*
G01X556787Y1093023D02*
X562637D01*
X563287Y1093673D01*
G01X557037Y1116173D02*
Y1120173D01*
G01X564837Y1104800D02*
Y1110473D01*
G01X574727Y1100373D02*
X568837D01*
X564837Y1104373D01*
Y1104800D01*
G01Y1114673D02*
Y1121223D01*
X570787Y1127173D01*
Y1133173D01*
G01X564837Y1110473D02*
Y1114673D01*
G01X579847Y1092973D02*
Y1084983D01*
X578287Y1083423D01*
G01D02*
X569687D01*
G01X563287Y1084673D02*
X557437D01*
X556937Y1085173D01*
G01X569687Y1083423D02*
X567037D01*
X565787Y1084673D01*
X563287D01*
G01X556937Y1085173D02*
X556787Y1085323D01*
Y1089523D01*
G01X585637Y1091673D02*
Y1096673D01*
G01Y1091673D02*
Y1086873D01*
G01Y1096673D02*
X578327D01*
X577287Y1097713D01*
Y1100373D01*
G01X611651Y112329D02*
X607929D01*
G01X621647Y107633D02*
X616903D01*
G01X636037Y240661D02*
X635868Y240492D01*
X615059D01*
G01X636037Y244761D02*
Y240661D01*
G01Y244761D02*
Y250161D01*
G01D02*
Y255911D01*
X636287Y256161D01*
G01X642287D02*
Y262200D01*
G01X636787Y270461D02*
X636756Y270492D01*
X615059D01*
G01X642287Y262200D02*
Y266461D01*
G01X652663Y502400D02*
Y506000D01*
G01X647663Y502400D02*
Y506000D01*
G01X624028Y503558D02*
Y499055D01*
G01X638263Y499018D02*
Y503494D01*
G01X627863Y517621D02*
Y522000D01*
G01X627907Y512537D02*
X627903Y512533D01*
Y506555D01*
G01X627907Y512537D02*
Y517577D01*
X627863Y517621D01*
G01X642138Y506518D02*
X642134Y506522D01*
Y512541D01*
G01D02*
Y516660D01*
X642344Y516870D01*
G01X642509Y520667D02*
Y517035D01*
X642344Y516870D01*
G01X611910Y562524D02*
X610160Y560774D01*
X607460D01*
G01X616060Y562574D02*
X616010Y562524D01*
X611910D01*
G01Y555124D02*
X610760Y556274D01*
X607460D01*
G01X616060Y555174D02*
X616010Y555124D01*
X611910D01*
G01X637213Y585905D02*
Y582155D01*
G01X636037Y693417D02*
X635868Y693248D01*
X615059D01*
G01X636037Y697517D02*
Y693417D01*
G01X636787Y723417D02*
X636618Y723248D01*
X615059D01*
G01X636287Y708917D02*
X636037Y708667D01*
Y702917D01*
G01D02*
Y697517D01*
G01X642287Y714800D02*
Y708917D01*
G01Y719817D02*
Y714800D01*
G01X642905Y724933D02*
Y722986D01*
X647207Y718684D01*
G01D02*
Y714197D01*
G01D02*
Y709555D01*
G01X637318Y745123D02*
X637326Y745115D01*
Y739816D01*
G01D02*
X642872D01*
X642909Y739853D01*
G01X646780Y732433D02*
X651495D01*
X656244Y737182D01*
Y755300D01*
G01X637318Y749649D02*
Y745123D01*
G01X646784Y756310D02*
Y747353D01*
G01X689172Y821534D02*
Y819228D01*
X690063Y818337D01*
Y815055D01*
X646784Y771776D01*
Y756310D01*
G01X636800Y1176000D02*
X630704D01*
X630700Y1176004D01*
X615059D01*
G01X636287Y1161673D02*
X636037Y1161423D01*
Y1155673D01*
G01D02*
Y1150273D01*
G01Y1146173D02*
X635868Y1146004D01*
X615059D01*
G01X636037Y1150273D02*
Y1146173D01*
G01X642287Y1161673D02*
Y1157473D01*
X642942Y1156818D01*
G01X642989Y1172409D02*
Y1170399D01*
X647716Y1165672D01*
G01D02*
Y1160810D01*
G01D02*
Y1154150D01*
G01X632316Y1201074D02*
Y1207774D01*
X638776Y1214234D01*
G01D02*
X667475Y1242933D01*
Y1284839D01*
X671862Y1289226D01*
X673538D01*
X673539Y1289225D01*
X688339D01*
X692225Y1285339D01*
Y1282775D01*
X693112Y1281888D01*
Y1280040D01*
G01X637316Y1201074D02*
Y1207413D01*
X658241Y1228338D01*
G01X641383Y1186238D02*
X641614Y1186007D01*
X647126D01*
G01D02*
Y1189513D01*
G01X642894Y1192640D02*
X641383Y1191129D01*
Y1186238D01*
G01X646864Y1179909D02*
X652800D01*
X655300Y1182409D01*
Y1208000D01*
X679907Y1232607D01*
G01X646769Y1200140D02*
Y1204796D01*
X658303Y1216330D01*
G01X661638Y109969D02*
Y113795D01*
X663449Y115606D01*
G01X666142Y109969D02*
X666383Y110210D01*
X675952D01*
G01X666142Y109969D02*
X661638D01*
G01X690807Y107247D02*
Y103298D01*
G01X685711Y101931D02*
X683829D01*
X682452Y103308D01*
Y107650D01*
G01X690807Y103298D02*
X689440Y101931D01*
X685711D01*
G01X693900Y181411D02*
X698300D01*
G01D02*
X701500Y184611D01*
Y187461D01*
G01X681250Y210561D02*
Y214661D01*
G01Y210561D02*
Y194161D01*
G01X681000Y187411D02*
X686750D01*
X687500Y188161D01*
G01X681250Y194161D02*
Y187661D01*
X681000Y187411D01*
G01X689050Y205161D02*
Y199160D01*
X690166Y198044D01*
G01X689050Y209261D02*
Y211145D01*
X695000Y217095D01*
Y227661D01*
G01X689050Y205161D02*
Y209261D01*
G01X690166Y198044D02*
X693349Y194861D01*
X698940D01*
G01X681050Y179561D02*
X681000Y179611D01*
Y183911D01*
G01X687500Y179161D02*
X681450D01*
X681050Y179561D01*
G01X693900Y177911D02*
X691250D01*
X690000Y179161D01*
X687500D01*
G01X702500Y177911D02*
X693900D01*
G01X681250Y214661D02*
X687000Y220411D01*
Y225661D01*
G01X689232Y355251D02*
X693112Y359131D01*
Y361401D01*
G01Y382100D02*
Y374529D01*
G01Y385976D02*
Y382100D01*
G01X689172Y380276D02*
Y374529D01*
G01Y385976D02*
Y380276D01*
G01X693112Y361401D02*
Y368779D01*
G01X689172Y362876D02*
Y368779D01*
G01Y358978D02*
Y362876D01*
G01X697903Y630996D02*
Y634901D01*
X699025Y636023D01*
G01X701700Y641717D02*
Y638698D01*
X699025Y636023D01*
G01X685500Y640167D02*
X690850D01*
X691600Y640917D01*
G01X685500Y640167D02*
Y642986D01*
X689758Y647244D01*
Y649790D01*
G01X691600Y631917D02*
X692931D01*
X696130Y628718D01*
X699125D01*
X701403Y630996D01*
G01X691600Y631917D02*
X685500D01*
G01Y636667D02*
Y631917D01*
G01X681750Y665817D02*
Y653336D01*
X683009Y652077D01*
X688966D01*
X689758Y651285D01*
Y649790D01*
G01X681750Y669917D02*
Y665817D01*
G01X687000Y678417D02*
Y673097D01*
X683820Y669917D01*
X681750D01*
G01X689050Y657917D02*
Y662017D01*
G01D02*
Y669146D01*
G01D02*
Y670787D01*
X695000Y676737D01*
Y680417D01*
G01X699140Y649117D02*
X694913D01*
X689050Y654980D01*
Y657917D01*
G01X693112Y821534D02*
Y819212D01*
X692263Y818363D01*
Y814143D01*
X656244Y778124D01*
Y755300D01*
G01X693112Y827284D02*
Y940100D01*
G01X689172Y827284D02*
Y928400D01*
G01X688563Y950755D02*
X689172Y950146D01*
Y928400D01*
G01X693563Y950755D02*
X693112Y950304D01*
Y940100D01*
G01X701500Y1092973D02*
Y1090123D01*
X698300Y1086923D01*
G01X693900D02*
X698300D01*
G01X680400Y1101050D02*
X681150Y1100300D01*
X685300D01*
X687500Y1098100D01*
Y1093673D01*
G01X680400Y1105800D02*
Y1111900D01*
X684211Y1115711D01*
X684917D01*
X687050Y1117844D01*
Y1119973D01*
G01X687000Y1131173D02*
Y1124123D01*
X687050Y1124073D01*
G01D02*
Y1119973D01*
G01X680400Y1101050D02*
Y1105800D01*
G01X691400Y1101900D02*
X688750Y1104550D01*
Y1106273D01*
G01X698940Y1100373D02*
X692927D01*
X691400Y1101900D01*
G01X688750Y1110373D02*
Y1114350D01*
X695000Y1120600D01*
Y1133173D01*
G01X688750Y1106273D02*
Y1110373D01*
G01X702500Y1083423D02*
X693900D01*
G01D02*
X691250D01*
X690000Y1084673D01*
X687500D01*
G01D02*
X685128D01*
X680650Y1089151D01*
Y1093100D01*
G01X680400Y1097550D02*
Y1097521D01*
X680488Y1097433D01*
Y1093262D01*
X680650Y1093100D01*
G01X658303Y1216330D02*
X689872Y1247899D01*
Y1271090D01*
X689172Y1271790D01*
Y1274290D01*
G01Y1280040D02*
Y1281872D01*
X690200Y1282900D01*
Y1284500D01*
X687500Y1287200D01*
X672700D01*
X669500Y1284000D01*
Y1239597D01*
X658241Y1228338D01*
G01X693112Y1274290D02*
Y1271990D01*
X692072Y1270950D01*
Y1244772D01*
X679907Y1232607D01*
G01X749450Y209600D02*
Y214950D01*
X758000Y223500D01*
G01X749450Y205500D02*
Y209600D01*
G01Y205500D02*
Y199761D01*
X747242Y197553D01*
G01X704060Y187461D02*
Y179471D01*
X702500Y177911D01*
G01X709850Y181161D02*
Y186161D01*
G01Y191161D02*
X702139D01*
X701500Y191800D01*
Y194861D01*
G01X709850Y176461D02*
Y181161D01*
G01Y186161D02*
Y191161D01*
G01X713350Y176461D02*
X717188D01*
G01X758000Y223500D02*
Y235500D01*
X753008Y240492D01*
X739272D01*
G01Y270492D02*
X751292D01*
X751300Y270500D01*
G01X701403Y630996D02*
X704260Y633853D01*
Y635957D01*
G01D02*
Y641717D01*
G01X709850Y629417D02*
Y633917D01*
G01Y638917D02*
Y643917D01*
G01Y633917D02*
Y638917D01*
G01X701700Y649117D02*
Y646247D01*
X702571Y645376D01*
X706023D01*
X707482Y643917D01*
X709850D01*
G01X713350Y629417D02*
X716600D01*
G01X748250Y681800D02*
Y690750D01*
X745752Y693248D01*
X739272D01*
G01X748250Y677700D02*
Y681800D01*
G01X749000Y672000D02*
Y674500D01*
X748250Y675250D01*
Y677700D01*
G01X749000Y666000D02*
X751759D01*
X754500Y668741D01*
G01X749000Y723417D02*
X748831Y723248D01*
X739272D01*
G01X709850Y1086673D02*
Y1081973D01*
G01X713350D02*
X716600D01*
G01X704060Y1092973D02*
Y1084983D01*
X702500Y1083423D01*
G01X709850Y1091673D02*
Y1096673D01*
G01Y1091673D02*
Y1086673D01*
G01Y1096673D02*
X701927D01*
X701500Y1097100D01*
Y1100373D01*
G01X760900Y1176000D02*
X760896Y1176004D01*
X739272D01*
G01Y1146004D02*
X746496D01*
X748750Y1143750D01*
X752500D01*
G01X751209Y159628D02*
X757020D01*
Y159692D01*
G01X751209Y165628D02*
X755710D01*
X758619Y168537D01*
G01X752500Y1143750D02*
Y1148250D01*
G01X760250Y1154000D02*
Y1156250D01*
X759000Y1157500D01*
X752500D01*
G01Y1148250D02*
X759000D01*
X760250Y1149500D01*
Y1154000D01*
G01X752500Y1163500D02*
Y1167500D01*
G01X897261Y1450061D02*
Y1456139D01*
X887825Y1465575D01*
X827589D01*
X827414Y1465750D01*
X827395D01*
X819489Y1473656D01*
X819344D01*
X819332Y1473668D01*
X800792D01*
X796848Y1469724D01*
G01X829921Y5709D02*
Y-458D01*
G01X825984Y5709D02*
Y-458D01*
G01X837795Y5709D02*
Y725D01*
X833724Y-3346D01*
G01X833858Y5709D02*
Y441D01*
X833671Y254D01*
G01X806299Y5709D02*
Y-458D01*
G01X802362Y5709D02*
Y-458D01*
G01X814173Y5709D02*
Y-458D01*
G01X810236Y5709D02*
Y-458D01*
G01X822047Y5709D02*
Y-458D01*
G01X818110Y5709D02*
Y-458D01*
G01X845670Y5709D02*
Y-3633D01*
X845661Y-3642D01*
G01X843463Y530D02*
Y499D01*
X841733Y2229D01*
Y5709D01*
G01X806314Y35952D02*
X806299Y35937D01*
Y29725D01*
G01X802362D02*
Y35911D01*
X802350Y35923D01*
G01X842470Y41295D02*
X845670Y38095D01*
Y29725D01*
G01X841733D02*
Y36654D01*
G01X884461Y1450061D02*
Y1453139D01*
X882675Y1454925D01*
X822311D01*
X816740Y1460496D01*
X806952D01*
G01X806568Y1464275D02*
X815825D01*
X823150Y1456950D01*
X883650D01*
X887021Y1453579D01*
Y1450061D01*
G01X889581D02*
Y1454319D01*
X884750Y1459150D01*
X824350D01*
X816432Y1467068D01*
X805829D01*
X802433Y1463672D01*
Y1461619D01*
G01X800900Y1465234D02*
X804934Y1469268D01*
X817432D01*
X825350Y1461350D01*
X885750D01*
X892141Y1454959D01*
Y1450061D01*
G01X800462Y1469231D02*
X802699Y1471468D01*
X818813D01*
X826556Y1463725D01*
X826575D01*
X826750Y1463550D01*
X886350D01*
X886525Y1463375D01*
X886589D01*
X894701Y1455263D01*
Y1450061D01*
G01X833859Y1618111D02*
X830619Y1614871D01*
Y1546002D01*
X829462Y1544845D01*
Y1496769D01*
X843086Y1483145D01*
X861064D01*
X872587Y1494668D01*
Y1507059D01*
X874077Y1508549D01*
X892966D01*
G01X833859Y1612599D02*
X837310Y1609148D01*
Y1547310D01*
X832137Y1542137D01*
Y1497878D01*
X844195Y1485820D01*
X859955D01*
X869912Y1495777D01*
Y1505950D01*
X869911Y1505951D01*
Y1508167D01*
X872968Y1511224D01*
X891660D01*
X893036Y1512600D01*
G01X834813Y1528889D02*
X836615Y1530691D01*
X841508D01*
G01X834974Y1533243D02*
Y1537174D01*
X836600Y1538800D01*
X838950D01*
G01X834974Y1533243D02*
X834982Y1533251D01*
X841508D01*
G01X886322Y69D02*
X884306Y-1947D01*
X873114D01*
X869292Y1875D01*
Y5709D01*
G01X865355D02*
Y2118D01*
X867080Y393D01*
G01X886427Y3802D02*
X884095Y1470D01*
X878517D01*
X877166Y2821D01*
Y5709D01*
G01X873229D02*
Y950D01*
X873892Y287D01*
G01X886418Y-7350D02*
X868737D01*
X864740Y-3353D01*
X857888D01*
X853544Y991D01*
Y5709D01*
G01X849607D02*
Y772D01*
X849484Y649D01*
G01X886351Y-3735D02*
X885619Y-4467D01*
X868737D01*
X861418Y2852D01*
Y5709D01*
G01X857481D02*
Y691D01*
X857513Y659D01*
G01X937205Y12599D02*
Y13435D01*
X930729Y19911D01*
X927079D01*
X905490Y41500D01*
X885250D01*
G01X885448Y37380D02*
X885250Y37578D01*
Y41500D01*
G01X887100Y359100D02*
X882900D01*
G01D02*
X878300D01*
G01X937205Y391732D02*
X923968Y378495D01*
X887500D01*
G01D02*
X883200D01*
G01D02*
X878307D01*
G01X878104Y445462D02*
X882400D01*
G01D02*
X885638D01*
X923620Y407480D01*
X937205D01*
G01X878150Y450200D02*
X882500D01*
G01D02*
X886100D01*
X924883Y411417D01*
X929331D01*
G01X937205Y423228D02*
X917572D01*
X885900Y454900D01*
X882500D01*
G01X929331Y427165D02*
X918135D01*
X885738Y459562D01*
X882600D01*
G01X874604Y445462D02*
X870389D01*
G01D02*
X867580D01*
X866317Y446725D01*
G01X947047Y407480D02*
X944928D01*
X940949Y403501D01*
X935943D01*
X931872Y399430D01*
X926926D01*
X888666Y437690D01*
X868017D01*
X859450Y446257D01*
Y451050D01*
X862000Y453600D01*
G01X954921Y411417D02*
Y409406D01*
X949016Y403501D01*
X946027D01*
X938463Y395937D01*
X935112D01*
X931223Y392048D01*
X930524D01*
X930278Y392294D01*
X927933D01*
X925956Y394271D01*
Y396616D01*
X887557Y435015D01*
X866385D01*
X855900Y445500D01*
Y450300D01*
X852000Y454200D01*
G01X874650Y450200D02*
X870221D01*
G01D02*
X867421D01*
X866321Y451300D01*
G01X878150Y454900D02*
X882500D01*
G01X878204Y459562D02*
X882600D01*
G01X870179Y454900D02*
X866276D01*
G01X874650D02*
X870179D01*
G01X882700Y464505D02*
X878193D01*
G01X937205Y431102D02*
X931998D01*
X930150Y432950D01*
X917950D01*
X886395Y464505D01*
X882700D01*
G01X878193D02*
Y467707D01*
G01X947047Y517716D02*
Y515147D01*
X942700Y510800D01*
Y507200D01*
X941100Y505600D01*
X935900D01*
X932300Y502000D01*
X885300D01*
X884000Y503300D01*
G01X878250Y471100D02*
X887900D01*
X919462Y439538D01*
X934781D01*
X939368Y444125D01*
X944999D01*
X946211Y442913D01*
X954921D01*
G01X874704Y459562D02*
X870263D01*
G01D02*
X866278D01*
G01X879393Y542405D02*
X883900D01*
G01X947047Y549212D02*
X943659Y552600D01*
X934653D01*
X930729Y556524D01*
X927933D01*
X913814Y542405D01*
X883900D01*
G01X929331Y529527D02*
X926904Y527100D01*
X917700D01*
X913405Y522805D01*
X884143D01*
G01X937205Y525590D02*
X936643Y525028D01*
X927933D01*
X919110Y516205D01*
X884143D01*
G01X954921Y521653D02*
X945915D01*
X938603Y514341D01*
X935807D01*
X932994Y517154D01*
X924049D01*
X916800Y509905D01*
X884143D01*
G01X929331Y561023D02*
X926866D01*
X914030Y548187D01*
X883969D01*
G01X929331Y576771D02*
X926229D01*
X909895Y593105D01*
X884143D01*
G01X937205Y572834D02*
X933500Y576539D01*
Y577900D01*
X930700Y580700D01*
X926600D01*
X908095Y599205D01*
X884143D01*
G01X954921Y568897D02*
X935303D01*
X931300Y572900D01*
X924284D01*
X910097Y587087D01*
X884069D01*
G01X954921Y584645D02*
X951700Y587866D01*
Y588702D01*
X948202Y592200D01*
X946234D01*
X938603Y599831D01*
X934666D01*
X931735Y596900D01*
X924200D01*
X909195Y611905D01*
X884043D01*
G01X947047Y580708D02*
X943355Y584400D01*
X934500D01*
X930880Y588020D01*
X926080D01*
X908595Y605505D01*
X884043D01*
G01X884182Y820251D02*
Y822018D01*
X881203Y824997D01*
Y829253D01*
G01X887600Y811900D02*
X887082Y811382D01*
X883400D01*
G01D02*
X883023Y811759D01*
Y816103D01*
G01D02*
Y819092D01*
X884182Y820251D01*
G01X879523Y816103D02*
Y812203D01*
X878673Y811353D01*
G01D02*
X878620Y811300D01*
X874569D01*
G01X879519Y821655D02*
Y820281D01*
X879523Y820277D01*
Y816103D01*
G01X878643Y829253D02*
Y822531D01*
X879519Y821655D01*
G01X876083Y829253D02*
Y824091D01*
X874623Y822631D01*
G01X874513Y818831D02*
Y822521D01*
X874623Y822631D01*
G01X874573Y814580D02*
Y818771D01*
X874513Y818831D01*
G01X881203Y845553D02*
Y852900D01*
G01X885882Y861618D02*
X882400D01*
G01D02*
X881123Y860341D01*
Y856903D01*
G01D02*
X881203Y856823D01*
Y852900D01*
G01X878643Y845553D02*
Y851157D01*
X876900Y852900D01*
G01X873647Y861653D02*
X877673D01*
G01X877623Y856903D02*
X876900Y856180D01*
Y852900D01*
G01X877673Y861653D02*
X877623Y861603D01*
Y856903D01*
G01X885853Y856727D02*
Y852820D01*
X885873Y852800D01*
G01X883763Y845553D02*
Y850690D01*
X885873Y852800D01*
G01X895676Y1369623D02*
X891631D01*
X885754Y1375500D01*
G01X895676Y1372183D02*
X893123D01*
X885608Y1379698D01*
G01X888643Y1356566D02*
X887134Y1355057D01*
X881448D01*
G01X895676Y1359383D02*
X891460D01*
X888643Y1356566D01*
G01X881448Y1355057D02*
X876748D01*
G01X895676Y1356823D02*
X892323D01*
X891150Y1355650D01*
Y1352266D01*
X889223Y1350339D01*
G01X876740Y1346964D02*
X881394D01*
X881420Y1346938D01*
G01D02*
X885822D01*
X889223Y1350339D01*
G01X895676Y1361943D02*
X872457D01*
X870889Y1363511D01*
X869534D01*
G01X868622Y1358528D02*
Y1362599D01*
X869534Y1363511D01*
G01X881361Y1375746D02*
X885508D01*
X885754Y1375500D01*
G01X881362Y1380412D02*
X884894D01*
X885608Y1379698D01*
G01X886792Y1407664D02*
Y1404100D01*
G01X882445Y1407547D02*
Y1404416D01*
X882226Y1404197D01*
G01X877445Y1407547D02*
X876666D01*
X873694Y1404575D01*
G01X877861Y1375746D02*
X873700D01*
G01X877862Y1380412D02*
X873581D01*
X873570Y1380401D01*
G01X879341Y1450061D02*
Y1445341D01*
X877500Y1443500D01*
G01Y1439250D02*
Y1443500D01*
G01X873000Y1439250D02*
X877500D01*
G01X881901Y1450061D02*
Y1443300D01*
G01X886500Y1439250D02*
X882000D01*
G01D02*
X881901Y1439349D01*
Y1443300D01*
G01X868500Y1439250D02*
Y1440300D01*
X871325Y1443125D01*
G01X876781Y1450061D02*
Y1448581D01*
X871325Y1443125D01*
G01X884461Y1472261D02*
Y1475261D01*
X888000Y1478800D01*
G01X888600Y1482500D02*
Y1479400D01*
X888000Y1478800D01*
G01X893050Y1482550D02*
X893000Y1482500D01*
X888600D01*
G01X881901Y1472261D02*
Y1476701D01*
X883647Y1478447D01*
G01X883947Y1482520D02*
Y1478747D01*
X883647Y1478447D01*
G01X879341Y1478200D02*
Y1472261D01*
G01X879321Y1482511D02*
Y1478220D01*
X879341Y1478200D01*
G01X877828Y1500379D02*
X894662D01*
X919877Y1475164D01*
X971160D01*
X1011549Y1434775D01*
X1115754D01*
X1122279Y1441300D01*
X1148100D01*
X1154907Y1434493D01*
Y1364182D01*
X1192573Y1326516D01*
Y1050047D01*
X1212930Y1029690D01*
Y941390D01*
X1198040Y926500D01*
X1166900D01*
X1146760Y906360D01*
Y834255D01*
X1040762Y728257D01*
Y441156D01*
X1043948Y437970D01*
X1047971D01*
X1049751Y436190D01*
Y434409D01*
G01X906850Y1508100D02*
X893415D01*
X892966Y1508549D01*
G01X906850Y1512600D02*
X893036D01*
G01X883947Y1486020D02*
Y1490974D01*
X882572Y1492349D01*
G01X877946Y1496527D02*
X878394D01*
X882572Y1492349D01*
G01X879321Y1486011D02*
Y1489626D01*
G01D02*
Y1489661D01*
G01X876096Y1505499D02*
X875397Y1504800D01*
Y1493550D01*
X879321Y1489626D01*
G01X855535Y1498705D02*
X860179Y1494061D01*
Y1491170D01*
G01X850500Y1501250D02*
X852990D01*
X855535Y1498705D01*
G01X860000Y1504750D02*
Y1509750D01*
X858500Y1511250D01*
G01X850500Y1504750D02*
X855523D01*
G01D02*
X860000D01*
G01X896335Y1524958D02*
X892958D01*
X892700Y1524700D01*
G01X848008Y1528131D02*
X854096D01*
X855899Y1529934D01*
G01D02*
X857353Y1531388D01*
Y1542592D01*
X858890Y1544129D01*
Y1609284D01*
X862205Y1612599D01*
G01X862375Y1518750D02*
X866750D01*
X867500Y1519500D01*
G01X868458Y1529687D02*
Y1523720D01*
G01X867500Y1519500D02*
X868458Y1520458D01*
Y1523720D01*
G01X1005571Y7943D02*
X997805Y15709D01*
X960765D01*
X960146Y15090D01*
Y14595D01*
X958712Y13161D01*
X953523D01*
X951594Y15090D01*
X951210D01*
X949300Y17000D01*
X944000D01*
X941900Y19100D01*
Y22300D01*
X940100Y24100D01*
X934800D01*
X929331Y29569D01*
Y32284D01*
G01X1005471Y14243D02*
X1001711Y18003D01*
X960097D01*
X957600Y20500D01*
X953100D01*
X949500Y24100D01*
X943800D01*
X939553Y28347D01*
X937205D01*
G01Y36221D02*
X941184Y40200D01*
X949500D01*
X953343Y44043D01*
X1005371D01*
G01X937205Y557086D02*
X942274D01*
X945649Y560461D01*
X948863D01*
X951676Y557648D01*
X958758D01*
X967289Y549117D01*
X984717D01*
X990132Y554532D01*
X1006400D01*
G01X919100Y912450D02*
X914600D01*
G01X916900Y921900D02*
Y917500D01*
X915654Y916254D01*
G01X914600Y912450D02*
Y915200D01*
X915654Y916254D01*
G01X923600Y912450D02*
Y913600D01*
X921100Y916100D01*
G01X919460Y921900D02*
Y917740D01*
X921100Y916100D01*
G01X928100Y912450D02*
Y916200D01*
G01X922020Y921900D02*
Y918780D01*
X924600Y916200D01*
X928100D01*
G01X923600Y908950D02*
Y905000D01*
G01D02*
X920810Y902210D01*
G01X928100Y908950D02*
Y905300D01*
G01D02*
Y900650D01*
G01X900615Y909723D02*
X901540Y910648D01*
Y916200D01*
G01Y921900D02*
Y916200D01*
G01X902571Y906534D02*
X903900Y907863D01*
Y912660D01*
X904100Y912860D01*
G01D02*
Y921900D01*
G01X903368Y934568D02*
X902000Y933200D01*
Y929400D01*
X906660Y924740D01*
Y921900D01*
G01X904594Y931141D02*
X909220Y926515D01*
Y921900D01*
G01X916204Y938572D02*
X911780Y934148D01*
Y921900D01*
G01X917550Y934742D02*
X914340Y931532D01*
Y921900D01*
G01X901540Y944100D02*
Y937712D01*
G01X896679Y927505D02*
X898980Y929806D01*
Y944100D01*
G01X896420Y921900D02*
Y916712D01*
G01X898468Y912970D02*
X898980Y913482D01*
Y921900D01*
G01X941274Y905195D02*
Y915422D01*
X936958Y919738D01*
Y930299D01*
X931085Y936172D01*
G01X941274Y900845D02*
Y905195D01*
G01X931085Y936172D02*
Y941695D01*
G01X923985Y954185D02*
X927861Y958061D01*
Y959457D01*
G01X922020Y944100D02*
Y952220D01*
X923985Y954185D01*
G01X927861Y959457D02*
X932361D01*
G01X916500Y959350D02*
Y957600D01*
X918577Y955523D01*
G01X920607Y959332D02*
X916518D01*
X916500Y959350D01*
G01X919460Y944100D02*
Y954640D01*
X918577Y955523D01*
G01X924580Y944100D02*
Y949430D01*
X929960Y954810D01*
G01X936861Y959457D02*
Y958487D01*
X933184Y954810D01*
X929960D01*
G01X919400Y991400D02*
Y986900D01*
X918220Y985720D01*
G01X917100Y981950D02*
Y984600D01*
X918220Y985720D01*
G01X921600Y981950D02*
X917100D01*
G01X921960Y991400D02*
Y986840D01*
X923100Y985700D01*
G01X926100Y981950D02*
Y982700D01*
X923100Y985700D01*
G01X924520Y991400D02*
Y988514D01*
X927460Y985574D01*
G01X930600Y981950D02*
Y983500D01*
X928526Y985574D01*
X927460D01*
G01X926100Y978450D02*
Y976161D01*
X927917Y974344D01*
G01X934142D02*
X927917D01*
G01X930600Y978450D02*
X934343D01*
G01X939481Y980230D02*
X937701Y978450D01*
X934343D01*
G01X912994Y967848D02*
Y956254D01*
X916900Y952348D01*
Y944100D01*
G01X912994Y967848D02*
Y971921D01*
G01X914340Y944100D02*
Y951360D01*
X910594Y955106D01*
G01D02*
Y971282D01*
X909900Y971976D01*
Y978692D01*
X910397Y979189D01*
G01X902991Y982230D02*
X904040Y983279D01*
Y991400D01*
G01X906600Y985800D02*
Y991400D01*
G01X909826Y982874D02*
X909526D01*
X906600Y985800D01*
G01X908094Y965295D02*
Y954006D01*
X911780Y950320D01*
Y944100D01*
G01X905271Y974586D02*
Y971305D01*
X908094Y968482D01*
Y965295D01*
G01X905506Y958415D02*
Y952706D01*
X909220Y948992D01*
Y944100D01*
G01X899846Y971468D02*
X905506Y965808D01*
Y958415D01*
G01X902866Y964401D02*
Y952234D01*
X906660Y948440D01*
Y944100D01*
G01X898617Y975434D02*
X897016Y973833D01*
Y970251D01*
X902866Y964401D01*
G01X900400Y960942D02*
X900600Y960742D01*
Y951200D01*
X904100Y947700D01*
Y944100D01*
G01X895837Y978389D02*
X894701Y977253D01*
Y966641D01*
X900400Y960942D01*
G01X895616Y985932D02*
X896432D01*
X898920Y988420D01*
Y991400D01*
G01X901480Y985800D02*
Y991400D01*
G01X896629Y982285D02*
X897965D01*
X901480Y985800D01*
G01X935623Y971054D02*
X940141D01*
X944617Y975530D01*
G01X924520Y1013600D02*
Y1021720D01*
X926513Y1023713D01*
G01X925053Y1028635D02*
Y1025173D01*
X926513Y1023713D01*
G01X929105Y1028510D02*
X928980Y1028635D01*
X925053D01*
G01X921960Y1013600D02*
Y1022940D01*
X920500Y1024400D01*
G01X916769Y1028689D02*
Y1028131D01*
X920500Y1024400D01*
G01X920879Y1028653D02*
X920843Y1028689D01*
X916769D01*
G01X927080Y1013600D02*
Y1018730D01*
X932316Y1023966D01*
G01X933263Y1028083D02*
Y1024913D01*
X932316Y1023966D01*
G01X918430Y1040930D02*
X912827Y1035327D01*
Y1027356D01*
X919400Y1020783D01*
Y1013600D01*
G01X919778Y1047278D02*
X910627Y1038127D01*
Y1026673D01*
X916840Y1020460D01*
Y1013600D01*
G01X904601Y998556D02*
X905044D01*
X909160Y994440D01*
Y991400D01*
G01X910040Y1006613D02*
X909200Y1005773D01*
Y1001289D01*
X911720Y998769D01*
Y991400D01*
G01X911807Y1002342D02*
X914280Y999869D01*
Y991400D01*
G01X919656Y998764D02*
X916840Y995948D01*
Y991400D01*
G01X942893Y1001345D02*
X941684D01*
X939544Y1003485D01*
G01X919400Y1056000D02*
Y1051200D01*
X908300Y1040100D01*
Y1025376D01*
X914280Y1019396D01*
Y1013600D01*
G01X914100Y1056200D02*
Y1049029D01*
X906215Y1041144D01*
Y1024385D01*
X911720Y1018880D01*
Y1013600D01*
G01X909160D02*
Y1018340D01*
X904027Y1023473D01*
Y1041820D01*
X910387Y1048180D01*
Y1051177D01*
G01X904875Y1046590D02*
X901827Y1043542D01*
Y1022673D01*
X906600Y1017900D01*
Y1013600D01*
G01X903442Y1003265D02*
X904040Y1003863D01*
Y1013600D01*
G01X896371Y1002112D02*
X901480Y1007221D01*
Y1013600D01*
G01X936674Y1032390D02*
Y1035426D01*
X936378Y1035722D01*
G01X936763Y1028083D02*
X936674Y1028172D01*
Y1032390D01*
G01X920770Y1067389D02*
X925000Y1063159D01*
Y1047500D01*
X918430Y1040930D01*
G01X921149Y1062424D02*
X922700Y1060873D01*
Y1050200D01*
X919778Y1047278D01*
G01X914948Y1063255D02*
X919400Y1058803D01*
Y1056000D01*
G01X908477Y1061823D02*
X914100Y1056200D01*
G01X910387Y1055344D02*
Y1051177D01*
G01X904875D02*
Y1046590D01*
G01X928194Y1373098D02*
X927302D01*
X924300Y1376100D01*
G01X917876Y1372183D02*
X923817D01*
X924200Y1371800D01*
G01X942925Y1376407D02*
X941925D01*
X939500Y1373982D01*
Y1371800D01*
X937505Y1369805D01*
X926195D01*
X924200Y1371800D01*
G01X917876Y1369623D02*
X921877D01*
X924436Y1367064D01*
G01D02*
X928439D01*
G01D02*
X928469Y1367034D01*
X932559D01*
G01D02*
X932565Y1367040D01*
X936959D01*
G01X917876Y1367063D02*
X921237D01*
X924400Y1363900D01*
Y1362000D01*
G01X942879Y1361807D02*
X938577Y1357505D01*
X927495D01*
X924400Y1360600D01*
Y1362000D01*
G01X917876Y1364503D02*
X920742D01*
X922000Y1363245D01*
Y1359716D01*
X925313Y1356403D01*
G01X928384Y1353332D02*
X925313Y1356403D01*
G01X936964Y1353362D02*
X932564D01*
G01D02*
X928414D01*
X928384Y1353332D01*
G01X917876Y1374743D02*
X921343D01*
X922700Y1376100D01*
X924300D01*
G01X936994Y1373098D02*
X932294D01*
G01D02*
X928194D01*
G01X906600Y1461600D02*
X902900D01*
X899821Y1458521D01*
Y1450061D01*
G01X909400Y1459200D02*
X903800D01*
X902381Y1457781D01*
Y1450061D01*
G01X910000Y1464900D02*
Y1470100D01*
X907839Y1472261D01*
X904941D01*
G01X905500Y1467161D02*
X903239D01*
X902381Y1468019D01*
Y1472261D01*
G01X908742Y1477427D02*
X901527D01*
X899821Y1475721D01*
Y1472261D01*
G01X897261D02*
Y1477683D01*
X898378Y1478800D01*
G01X908542Y1481127D02*
X900705D01*
X898378Y1478800D01*
G01X929950Y1522310D02*
X929110D01*
X925000Y1518200D01*
X924000D01*
G01X910350Y1508100D02*
X911900D01*
X922000Y1518200D01*
X924000D01*
G01X910350Y1512600D02*
X911721D01*
X923400Y1524279D01*
G01X930250D02*
X923400D01*
G01X907950Y1522500D02*
X901700D01*
X900248Y1521048D01*
G01D02*
X899242Y1520042D01*
X896365D01*
G01D02*
X896335Y1520072D01*
Y1524958D01*
G01X966713Y-122342D02*
Y-112100D01*
X986122Y-92691D01*
Y-44738D01*
X1010380Y-20480D01*
G01X961713Y-122342D02*
Y-113316D01*
X983447Y-91582D01*
Y-43237D01*
X1011125Y-15559D01*
G01X981700Y-115500D02*
X981713Y-115513D01*
Y-122342D01*
G01X976713D02*
Y-115570D01*
G01X989316Y-94984D02*
X994764Y-100432D01*
Y-103956D01*
G01X947047Y67717D02*
Y64553D01*
X952698Y58902D01*
X1005981D01*
G01X947047Y51969D02*
X949478Y54400D01*
X1004000D01*
G01X954921Y63780D02*
X1005400D01*
G01X954921Y40158D02*
X972213D01*
X974100Y38271D01*
X1005457D01*
G01X947047Y44095D02*
Y46247D01*
X952465Y51665D01*
X958750D01*
X960544Y49871D01*
X1005557D01*
G01X954921Y32284D02*
X966416D01*
X972157Y26543D01*
X1005471D01*
G01X947047Y36221D02*
X971079D01*
X974957Y32343D01*
X1005471D01*
G01X947047Y28347D02*
X960653D01*
X968557Y20443D01*
X1005571D01*
G01X954921Y339371D02*
X962510D01*
X985688Y362549D01*
G01X954921Y553149D02*
X962863Y545207D01*
X1006815D01*
G01X947047Y564960D02*
X955757D01*
X958665Y567868D01*
Y571459D01*
X968463Y581257D01*
X1002954D01*
X1005157Y579054D01*
G01X955980Y921900D02*
Y918020D01*
X958200Y915800D01*
G01D02*
X961500Y912500D01*
Y911750D01*
G01D02*
X957000D01*
G01X958540Y921900D02*
Y919460D01*
X960500Y917500D01*
X961396D01*
X963066Y915830D01*
G01D02*
X966000Y912896D01*
Y911750D01*
G01D02*
X970500D01*
G01X953420Y921900D02*
Y915900D01*
X953320Y915800D01*
G01X952500Y911750D02*
Y914980D01*
X953320Y915800D01*
G01X961100Y921900D02*
Y931640D01*
G01X960503Y936185D02*
X963660Y933028D01*
Y921900D01*
G01X967583Y933607D02*
X966220Y932244D01*
Y921900D01*
G01X968698Y928957D02*
X968780Y928875D01*
Y921900D01*
G01X974484Y935078D02*
X971340Y931934D01*
Y921900D01*
G01X976419Y931628D02*
X973900Y929109D01*
Y921900D01*
G01X976460D02*
Y927891D01*
G01X981679Y936678D02*
X979020Y934019D01*
Y921900D01*
G01X966000Y937500D02*
X963660Y939840D01*
Y944100D01*
G01X961100Y949800D02*
Y944100D01*
G01X959400Y953650D02*
Y951500D01*
X961100Y949800D01*
G01X963900Y953650D02*
X959400D01*
G01X954900D02*
Y951800D01*
X956800Y949900D01*
G01X958540Y944100D02*
Y948160D01*
X956800Y949900D01*
G01X950400Y949800D02*
Y953650D01*
G01X955980Y944100D02*
Y947320D01*
X953500Y949800D01*
X950400D01*
G01X950500Y982750D02*
Y985400D01*
X951700Y986600D01*
G01X955000Y982750D02*
X950500D01*
G01X959500D02*
Y983400D01*
X956300Y986600D01*
G01X964000Y982750D02*
X959500D01*
G01X946000D02*
Y985058D01*
X947400Y986458D01*
G01X954900Y957150D02*
Y958260D01*
X953013Y960147D01*
G01X950400Y957150D02*
X947174D01*
G01X981580Y953300D02*
Y944100D01*
G01X979020Y960000D02*
X981580Y957440D01*
Y953300D01*
G01X979020Y944100D02*
Y949700D01*
G01D02*
Y956200D01*
G01X976460Y953300D02*
Y944100D01*
G01X973900Y960000D02*
X976460Y957440D01*
Y953300D01*
G01X973900Y944100D02*
Y949800D01*
G01D02*
Y956200D01*
G01X971340Y953300D02*
Y944100D01*
G01X968780Y960000D02*
X971340Y957440D01*
Y953300D01*
G01X968780Y944100D02*
Y949800D01*
G01D02*
Y956200D01*
G01X976213Y938846D02*
X968054D01*
X966220Y940680D01*
Y944100D01*
G01X946000Y979250D02*
Y976913D01*
X944617Y975530D01*
G01X993194Y978090D02*
X989219D01*
X987734Y979575D01*
G01X956100Y1020300D02*
Y1014600D01*
G01Y1020300D02*
Y1022450D01*
X955700Y1022850D01*
Y1024050D01*
G01D02*
X960400D01*
G01X950980Y992400D02*
Y988900D01*
X951700Y988180D01*
Y986600D01*
G01X953540Y992400D02*
Y989360D01*
X956300Y986600D01*
G01X948420Y992400D02*
Y987478D01*
X947400Y986458D01*
G01X953540Y1014600D02*
Y1018560D01*
X951800Y1020300D01*
G01X951200Y1024050D02*
Y1020900D01*
X951800Y1020300D01*
G01X946700Y1024050D02*
Y1020300D01*
X946800Y1020200D01*
G01X950980Y1014600D02*
Y1017820D01*
X948600Y1020200D01*
X946800D01*
G01X951200Y1027550D02*
Y1030700D01*
G01X946700Y1027550D02*
Y1030700D01*
G01X947759Y998726D02*
X949935Y996550D01*
X955150D01*
X956100Y995600D01*
Y992400D01*
G01X958660D02*
Y996240D01*
X956150Y998750D01*
X952450D01*
X949855Y1001345D01*
X942893D01*
G01X961220Y992400D02*
Y1001600D01*
G01Y1005400D02*
X963780Y1002840D01*
Y992400D01*
G01X966340D02*
Y1001600D01*
G01Y1005400D02*
X968900Y1002840D01*
Y992400D01*
G01X971460D02*
Y1001600D01*
G01Y1005400D02*
X974020Y1002840D01*
Y992400D01*
G01Y1026200D02*
X976580Y1023640D01*
Y1014600D01*
G01X974020D02*
Y1022400D01*
G01X968900Y1026200D02*
X971460Y1023640D01*
Y1014600D01*
G01X968900D02*
Y1022400D01*
G01X963780Y1026200D02*
X966340Y1023640D01*
Y1014600D01*
G01X963780D02*
Y1022400D01*
G01X956600Y1001700D02*
X958800Y1003900D01*
Y1006092D01*
X961220Y1008512D01*
Y1014600D01*
G01X956600Y1005700D02*
Y1007800D01*
X958660Y1009860D01*
Y1014600D01*
G01X972924Y1158033D02*
X975555Y1160664D01*
Y1165653D01*
G01X978115Y1172153D02*
Y1175615D01*
X981500Y1179000D01*
G01X982387Y1183598D02*
X981500Y1182711D01*
Y1179000D01*
G01X968640Y1153500D02*
Y1148840D01*
X965404Y1145604D01*
X954395D01*
G01X968800Y1158500D02*
X972995Y1162695D01*
Y1165653D01*
G01X968800Y1158500D02*
X968640Y1158340D01*
Y1153500D01*
G01X951872Y1361852D02*
X949515D01*
X949500Y1361837D01*
X947159D01*
G01D02*
X946159D01*
X946129Y1361807D01*
X942879D01*
G01X951525Y1376407D02*
X947125D01*
G01D02*
X942925D01*
G01X991713Y-122342D02*
Y-115413D01*
G01X998045Y-79300D02*
Y-90000D01*
G01D02*
Y-95045D01*
X1001063Y-98063D01*
Y-103956D01*
G01X1006660Y-59968D02*
Y-81200D01*
G01D02*
Y-94060D01*
X1007363Y-94763D01*
Y-103956D01*
G01X1031713Y-122342D02*
Y-115487D01*
X1039525Y-107675D01*
X1058125D01*
X1071836Y-93964D01*
X1090496D01*
X1094300Y-90160D01*
Y-84700D01*
G01X993816Y-95184D02*
X997914Y-99282D01*
Y-103956D01*
G01X1010800Y-77400D02*
X1009000Y-79200D01*
Y-92800D01*
X1010512Y-94312D01*
Y-103956D01*
G01X1026713Y-122342D02*
Y-116887D01*
X1038400Y-105200D01*
X1056100D01*
X1075100Y-86200D01*
G01X1004082Y-43500D02*
X1004100Y-43518D01*
Y-47369D01*
G01X1004082Y-43500D02*
Y-38200D01*
G01X1004100Y-47369D02*
Y-52568D01*
G01Y-69982D02*
Y-65700D01*
G01X1000418Y-69982D02*
X1004100D01*
G01Y-65700D02*
Y-59968D01*
G01X1006660D02*
Y-57635D01*
X1005525Y-56500D01*
X1002800D01*
X1001540Y-55240D01*
Y-52568D01*
G01X1038712Y-42008D02*
Y-43512D01*
X1039560Y-44360D01*
Y-45900D01*
G01X1043112Y-42058D02*
X1043062Y-42008D01*
X1038712D01*
G01X1039560Y-45900D02*
Y-52355D01*
G01X1038808Y-71536D02*
Y-67700D01*
G01Y-75936D02*
Y-71536D01*
G01Y-67700D02*
Y-66192D01*
X1039560Y-65440D01*
Y-61355D01*
G01X1021660Y-56732D02*
Y-53335D01*
X1021225Y-52900D01*
X1017600D01*
X1016540Y-51840D01*
Y-49332D01*
G01X1021660Y-56732D02*
Y-71440D01*
X1015700Y-77400D01*
X1010800D01*
G01X1019100Y-49332D02*
Y-43996D01*
G01X1019118Y-34382D02*
Y-40100D01*
G01X1019100Y-43996D02*
X1019118Y-43978D01*
Y-40100D01*
G01X1019082Y-66200D02*
X1019100Y-66182D01*
Y-62000D01*
G01X1019082Y-66200D02*
Y-71000D01*
G01X1019100Y-62000D02*
Y-56732D01*
G01X1010380Y-20480D02*
X1017883D01*
X1026717Y-11646D01*
G01X1011125Y-15559D02*
X1017209D01*
X1021086Y-11682D01*
G01X1005981Y58902D02*
X1010648D01*
X1010650Y58900D01*
G01Y54200D02*
Y49950D01*
G01X1004000Y54400D02*
X1010450D01*
X1010650Y54200D01*
G01Y63600D02*
Y67650D01*
G01X1005400Y63780D02*
X1007620D01*
X1007800Y63600D01*
X1010650D01*
G01X1138198Y832424D02*
Y831798D01*
X1038130Y731730D01*
Y729409D01*
X1038087Y729366D01*
Y443247D01*
X1037505Y442665D01*
Y392475D01*
X1045292Y384688D01*
G01X1011356Y554532D02*
X1011400Y554488D01*
Y550000D01*
G01X1011422Y545207D02*
X1006815D01*
G01X1006400Y554532D02*
X1011356D01*
G01X1037483Y845653D02*
Y842683D01*
X1035973Y841173D01*
Y838679D01*
X1035958Y838664D01*
G01X1035980Y834829D02*
X1035973Y834836D01*
G01D02*
Y830953D01*
G01X1035958Y838664D02*
X1035973Y838649D01*
Y834836D01*
G01X1042101Y877191D02*
X1038215D01*
G01X1040043Y861953D02*
Y865957D01*
X1037400Y868600D01*
G01D02*
Y870256D01*
X1038623Y871479D01*
Y872703D01*
G01D02*
X1038585Y872741D01*
X1034264D01*
G01D02*
Y876904D01*
X1034271Y876911D01*
G01X1025660Y921400D02*
Y917940D01*
X1026195Y917405D01*
Y917341D01*
X1030461Y913075D01*
X1030525D01*
X1031200Y912400D01*
X1033600D01*
G01X1034400Y908450D02*
Y911600D01*
X1033600Y912400D01*
G01X1039100Y908450D02*
X1034400D01*
G01X1028220Y921400D02*
Y918180D01*
X1031300Y915100D01*
X1039900D01*
X1042155Y912845D01*
G01X1030780Y921400D02*
Y918484D01*
X1031764Y917500D01*
X1046550D01*
X1051573Y912477D01*
G01X1020480Y908250D02*
Y910020D01*
X1019221Y911279D01*
Y913481D01*
G01X1020540Y921400D02*
Y915800D01*
X1019221Y914481D01*
Y913481D01*
G01X1028685Y908603D02*
Y909515D01*
X1025400Y912800D01*
G01X1023100Y921400D02*
Y915100D01*
X1025400Y912800D01*
G01X1015728Y904750D02*
X1011250D01*
X1011100Y904600D01*
G01X1020480Y904750D02*
X1015728D01*
G01X1025150Y904200D02*
Y897850D01*
X1025000Y897700D01*
G01X1025185Y908603D02*
Y904235D01*
X1025150Y904200D01*
G01X1036431Y929752D02*
Y924943D01*
X1035900Y924412D01*
Y921400D01*
G01X1038460Y943600D02*
Y936466D01*
X1044101Y930825D01*
Y927130D01*
G01X1035900Y943600D02*
Y934483D01*
X1037083Y933300D01*
G01X1012750Y913625D02*
X1014022D01*
X1016842Y916445D01*
G01X1000174Y986100D02*
Y992740D01*
G01X1002194Y981590D02*
Y983095D01*
X1000174Y985115D01*
Y986100D01*
G01X997694Y981590D02*
X1002194D01*
G01X1002734Y992740D02*
Y990060D01*
X1006694Y986100D01*
G01Y981590D02*
Y986100D01*
G01X1011194Y981590D02*
X1006694D01*
G01X1033340Y943600D02*
Y946193D01*
X1035947Y948800D01*
G01X1023100Y943600D02*
Y951000D01*
G01D02*
Y956000D01*
G01X993194Y981590D02*
Y984294D01*
X994900Y986000D01*
G01X997614Y992740D02*
Y988714D01*
X994900Y986000D01*
G01X1017194Y1027190D02*
X1012494D01*
G01X1005294Y1014940D02*
Y1018500D01*
X1007294Y1020500D01*
X1009200D01*
G01X1012494Y1027190D02*
Y1023794D01*
X1009200Y1020500D01*
G01X1003194Y1027090D02*
Y1023194D01*
X1003000Y1023000D01*
G01X1002734Y1014940D02*
Y1022734D01*
X1003000Y1023000D01*
G01X1000174Y1014940D02*
Y1021365D01*
X998439Y1023100D01*
G01Y1027087D02*
Y1023100D01*
G01X1028657Y1009103D02*
X1025774Y1011986D01*
Y1014940D01*
G01X1020654D02*
Y1023940D01*
G01X1018094Y1014940D02*
Y1021240D01*
G01X1015534Y1014940D02*
Y1023840D01*
G01X1007849Y1033743D02*
Y1030593D01*
G01D02*
X1003197D01*
X1003194Y1030590D01*
G01X998439Y1030587D02*
X993655D01*
X993649Y1030593D01*
G01D02*
Y1032749D01*
X994643Y1033743D01*
X996600D01*
G01X1012974Y1014940D02*
Y1021240D01*
G01X1013700Y1007640D02*
Y1008700D01*
X1010414Y1011986D01*
Y1014940D01*
G01X1009509Y1009850D02*
X1007854Y1011505D01*
Y1014940D01*
G01X1005294Y992740D02*
Y997940D01*
G01Y1001740D02*
X1007854Y999180D01*
Y992740D01*
G01X1010414D02*
Y997940D01*
G01Y1001740D02*
X1012974Y999180D01*
Y992740D01*
G01X1023214Y1014940D02*
Y1007140D01*
G01X1028480Y1083900D02*
Y1078770D01*
X1029339Y1077911D01*
G01X1028000Y1073750D02*
X1032500D01*
G01D02*
Y1074750D01*
X1029339Y1077911D01*
G01X1031040Y1083900D02*
Y1080910D01*
X1034069Y1077881D01*
G01X1037000Y1073750D02*
Y1074950D01*
X1034069Y1077881D01*
G01X1041500Y1073750D02*
X1037000D01*
G01X1023500D02*
Y1076800D01*
X1024500Y1077800D01*
G01X1025920Y1083900D02*
Y1079220D01*
X1024500Y1077800D01*
G01X1033600Y1106100D02*
Y1110464D01*
X1031400Y1112664D01*
G01Y1118050D02*
Y1112664D01*
G01X1035900Y1118050D02*
X1031400D01*
G01X1026900D02*
Y1114107D01*
G01X1031040Y1106100D02*
Y1108960D01*
X1026900Y1113100D01*
Y1114107D01*
G01X1022400Y1118050D02*
Y1114181D01*
G01X1028480Y1106100D02*
Y1108720D01*
X1026925Y1110275D01*
X1026306D01*
X1022400Y1114181D01*
G01X1026900Y1125640D02*
Y1121550D01*
G01Y1129466D02*
Y1125640D01*
G01X1022400Y1121550D02*
Y1125311D01*
G01D02*
Y1129183D01*
G01X1036160Y1095500D02*
X1033600Y1092940D01*
Y1083900D01*
G01X1036160D02*
Y1091700D01*
G01X1041280Y1117700D02*
X1038720Y1115140D01*
Y1106100D01*
G01X1036160D02*
Y1111900D01*
G01X1041280Y1095500D02*
X1038720Y1092940D01*
Y1083900D01*
G01X999500Y1154500D02*
Y1149920D01*
X998208Y1148628D01*
G01X995000Y1144250D02*
Y1145420D01*
X998208Y1148628D01*
G01X999700Y1144250D02*
X995000D01*
G01X1004500Y1148300D02*
Y1154500D01*
G01Y1148300D02*
Y1144450D01*
X1004300Y1144250D01*
G01D02*
X1008700D01*
G01X1017800D02*
X1013400D01*
G01X1009500Y1154500D02*
Y1150300D01*
X1011497Y1148303D01*
G01X1013400Y1144250D02*
Y1146400D01*
X1011497Y1148303D01*
G01X1009500Y1174500D02*
Y1180377D01*
G01X1014500Y1174500D02*
Y1180413D01*
G01X1004500Y1174500D02*
Y1180370D01*
G01X1009500Y1180377D02*
Y1184250D01*
G01X1014500Y1180413D02*
Y1184250D01*
G01X1004500Y1180370D02*
Y1184250D01*
G01X1009500Y1187750D02*
Y1188270D01*
X1017354Y1196124D01*
G01X1014500Y1187750D02*
X1021061Y1194311D01*
Y1198543D01*
G01X1038000Y1324216D02*
X1042343D01*
G01X1038000D02*
X1032979D01*
G01D02*
X1032817Y1324378D01*
Y1325600D01*
X1030863Y1327554D01*
X1020473D01*
X1016835Y1323916D01*
G01X1038103Y1349992D02*
X1041975D01*
G01X1038124Y1354526D02*
X1042039D01*
G01X1038200Y1337616D02*
X1042343D01*
G01X1032979D02*
X1038200D01*
G01X1038400Y1342668D02*
X1042443D01*
G01X1038400D02*
X1033079D01*
G01X1016672Y1338228D02*
X1025050Y1346606D01*
X1029141D01*
X1033079Y1342668D01*
G01X1038200Y1330916D02*
X1042343D01*
G01X1038200D02*
X1032979D01*
G01D02*
X1029617Y1334278D01*
X1018878D01*
X1016600Y1332000D01*
G01X1051713Y-122342D02*
Y-114887D01*
G01X1056713Y-122342D02*
Y-115413D01*
G01X1086713Y-122342D02*
Y-115570D01*
G01X1081713Y-122342D02*
Y-115570D01*
G01X1071713Y-122342D02*
Y-115570D01*
G01X1066713Y-122342D02*
Y-115570D01*
G01X1041713Y-115465D02*
Y-122342D01*
G01X1062071Y-76578D02*
Y-80928D01*
X1062121Y-80978D01*
G01X1075100Y-86200D02*
X1077900Y-83400D01*
Y-68900D01*
X1076960Y-67960D01*
Y-63832D01*
G01X1091860Y-77432D02*
Y-74360D01*
X1091200Y-73700D01*
X1087415D01*
X1086740Y-73025D01*
Y-70032D01*
G01X1066225Y-47450D02*
X1061325D01*
G01D02*
Y-50352D01*
X1062073Y-51100D01*
G01D02*
Y-57597D01*
G01Y-66597D02*
Y-70900D01*
X1062400Y-71227D01*
Y-72800D01*
G01D02*
Y-74771D01*
X1062071Y-75100D01*
Y-76578D01*
G01X1076960Y-63832D02*
Y-61160D01*
X1075800Y-60000D01*
X1072400D01*
X1071840Y-59440D01*
Y-56432D01*
G01X1074400D02*
Y-50694D01*
G01X1078900Y-45782D02*
X1074400D01*
G01Y-50694D02*
Y-45782D01*
G01Y-73618D02*
Y-69174D01*
G01X1070918Y-73618D02*
X1074400D01*
G01Y-69174D02*
Y-63832D01*
G01X1077505Y22405D02*
X1073400D01*
G01D02*
X1069668D01*
G01X1123031Y40158D02*
X1102342D01*
X1098761Y43739D01*
X1096661D01*
X1091500Y48900D01*
X1067200D01*
G01X1072205Y31082D02*
X1076418D01*
G01X1067705Y35182D02*
X1076944D01*
G01X1077260Y42612D02*
X1077253D01*
Y42682D01*
X1067705D01*
G01X1072200Y52000D02*
X1077400D01*
G01X1072205Y38982D02*
X1077082D01*
G01X1072382Y46195D02*
X1076905D01*
G01X1067805Y27282D02*
X1076299D01*
G01X1115157Y67717D02*
X1112483D01*
X1110600Y69600D01*
Y75800D01*
X1106800Y79600D01*
X1103100D01*
X1099200Y83500D01*
X1085596D01*
X1081561Y79465D01*
X1073598D01*
G01D02*
X1066354D01*
G01X1049787Y429753D02*
X1053774D01*
G01X1105315Y423228D02*
Y424985D01*
X1098200Y432100D01*
X1059261D01*
X1056914Y429753D01*
X1053774D01*
G01X1046287D02*
X1042769D01*
X1040180Y432342D01*
Y437510D01*
G01X1053721Y434409D02*
X1049751D01*
G01X1105315Y431102D02*
X1100174Y436243D01*
X1057658D01*
X1055824Y434409D01*
X1053721D01*
G01X1043500Y446600D02*
X1047853D01*
G01D02*
X1048500D01*
X1049750Y445350D01*
Y442000D01*
G01D02*
X1073700D01*
X1086890Y455190D01*
X1099590D01*
X1102499Y458099D01*
X1106801D01*
X1114400Y450500D01*
X1116280D01*
X1123031Y443749D01*
Y442913D01*
G01X1097441Y529527D02*
X1092767Y524853D01*
X1051915D01*
G01X1105315Y525590D02*
Y523115D01*
X1100453Y518253D01*
X1051915D01*
G01X1123031Y521653D02*
X1119386Y518008D01*
Y509298D01*
X1116545Y506457D01*
X1112531D01*
X1110095Y504021D01*
Y500339D01*
X1108349Y498593D01*
X1103917D01*
X1099980Y502530D01*
X1093608D01*
X1090436Y505702D01*
X1051957D01*
G01X1115157Y517716D02*
X1111782Y514341D01*
Y510261D01*
X1107052Y505531D01*
X1102588D01*
X1098839Y509280D01*
X1089626D01*
X1086604Y512302D01*
X1051957D01*
G01X1049965Y557053D02*
X1053700D01*
G01X1115157Y549212D02*
X1112982Y551387D01*
X1109651D01*
X1107838Y553200D01*
X1103400D01*
X1099547Y557053D01*
X1053700D01*
G01X1097441Y576771D02*
X1092529D01*
X1088953Y580347D01*
X1051185D01*
G01X1105315Y572834D02*
X1100816Y577333D01*
Y578169D01*
X1098085Y580900D01*
X1093200D01*
X1087779Y586321D01*
X1051131D01*
G01X1123031Y584645D02*
Y585481D01*
X1115431Y593081D01*
X1103917D01*
X1100898Y596100D01*
X1092800D01*
X1090285Y598615D01*
X1051147D01*
G01X1115157Y580708D02*
X1111265Y584600D01*
X1102526D01*
X1099106Y588020D01*
X1091480D01*
X1087085Y592415D01*
X1051147D01*
G01X1097441Y561023D02*
X1096098Y562366D01*
X1051181D01*
G01X1115157Y564960D02*
X1110088D01*
X1106713Y561585D01*
X1103532D01*
X1100076Y565041D01*
X1089400D01*
X1086141Y568300D01*
X1051200D01*
G01X1123031Y568897D02*
X1102903D01*
X1098966Y572834D01*
X1091066D01*
X1089653Y574247D01*
X1051185D01*
G01X1049301Y835703D02*
X1044223D01*
G01X1054419Y839493D02*
Y835703D01*
G01D02*
X1049301D01*
G01X1044223D02*
Y838077D01*
X1042603Y839697D01*
Y845653D01*
G01X1050763Y829163D02*
X1046937D01*
G01D02*
X1045890D01*
X1044100Y830953D01*
X1040773D01*
G01X1040723Y835703D02*
X1040043Y836383D01*
Y845653D01*
G01X1040773Y830953D02*
Y835653D01*
X1040723Y835703D01*
G01X1042603Y861953D02*
Y867920D01*
X1042123Y868400D01*
G01D02*
Y872703D01*
G01D02*
Y877169D01*
X1042101Y877191D01*
G01X1046803Y872677D02*
Y868900D01*
G01X1045163Y861953D02*
Y866163D01*
X1046803Y867803D01*
Y868900D01*
G01X1043900Y908450D02*
Y911100D01*
X1042155Y912845D01*
G01X1048400Y908450D02*
X1043900D01*
G01X1053200D02*
Y910850D01*
X1051573Y912477D01*
G01X1057700Y908450D02*
X1053200D01*
G01X1073408Y942399D02*
X1069918D01*
G01X1115105Y988592D02*
X1113753Y987240D01*
Y972027D01*
X1101251Y959525D01*
X1075648D01*
X1069918Y953795D01*
Y942399D01*
G01X1109593Y988592D02*
X1111078Y987107D01*
Y973136D01*
X1100142Y962200D01*
X1074539D01*
X1064918Y952579D01*
Y942399D01*
G01D02*
X1060024D01*
X1058571Y943852D01*
G01X1078000Y1073750D02*
X1073500D01*
G01X1075980Y1084900D02*
Y1079392D01*
X1074292Y1077704D01*
G01X1073500Y1073750D02*
Y1076912D01*
X1074292Y1077704D01*
G01X1078540Y1084900D02*
X1078534D01*
Y1077715D01*
G01X1082500Y1073750D02*
X1082499D01*
X1078534Y1077715D01*
G01X1087000Y1073750D02*
X1082500D01*
G01X1091400Y1070900D02*
Y1072900D01*
X1086220Y1078080D01*
Y1084900D01*
G01X1069000Y1073750D02*
Y1076900D01*
X1069870Y1077770D01*
G01X1073420Y1084900D02*
Y1081320D01*
X1069870Y1077770D01*
G01X1092200Y1119150D02*
X1087700D01*
G01X1081100Y1107100D02*
Y1112100D01*
X1082112Y1113112D01*
X1085612D01*
X1086842Y1114342D01*
G01X1087700Y1119150D02*
Y1115200D01*
X1086842Y1114342D01*
G01X1078540Y1107100D02*
Y1112159D01*
X1079000Y1112619D01*
Y1115489D01*
G01D02*
Y1119250D01*
G01X1075980Y1107100D02*
Y1112127D01*
X1074500Y1113607D01*
Y1115393D01*
G01D02*
Y1119250D01*
G01X1079000Y1122750D02*
X1083352D01*
X1083355Y1122753D01*
G01D02*
Y1125903D01*
G01X1074500Y1122750D02*
X1070158D01*
X1070155Y1122753D01*
G01D02*
Y1125903D01*
G01X1048960Y1106100D02*
Y1113900D01*
G01Y1117700D02*
X1046400Y1115140D01*
Y1106100D01*
G01X1041280Y1121500D02*
X1043840Y1118940D01*
Y1106100D01*
G01X1041280D02*
Y1113900D01*
G01X1081078Y1095362D02*
Y1084922D01*
X1081100Y1084900D01*
G01X1083660D02*
Y1092700D01*
G01X1041280Y1083900D02*
Y1091700D01*
G01Y1100500D02*
Y1099520D01*
X1043840Y1096960D01*
Y1083900D01*
G01X1048960Y1095500D02*
X1046400Y1092940D01*
Y1083900D01*
G01X1048960D02*
Y1091700D01*
G01Y1099300D02*
X1051520Y1096740D01*
Y1083900D01*
G01X1054080Y1106100D02*
Y1113900D01*
G01Y1117700D02*
X1051520Y1115140D01*
Y1106100D01*
G01X1041975Y1349992D02*
X1048251D01*
G01X1046372Y1356326D02*
X1044572Y1354526D01*
X1042039D01*
G01X1089318Y-87500D02*
X1089300Y-87482D01*
Y-82962D01*
G01X1089318Y-87500D02*
Y-91682D01*
G01X1089300Y-82962D02*
Y-77432D01*
G01X1094300Y-84700D02*
X1091860Y-82260D01*
Y-77432D01*
G01X1089300Y-60300D02*
Y-64555D01*
G01X1094300Y-60300D02*
X1089300D01*
G01Y-64555D02*
Y-70032D01*
G01X1104802Y-65121D02*
Y-61502D01*
X1103300Y-60000D01*
G01X1109922Y-65121D02*
Y-61466D01*
X1111095Y-60293D01*
X1111778D01*
G01D02*
X1115603D01*
G01X1115157Y51969D02*
X1118489Y55301D01*
Y65094D01*
X1121575Y68180D01*
X1124345D01*
X1127976Y71811D01*
Y85884D01*
X1143452Y101360D01*
X1172375D01*
G01X1123031Y63780D02*
X1125224D01*
X1131028Y69584D01*
Y85152D01*
X1142670Y96794D01*
X1171552D01*
G01X1190200Y301168D02*
Y303268D01*
X1182372Y311096D01*
X1179184D01*
X1101417Y388863D01*
Y403582D01*
X1105315Y407480D01*
G01X1185588Y301468D02*
Y305016D01*
X1181825Y308779D01*
X1176860D01*
X1093407Y392232D01*
Y407383D01*
X1097441Y411417D01*
G01X1180953Y303520D02*
X1178108Y306365D01*
X1175835D01*
X1090637Y391563D01*
Y420361D01*
X1097441Y427165D01*
G01X1123031Y339371D02*
X1138569D01*
X1176272Y301668D01*
G01X1105315Y391732D02*
X1108443D01*
X1182411Y317764D01*
G01X1115157Y407480D02*
X1124120D01*
X1144625Y386975D01*
Y359375D01*
X1189924Y314076D01*
G01X1123031Y411417D02*
X1123967D01*
X1147300Y388084D01*
Y360546D01*
X1178081Y329765D01*
G01X1105315Y557086D02*
X1110384D01*
X1113759Y553711D01*
X1116870D01*
X1120807Y549774D01*
X1128704D01*
X1217601Y460877D01*
Y362399D01*
X1227100Y352900D01*
Y275700D01*
X1220200Y268800D01*
G01X1123031Y553149D02*
X1129113D01*
X1220276Y461986D01*
Y363508D01*
X1258463Y325321D01*
X1550529D01*
X1589100Y286750D01*
Y146241D01*
G01X1176835Y611182D02*
X1173835D01*
X1149065Y586412D01*
Y581334D01*
X1123031Y555300D01*
Y553149D01*
G01X1119700Y1073850D02*
X1115200D01*
G01X1118980Y1084900D02*
Y1079449D01*
X1120179Y1078250D01*
G01D02*
Y1074329D01*
X1119700Y1073850D01*
G01X1121540Y1084900D02*
Y1082310D01*
X1125362Y1078488D01*
G01X1124500Y1073850D02*
Y1077626D01*
X1125362Y1078488D01*
G01X1128900Y1073850D02*
X1124500D01*
G01X1091494Y1075994D02*
X1088780Y1078708D01*
Y1084900D01*
G01X1097800Y1070700D02*
X1094000Y1074500D01*
Y1076831D01*
X1091340Y1079491D01*
Y1084900D01*
G01X1097500Y1075100D02*
Y1076195D01*
X1093900Y1079795D01*
Y1084900D01*
G01X1103800Y1070600D02*
X1100150Y1074250D01*
Y1076750D01*
X1096460Y1080440D01*
Y1084900D01*
G01X1103800Y1075600D02*
Y1076200D01*
X1099020Y1080980D01*
Y1084900D01*
G01X1116420D02*
Y1079375D01*
X1115520Y1078475D01*
G01X1110500Y1073850D02*
X1110895D01*
X1115520Y1078475D01*
G01X1124100Y1107100D02*
Y1110738D01*
X1127100Y1113738D01*
G01X1128800Y1118450D02*
X1124100D01*
G01D02*
X1127100Y1115450D01*
Y1113738D01*
G01X1121540Y1107100D02*
Y1110957D01*
X1122500Y1111917D01*
Y1113770D01*
G01D02*
Y1115450D01*
X1119500Y1118450D01*
G01X1115000D02*
Y1116770D01*
X1118000Y1113770D01*
G01D02*
X1118980Y1112790D01*
Y1107100D01*
G01X1119500Y1121950D02*
Y1125100D01*
G01X1115000Y1121950D02*
Y1125100D01*
G01X1123600Y1096400D02*
X1121500Y1094300D01*
Y1091500D01*
X1124100Y1088900D01*
Y1084900D01*
G01X1123838Y1092800D02*
X1126660Y1089978D01*
Y1084900D01*
G01X1123600Y1100000D02*
X1124900D01*
X1129220Y1095680D01*
Y1084900D01*
G01X1133981Y1096283D02*
X1131780Y1094082D01*
Y1084900D01*
G01X1134340D02*
Y1092262D01*
X1134002Y1092600D01*
G01X1134103Y1099881D02*
X1136900Y1097084D01*
Y1084900D01*
G01Y1107100D02*
Y1113494D01*
X1136007Y1114387D01*
G01D02*
Y1123321D01*
X1137436Y1124750D01*
G01X1101580Y1107100D02*
Y1112142D01*
X1103064Y1113626D01*
G01X1099020Y1107100D02*
Y1112276D01*
G01X1096460Y1107100D02*
Y1115125D01*
G01X1093900Y1107100D02*
Y1112304D01*
X1092742Y1113462D01*
G01X1176500Y1127000D02*
Y1146753D01*
X1159573Y1163680D01*
X1118528D01*
X1115105Y1160257D01*
G01X1113530Y1266556D02*
Y1267630D01*
X1115800Y1269900D01*
X1177600D01*
X1181400Y1266100D01*
G01X1184000Y1260100D02*
X1167500D01*
X1165100Y1262500D01*
X1112624D01*
X1109593Y1259469D01*
G01X1176799Y101360D02*
Y102780D01*
X1178656Y104637D01*
G01X1172375Y101360D02*
X1176799D01*
G01X1176952Y93390D02*
Y96794D01*
G01X1171552D02*
X1176952D01*
G01X1171749Y259163D02*
Y276426D01*
X1172973Y277650D01*
X1176100D01*
G01Y262750D02*
Y259500D01*
X1175400Y258800D01*
G01X1181145Y264900D02*
Y261196D01*
X1178900Y258951D01*
Y250450D01*
X1179550Y249800D01*
G01X1185100Y245100D02*
X1183900D01*
X1183050Y245950D01*
Y249800D01*
G01X1180953Y296235D02*
Y303520D01*
G01X1176300Y296150D02*
X1174150D01*
X1172900Y294900D01*
Y287900D01*
X1176300Y284500D01*
G01Y296150D02*
Y301640D01*
X1176272Y301668D01*
G01X1180953Y292735D02*
Y288600D01*
G01D02*
Y284800D01*
G01X1176100Y277650D02*
X1178350D01*
X1181145Y274855D01*
Y274100D01*
G01D02*
Y270978D01*
X1183023Y269100D01*
X1188318D01*
X1192300Y265118D01*
G01X1181145Y264900D02*
X1179300D01*
X1177150Y262750D01*
X1176100D01*
G01X1182411Y317764D02*
X1189700Y310475D01*
Y308527D01*
G01X1178081Y329765D02*
X1198100Y309746D01*
Y306858D01*
G01X1172736Y1031786D02*
X1175491Y1029031D01*
X1188400D01*
G01X1177036Y1032086D02*
X1178681Y1033731D01*
X1189900D01*
G01X1148997Y1097672D02*
X1146172D01*
X1139460Y1090960D01*
Y1084900D01*
G01X1152880Y1097672D02*
X1148997D01*
G01X1142020Y1084900D02*
Y1088478D01*
X1144662Y1091120D01*
X1148827D01*
X1148830Y1091117D01*
G01D02*
X1148833Y1091120D01*
X1152664D01*
X1152682Y1091138D01*
G01X1144580Y1107100D02*
Y1111751D01*
X1145936Y1113107D01*
G01D02*
X1148633Y1115804D01*
X1149984D01*
G01X1142020Y1107100D02*
Y1114701D01*
G01D02*
Y1118787D01*
X1143550Y1120317D01*
G01X1138679Y1117874D02*
X1138747Y1117806D01*
Y1115029D01*
X1139460Y1114316D01*
Y1107100D01*
G01X1138679Y1117874D02*
X1138747Y1117942D01*
Y1121040D01*
X1139524Y1121817D01*
G01X1176500Y1120250D02*
Y1127000D01*
G01X1215547Y256765D02*
Y261747D01*
X1215600Y261800D01*
G01X1224960Y236291D02*
X1228600D01*
X1229031Y235860D01*
X1233900D01*
G01X1224960Y236291D02*
X1225008Y236339D01*
Y239692D01*
X1223600Y241100D01*
G01D02*
Y241101D01*
X1219962Y244739D01*
G01X1190882Y249800D02*
Y255782D01*
G01D02*
Y258618D01*
X1187055Y262445D01*
Y264900D01*
G01X1185100Y245100D02*
X1186700D01*
X1187382Y245782D01*
Y249800D01*
G01X1190200Y296150D02*
Y301168D01*
G01X1185588Y296200D02*
Y301468D01*
G01X1220200Y268800D02*
X1215547Y264147D01*
Y261853D01*
X1215600Y261800D01*
G01X1194600Y296150D02*
Y303627D01*
X1189700Y308527D01*
G01X1190200Y288892D02*
Y285023D01*
G01Y292650D02*
Y288892D01*
G01X1199000Y295750D02*
Y302484D01*
X1201835Y305319D01*
G01X1189924Y314076D02*
X1193800Y310200D01*
Y307857D01*
G01X1185588Y292700D02*
Y288981D01*
G01D02*
Y285035D01*
G01X1197100Y275950D02*
X1195150D01*
X1193400Y277700D01*
X1192600D01*
G01D02*
X1188200D01*
X1187055Y276555D01*
Y274100D01*
G01X1197100Y275950D02*
Y279300D01*
X1197000Y279400D01*
G01X1187055Y264900D02*
X1188500D01*
X1191700Y261700D01*
X1194700D01*
G01X1188900Y281300D02*
X1190300Y282700D01*
X1197394D01*
X1198100Y283406D01*
Y284750D01*
G01D02*
Y288003D01*
X1199000Y288903D01*
Y292250D01*
G01X1185085Y274100D02*
Y277485D01*
X1188900Y281300D01*
G01X1192300Y268618D02*
Y273100D01*
X1192600Y273400D01*
G01D02*
X1194200D01*
X1195150Y272450D01*
X1197100D01*
G01X1239758Y489880D02*
Y470710D01*
X1229269Y460221D01*
Y360888D01*
X1232557Y357600D01*
X1238081D01*
X1241869Y361388D01*
Y365630D01*
X1242718Y366479D01*
Y368779D01*
G01X1250660Y478500D02*
X1231469Y459309D01*
Y361800D01*
X1233469Y359800D01*
X1237169D01*
X1239669Y362300D01*
Y365588D01*
X1238778Y366479D01*
Y368779D01*
G01X1242718Y821534D02*
Y819234D01*
X1241869Y818385D01*
Y814143D01*
X1238081Y810355D01*
X1232557D01*
X1227769Y815143D01*
Y881267D01*
X1240222Y893720D01*
Y911913D01*
G01X1238778Y821534D02*
Y819234D01*
X1239669Y818343D01*
Y815055D01*
X1237169Y812555D01*
X1233469D01*
X1229969Y816055D01*
Y880355D01*
X1254331Y904717D01*
Y935742D01*
G01X1194379Y1029031D02*
X1188400D01*
G01X1189900Y1033731D02*
X1194379D01*
G01X1242718Y1280040D02*
Y1282640D01*
X1241750Y1283608D01*
Y1289612D01*
X1238362Y1293000D01*
X1217607D01*
X1211205Y1286598D01*
Y1174705D01*
G01Y1162194D02*
Y1174705D01*
G01X1216205Y1162194D02*
Y1182451D01*
G01X1221970Y1153391D02*
X1220723Y1152144D01*
Y1146560D01*
G01D02*
X1221783Y1145500D01*
X1226022D01*
X1226197Y1145325D01*
G01X1232842Y1140722D02*
X1227673D01*
X1226197Y1142198D01*
Y1145325D01*
G01X1225845Y1160891D02*
Y1196126D01*
X1238778Y1209059D01*
Y1222200D01*
G01Y1280040D02*
Y1282728D01*
X1239550Y1283500D01*
Y1286600D01*
X1237450Y1288700D01*
X1220719D01*
X1216205Y1284186D01*
Y1182451D01*
G01X1256500Y256161D02*
Y250161D01*
G01X1256750Y244861D02*
Y240661D01*
G01X1288878Y240492D02*
X1256919D01*
X1256750Y240661D01*
G01X1256500Y250161D02*
X1256750Y249911D01*
Y244861D01*
G01X1250500Y256161D02*
Y262600D01*
G01X1250410Y232959D02*
X1244141D01*
X1243800Y233300D01*
X1240400D01*
G01X1249000Y227700D02*
X1250410Y229110D01*
Y232959D01*
G01X1253300Y227700D02*
X1249000D01*
G01X1288878Y270492D02*
X1253508D01*
X1250500Y273500D01*
G01Y262600D02*
Y266600D01*
G01X1261500Y451500D02*
X1242718Y432718D01*
Y374529D01*
G01X1256500Y465200D02*
X1238778Y447478D01*
Y374529D01*
G01X1269878Y498421D02*
Y459878D01*
X1261500Y451500D01*
G01X1264878Y498421D02*
Y473578D01*
X1256500Y465200D01*
G01X1239758Y499401D02*
Y489880D01*
G01X1253867Y499400D02*
Y481707D01*
X1250660Y478500D01*
G01X1244910Y513555D02*
X1239497D01*
X1239374Y513432D01*
G01X1243633Y506901D02*
X1244910Y508178D01*
Y513555D01*
G01X1239362Y524168D02*
X1239374Y524156D01*
Y513432D01*
G01X1257742Y506900D02*
X1259426Y508584D01*
Y513463D01*
G01X1253511D02*
X1259426D01*
G01X1253511Y517606D02*
Y513463D01*
G01X1254750Y693417D02*
X1254919Y693248D01*
X1288878D01*
G01X1254750Y697850D02*
Y693417D01*
G01X1254000Y722917D02*
X1254331Y723248D01*
X1288878D01*
G01X1254500Y708917D02*
Y702917D01*
G01D02*
X1254750Y702667D01*
Y697850D01*
G01X1268400Y716100D02*
X1251800D01*
X1250660Y714960D01*
G01X1248500Y708917D02*
Y712800D01*
X1250660Y714960D01*
G01X1268742Y922198D02*
Y908742D01*
X1242718Y882718D01*
Y827284D01*
G01X1263742Y938298D02*
Y907842D01*
X1238778Y882878D01*
Y827284D01*
G01X1268742Y950586D02*
Y922198D01*
G01X1240222Y951942D02*
Y911913D01*
G01X1254331Y951941D02*
Y935742D01*
G01X1263742Y938298D02*
Y950586D01*
G01X1239826Y965973D02*
X1245251D01*
G01D02*
X1245374Y965850D01*
Y960719D01*
X1244097Y959442D01*
G01X1253338Y980784D02*
X1250484D01*
X1239826Y970126D01*
Y965973D01*
G01X1253975Y966004D02*
Y970147D01*
G01Y966004D02*
X1259296D01*
X1259600Y965700D01*
G01D02*
X1259890Y965410D01*
Y961125D01*
X1258206Y959441D01*
G01X1253900Y1176000D02*
X1253904Y1176004D01*
X1288878D01*
G01X1254750Y1155423D02*
Y1150173D01*
G01X1255800Y1161800D02*
Y1158500D01*
X1254750Y1157450D01*
Y1155423D01*
G01Y1146173D02*
X1254919Y1146004D01*
X1288878D01*
G01X1254750Y1150173D02*
Y1146173D01*
G01X1260300Y1169000D02*
X1251700D01*
X1251053Y1168353D01*
G01X1249800Y1161800D02*
Y1167100D01*
X1251053Y1168353D01*
G01X1236070Y1153364D02*
X1234600Y1151894D01*
Y1146448D01*
X1234995Y1146053D01*
G01D02*
X1235635Y1145413D01*
X1240314D01*
G01D02*
Y1139741D01*
G01X1239945Y1160864D02*
Y1176309D01*
X1242718Y1179082D01*
Y1190900D01*
G01D02*
Y1274290D01*
G01X1238778D02*
Y1222200D01*
G01X1323829Y55929D02*
X1325735Y57835D01*
Y65129D01*
G01X1328295D02*
Y55800D01*
G01X1304563Y91008D02*
Y96258D01*
G01D02*
Y100771D01*
G01X1325601Y96135D02*
Y92385D01*
X1323181Y89965D01*
G01X1318821Y86205D02*
X1319421D01*
X1323181Y89965D01*
G01X1314071Y86155D02*
X1318771D01*
X1318821Y86205D01*
G01X1328161Y96135D02*
Y90500D01*
G01X1327921Y86205D02*
X1328161Y86445D01*
Y90500D01*
G01X1323521Y86205D02*
X1327921D01*
G01X1299569Y90941D02*
Y96258D01*
G01D02*
Y100639D01*
G01X1317900Y90500D02*
X1314426D01*
X1314071Y90855D01*
G01X1323041Y96135D02*
Y93141D01*
X1320400Y90500D01*
X1317900D01*
G01X1314071Y90855D02*
Y92710D01*
X1315961Y94600D01*
Y98112D01*
G01X1328161Y118335D02*
Y123635D01*
X1327307Y124489D01*
G01X1328534Y130338D02*
Y128083D01*
X1327307Y126856D01*
Y124489D01*
G01X1319797Y130338D02*
Y125693D01*
X1319807Y125683D01*
G01X1325601Y118335D02*
Y121899D01*
X1323465Y124035D01*
X1321455D01*
X1319807Y125683D01*
G01X1324207Y138756D02*
Y133853D01*
G01D02*
X1324222Y133838D01*
X1328534D01*
G01X1315115Y133850D02*
X1315102Y133863D01*
Y137903D01*
G01X1319797Y133838D02*
X1319785Y133850D01*
X1315115D01*
G01X1311200Y178161D02*
X1317000D01*
G01X1321900Y178311D02*
X1321750Y178161D01*
X1317000D01*
G01X1303800Y175601D02*
X1301000D01*
X1299000Y177601D01*
Y183900D01*
X1301300Y186200D01*
X1308250D01*
G01D02*
Y191161D01*
G01Y195261D02*
Y200411D01*
X1308500Y200661D01*
G01X1308250Y191161D02*
Y195261D01*
G01X1324500Y194661D02*
X1323500Y193661D01*
Y188161D01*
G01X1329250Y194661D02*
X1324500D01*
G01X1311200Y180721D02*
X1314560D01*
X1315650Y181811D01*
X1321900D01*
G01D02*
X1326400D01*
G01D02*
Y183900D01*
X1323500Y186800D01*
Y188161D01*
G01X1322000Y169411D02*
X1317000D01*
G01D02*
X1312000D01*
G01X1307500D02*
Y177661D01*
X1307000Y178161D01*
X1303800D01*
G01X1312000Y169411D02*
X1307500D01*
G01X1322000Y165911D02*
X1326300D01*
G01X1333988Y161471D02*
X1329548Y165911D01*
X1326300D01*
G01X1311200Y630917D02*
X1317000D01*
G01X1322000Y631067D02*
X1321850Y630917D01*
X1317000D01*
G01X1303800Y628357D02*
X1301000D01*
X1299000Y630357D01*
Y638917D01*
X1302500Y642417D01*
G01X1308250Y648017D02*
Y643917D01*
G01D02*
X1304000D01*
X1302500Y642417D01*
G01X1324500Y647417D02*
X1323500Y646417D01*
Y640917D01*
G01X1329250Y647417D02*
X1324500D01*
G01X1311200Y633477D02*
X1314560D01*
X1315650Y634567D01*
X1322000D01*
G01D02*
X1326500D01*
G01D02*
Y636800D01*
X1323500Y639800D01*
Y640917D01*
G01X1322000Y622167D02*
X1317000D01*
G01D02*
X1312000D01*
G01X1307500D02*
Y630417D01*
X1307000Y630917D01*
X1303800D01*
G01X1312000Y622167D02*
X1307500D01*
G01X1322000Y618667D02*
X1326423D01*
G01D02*
X1327667D01*
X1336000Y627000D01*
G01X1308500Y653417D02*
X1308250Y653167D01*
Y648017D01*
G01X1303800Y1081113D02*
X1301000D01*
X1299000Y1083113D01*
Y1091673D01*
X1302500Y1095173D01*
G01X1305100Y1074923D02*
Y1076999D01*
X1307100Y1078999D01*
Y1082897D01*
X1306324Y1083673D01*
X1303800D01*
G01X1309600Y1074923D02*
X1305100D01*
G01X1313400D02*
X1309600D01*
G01X1313400D02*
X1317373D01*
X1317400Y1074950D01*
G01Y1071450D02*
Y1068000D01*
G01X1311200Y1083673D02*
X1317000D01*
G01X1322000Y1083823D02*
X1321850Y1083673D01*
X1317000D01*
G01X1308500Y1106173D02*
X1308250Y1105923D01*
Y1100773D01*
G01D02*
Y1096673D01*
G01D02*
X1304000D01*
X1302500Y1095173D01*
G01X1311200Y1086233D02*
X1314560D01*
X1315650Y1087323D01*
X1322000D01*
G01X1329250Y1100173D02*
X1324500D01*
G01D02*
X1323500Y1099173D01*
Y1093673D01*
G01X1322000Y1087323D02*
X1326500D01*
G01D02*
Y1089400D01*
X1323500Y1092400D01*
Y1093673D01*
G01X1354437Y81488D02*
X1358355D01*
G01X1338215Y107586D02*
X1333281Y112520D01*
Y118335D01*
G01X1336034Y82542D02*
Y85294D01*
X1336516Y85776D01*
Y87410D01*
G01X1335841Y96135D02*
Y90043D01*
X1336516Y89368D01*
Y87410D01*
G01X1334383Y75892D02*
X1334598D01*
X1337176Y78470D01*
G01X1338401Y96135D02*
Y92187D01*
X1338936Y91652D01*
Y84936D01*
X1338500Y84500D01*
Y81564D01*
X1337176Y80240D01*
Y78470D01*
G01X1340961Y96135D02*
Y82656D01*
G01D02*
Y78811D01*
G01X1343521Y96135D02*
Y89403D01*
G01D02*
Y85472D01*
G01X1346081Y96135D02*
Y80671D01*
G01X1348641Y96135D02*
Y87218D01*
G01D02*
Y83326D01*
G01X1352351Y101724D02*
X1352817Y102190D01*
Y113648D01*
X1351201Y115264D01*
Y118335D01*
G01X1350779Y106496D02*
Y112544D01*
X1348641Y114682D01*
Y118335D01*
G01Y110550D02*
X1346081Y113110D01*
Y118335D01*
G01X1330721Y96135D02*
Y84656D01*
X1331759Y83618D01*
Y80400D01*
G01X1330855Y71629D02*
Y75855D01*
X1331759Y76759D01*
Y80400D01*
G01X1333281Y96135D02*
Y90526D01*
G01D02*
Y85133D01*
G01X1349931Y134433D02*
Y138361D01*
G01X1345753Y133842D02*
X1349340D01*
X1349931Y134433D01*
G01X1338400Y126015D02*
X1338481D01*
X1335841Y123375D01*
Y118335D01*
G01X1331365Y125601D02*
Y128769D01*
X1332934Y130338D01*
G01X1330721Y118335D02*
Y122769D01*
X1331365Y123413D01*
Y125601D01*
G01X1332934Y130338D02*
X1337634D01*
G01X1343521Y118335D02*
Y121425D01*
X1346678Y124582D01*
X1351008D01*
G01X1351665Y128325D02*
X1351008Y127668D01*
Y124582D01*
G01X1336500Y194661D02*
X1332750D01*
G01D02*
Y188411D01*
X1332500Y188161D01*
G01X1335250Y223661D02*
X1338000Y220911D01*
Y196161D01*
X1336500Y194661D01*
G01X1333500Y234161D02*
Y232411D01*
X1335250Y230661D01*
Y227761D01*
G01D02*
Y223661D01*
G01X1374713Y256161D02*
Y263900D01*
G01X1384713Y323200D02*
Y283013D01*
X1374713Y273013D01*
Y263900D01*
G01X1366931Y368779D02*
Y366479D01*
X1366082Y365630D01*
Y361388D01*
X1362294Y357600D01*
X1356770D01*
X1347982Y366388D01*
Y482100D01*
G01X1366931Y374529D02*
Y402900D01*
G01D02*
Y489500D01*
X1364882Y491549D01*
Y498000D01*
G01X1362991Y374529D02*
Y429900D01*
G01Y368779D02*
Y366479D01*
X1363882Y365588D01*
Y362300D01*
X1361382Y359800D01*
X1358900D01*
X1356542Y362158D01*
Y458900D01*
G01X1359882Y498000D02*
Y491109D01*
X1362991Y488000D01*
Y429900D01*
G01X1336110Y499272D02*
Y493972D01*
X1347982Y482100D01*
G01X1350219Y499271D02*
Y489804D01*
X1356542Y483481D01*
Y458900D01*
G01X1339985Y506772D02*
X1341262Y508049D01*
Y513426D01*
G01X1335726Y513303D02*
X1341139D01*
X1341262Y513426D01*
G01X1338100Y520300D02*
X1336100Y518300D01*
Y513677D01*
X1335726Y513303D01*
G01X1354094Y506771D02*
X1355778Y508455D01*
Y513334D01*
G01X1349863D02*
Y515263D01*
X1353500Y518900D01*
G01X1355778Y513334D02*
X1349863D01*
G01X1336500Y647417D02*
X1332750D01*
G01D02*
Y641167D01*
X1332500Y640917D01*
G01X1335250Y676417D02*
X1338000Y673667D01*
Y648917D01*
X1336500Y647417D01*
G01X1333500Y686917D02*
Y685167D01*
X1335250Y683417D01*
Y680517D01*
G01D02*
Y676417D01*
G01X1383952Y717435D02*
X1376735D01*
X1374839Y715539D01*
G01X1372713Y708917D02*
Y713413D01*
X1374839Y715539D01*
G01X1366931Y827284D02*
Y921200D01*
G01X1362991Y827284D02*
Y888400D01*
G01X1366931Y821534D02*
Y819031D01*
X1366082Y818182D01*
Y814143D01*
X1362294Y810355D01*
X1356770D01*
X1351982Y815143D01*
Y918518D01*
X1345800Y924700D01*
G01X1354301Y935405D02*
X1356542Y933164D01*
Y817395D01*
X1358882Y815055D01*
X1362238D01*
X1363882Y816699D01*
Y818343D01*
X1362991Y819234D01*
Y821534D01*
G01X1362382Y950755D02*
X1362991Y950146D01*
Y888400D01*
G01X1366931Y921200D02*
Y950304D01*
X1367382Y950755D01*
G01X1338611Y952153D02*
Y931889D01*
X1345800Y924700D01*
G01X1352803Y952194D02*
Y936903D01*
X1354301Y935405D01*
G01X1343677Y965649D02*
X1343501Y965825D01*
X1338255D01*
G01X1342486Y959653D02*
X1343677Y960844D01*
Y965649D01*
G01X1338255Y965825D02*
Y967755D01*
X1339404Y968904D01*
Y969600D01*
G01X1356678Y959694D02*
X1358581Y961597D01*
Y966602D01*
G01X1352296Y965705D02*
Y968420D01*
X1353762Y969886D01*
G01X1352296Y965705D02*
X1354632D01*
X1355727Y966800D01*
X1358383D01*
X1358581Y966602D01*
G01X1336500Y1100173D02*
X1332750D01*
G01X1335250Y1133273D02*
Y1129173D01*
G01X1332750Y1100173D02*
Y1093923D01*
X1332500Y1093673D01*
G01X1335250Y1129173D02*
X1344927D01*
X1352500Y1121600D01*
Y1106800D01*
X1345873Y1100173D01*
X1336500D01*
G01X1357711Y1131655D02*
X1356639Y1130583D01*
Y1123408D01*
G01D02*
X1356682Y1123365D01*
X1361904D01*
G01D02*
Y1115395D01*
X1361074Y1114565D01*
G01X1333500Y1139673D02*
Y1137923D01*
X1335250Y1136173D01*
Y1133273D01*
G01X1346321Y1182700D02*
Y1162153D01*
G01X1351321D02*
Y1211900D01*
G01X1374000Y1161700D02*
Y1167700D01*
X1375687Y1169387D01*
X1375887D01*
G01X1383899Y1166690D02*
X1381202Y1169387D01*
X1375887D01*
G01X1361213Y1147073D02*
X1355427D01*
X1355100Y1147400D01*
G01X1361213Y1147073D02*
Y1144842D01*
X1360238Y1143867D01*
G01X1355100Y1147400D02*
X1354700Y1147800D01*
Y1151005D01*
X1356919Y1153224D01*
G01X1366931Y1198700D02*
Y1178663D01*
X1368363Y1177231D01*
Y1142663D01*
X1364855Y1139155D01*
X1361586D01*
G01X1360794Y1160724D02*
Y1177745D01*
X1362991Y1179942D01*
Y1254400D01*
G01X1346321Y1182700D02*
Y1284370D01*
X1354951Y1293000D01*
X1362575D01*
X1365963Y1289612D01*
Y1283608D01*
X1366931Y1282640D01*
Y1280040D01*
G01X1351321Y1211900D02*
Y1281958D01*
X1358063Y1288700D01*
X1361663D01*
X1363763Y1286600D01*
Y1283500D01*
X1362991Y1282728D01*
Y1280040D01*
G01X1366931Y1198700D02*
Y1274290D01*
G01X1362991D02*
Y1254400D01*
G01X1428013Y175601D02*
X1425213D01*
X1423213Y177601D01*
Y185718D01*
X1425796Y188301D01*
X1430785D01*
X1432463Y186623D01*
G01X1380713Y256161D02*
Y251400D01*
G01X1413091Y240492D02*
X1381132D01*
X1380963Y240661D01*
G01D02*
Y244825D01*
X1380959Y244829D01*
G01D02*
Y249915D01*
X1380713Y250161D01*
Y251400D01*
G01X1378700Y270400D02*
X1378792Y270492D01*
X1413091D01*
G01X1428013Y628357D02*
X1425213D01*
X1423213Y630357D01*
Y638917D01*
X1426713Y642417D01*
G01X1378963Y693417D02*
X1379132Y693248D01*
X1413091D01*
G01X1378963Y697517D02*
Y693417D01*
G01X1378213Y722917D02*
X1383169D01*
X1383500Y723248D01*
X1413091D01*
G01X1378713Y708917D02*
Y702917D01*
G01D02*
X1378963Y702667D01*
Y697517D01*
G01X1428013Y1081113D02*
X1425213D01*
X1423213Y1083113D01*
Y1091673D01*
X1426713Y1095173D01*
G01X1378400Y1176000D02*
X1378404Y1176004D01*
X1413091D01*
G01X1378963Y1155600D02*
Y1150273D01*
G01X1380000Y1161700D02*
Y1158000D01*
X1378963Y1156963D01*
Y1155600D01*
G01Y1146173D02*
X1379132Y1146004D01*
X1413091D01*
G01X1378963Y1150273D02*
Y1146173D01*
G01X1435413Y178161D02*
X1441213D01*
G01X1446013Y178311D02*
X1445863Y178161D01*
X1441213D01*
G01X1460713Y194661D02*
X1456963D01*
G01D02*
Y188411D01*
X1456713Y188161D01*
G01X1459463Y223661D02*
X1462213Y220911D01*
Y196161D01*
X1460713Y194661D01*
G01X1432463Y186623D02*
Y191161D01*
G01Y195261D02*
Y200411D01*
X1432713Y200661D01*
G01X1432463Y191161D02*
Y195261D01*
G01X1448713Y194661D02*
X1447713Y193661D01*
Y188161D01*
G01X1453463Y194661D02*
X1448713D01*
G01X1435413Y180721D02*
X1438773D01*
X1439863Y181811D01*
X1446013D01*
G01D02*
X1450713D01*
G01D02*
Y183987D01*
X1447713Y186987D01*
Y188161D01*
G01X1446213Y169411D02*
X1441213D01*
G01D02*
X1436213D01*
G01X1431713D02*
Y177661D01*
X1431213Y178161D01*
X1428013D01*
G01X1436213Y169411D02*
X1431713D01*
G01X1446213Y165911D02*
X1446239Y165937D01*
X1450700D01*
G01D02*
X1453339D01*
X1456373Y168971D01*
G01X1457713Y234161D02*
Y232411D01*
X1459463Y230661D01*
Y227761D01*
G01D02*
Y223661D01*
G01X1491143Y368779D02*
Y366479D01*
X1490294Y365630D01*
Y361388D01*
X1486506Y357600D01*
X1480982D01*
X1472194Y366388D01*
Y448500D01*
G01X1453451Y499121D02*
Y493153D01*
X1472194Y474410D01*
Y448500D01*
G01X1463085Y494974D02*
Y503135D01*
G01X1463000Y490638D02*
X1463085Y490723D01*
Y494974D01*
G01X1472480Y499018D02*
Y485272D01*
X1477766Y479986D01*
G01X1463085Y503135D02*
X1460812D01*
X1457326Y506621D01*
G01X1463521Y567421D02*
X1464700Y568600D01*
Y573300D01*
G01X1474700Y569100D02*
Y572350D01*
G01X1462121Y559350D02*
Y566021D01*
X1463521Y567421D01*
G01X1470700Y572350D02*
X1469750Y573300D01*
X1464700D01*
G01X1474700Y572350D02*
X1470700D01*
G01X1467250Y556490D02*
X1469690D01*
X1474700Y561500D01*
G01X1482350Y560400D02*
X1481250Y561500D01*
X1474700D01*
G01Y554521D02*
X1466950D01*
G01X1482350Y556100D02*
X1480771Y554521D01*
X1474700D01*
G01X1435413Y630917D02*
X1441213D01*
G01X1446013Y631067D02*
X1445863Y630917D01*
X1441213D01*
G01X1460713Y647417D02*
X1456963D01*
G01D02*
Y641167D01*
X1456713Y640917D01*
G01X1459463Y676417D02*
X1462213Y673667D01*
Y648917D01*
X1460713Y647417D01*
G01X1432463Y648017D02*
Y643917D01*
G01D02*
X1428213D01*
X1426713Y642417D01*
G01X1448713Y647417D02*
X1447713Y646417D01*
Y640917D01*
G01X1453463Y647417D02*
X1448713D01*
G01X1435413Y633477D02*
X1438773D01*
X1439863Y634567D01*
X1446013D01*
G01D02*
X1450713D01*
G01D02*
Y635987D01*
X1447713Y638987D01*
Y640917D01*
G01X1446213Y622167D02*
X1441213D01*
G01D02*
X1436213D01*
G01X1431713D02*
Y630417D01*
X1431213Y630917D01*
X1428013D01*
G01X1436213Y622167D02*
X1431713D01*
G01X1446213Y618667D02*
X1451016D01*
G01X1455202Y618557D02*
X1455092Y618667D01*
X1451016D01*
G01X1457713Y686917D02*
Y685167D01*
X1459463Y683417D01*
Y680517D01*
G01D02*
Y676417D01*
G01X1432713Y653417D02*
X1432463Y653167D01*
Y648017D01*
G01X1491143Y821534D02*
Y819234D01*
X1490294Y818385D01*
Y814143D01*
X1487651Y811500D01*
X1483600D01*
X1479717Y815383D01*
Y923829D01*
X1466036Y937510D01*
G01X1462823Y952111D02*
Y940723D01*
X1466036Y937510D01*
G01X1462467Y965883D02*
Y968116D01*
X1463616Y969265D01*
G01X1467889Y965707D02*
X1467713Y965883D01*
X1462467D01*
G01X1466698Y959611D02*
X1467889Y960802D01*
Y965707D01*
G01X1446213Y1074923D02*
X1441213D01*
G01D02*
X1436213D01*
G01X1431713D02*
Y1083173D01*
X1431213Y1083673D01*
X1428013D01*
G01X1436213Y1074923D02*
X1431713D01*
G01X1446213Y1071423D02*
Y1066700D01*
G01D02*
Y1062300D01*
G01X1435413Y1083673D02*
X1441213D01*
G01X1446013Y1083823D02*
X1445863Y1083673D01*
X1441213D01*
G01X1460713Y1100173D02*
X1456963D01*
G01X1460713D02*
X1464284Y1103744D01*
Y1124352D01*
X1459463Y1129173D01*
G01D02*
Y1133273D01*
G01X1456963Y1100173D02*
Y1093923D01*
X1456713Y1093673D01*
G01X1432713Y1106173D02*
X1432463Y1105923D01*
Y1100773D01*
G01D02*
Y1096673D01*
G01D02*
X1428213D01*
X1426713Y1095173D01*
G01X1453463Y1100173D02*
X1448713D01*
G01X1435413Y1086233D02*
X1438773D01*
X1439863Y1087323D01*
X1446013D01*
G01X1447713Y1093673D02*
Y1099173D01*
X1448713Y1100173D01*
G01X1446013Y1087323D02*
X1450713D01*
G01D02*
Y1089387D01*
X1447713Y1092387D01*
Y1093673D01*
G01X1459463Y1133273D02*
Y1136173D01*
X1457713Y1137923D01*
Y1139673D01*
G01X1470953Y1162027D02*
Y1229771D01*
X1476175Y1234993D01*
Y1265600D01*
G01X1503025Y256061D02*
Y250061D01*
G01D02*
X1503275Y249811D01*
Y244661D01*
G01Y240561D02*
X1503344Y240492D01*
X1537303D01*
G01X1503275Y244661D02*
Y240561D01*
G01X1497025Y273400D02*
Y256061D01*
G01X1500900Y265600D02*
X1507900D01*
X1512792Y270492D01*
X1537303D01*
G01X1508925Y323200D02*
X1497025Y311300D01*
Y273400D01*
G01X1491143Y374529D02*
Y420100D01*
G01X1487203Y374529D02*
Y448300D01*
G01X1477766Y479986D02*
X1480754Y476998D01*
Y362246D01*
X1483200Y359800D01*
X1485594D01*
X1488094Y362300D01*
Y365588D01*
X1487203Y366479D01*
Y368779D01*
G01X1491594Y498000D02*
X1491143Y497549D01*
Y420100D01*
G01X1486594Y498000D02*
X1487203Y497391D01*
Y448300D01*
G01X1481938Y493921D02*
Y489926D01*
G01Y493921D02*
Y503020D01*
G01X1502400Y544100D02*
Y547400D01*
G01D02*
X1502025Y547775D01*
X1491108D01*
G01X1481938Y503020D02*
X1479853D01*
X1476355Y506518D01*
G01X1485850Y560400D02*
X1494400D01*
G01X1485850Y556100D02*
X1494400D01*
G01X1503175Y693417D02*
X1503344Y693248D01*
X1537303D01*
G01X1503175Y697517D02*
Y693417D01*
G01X1502425Y722917D02*
X1502756Y723248D01*
X1537303D01*
G01X1502925Y708917D02*
Y702917D01*
G01D02*
X1503175Y702667D01*
Y697517D01*
G01X1505900Y717600D02*
X1500200D01*
X1498349Y715749D01*
G01X1496925Y708917D02*
Y714325D01*
X1498349Y715749D01*
G01X1491143Y827284D02*
Y863600D01*
G01X1487203Y827284D02*
Y887900D01*
G01X1484054Y911900D02*
Y815046D01*
X1485000Y814100D01*
X1487139D01*
X1488094Y815055D01*
Y818343D01*
X1487203Y819234D01*
Y821534D01*
G01X1491143Y863600D02*
Y950304D01*
X1491594Y950755D01*
G01X1487203Y887900D02*
Y950146D01*
X1486594Y950755D01*
G01X1477015Y952152D02*
Y942428D01*
X1484054Y935389D01*
Y911900D01*
G01X1480890Y959652D02*
X1482793Y961555D01*
Y966760D01*
G01X1477974Y970044D02*
X1476508Y968578D01*
Y965763D01*
G01X1482793Y966760D02*
X1478997D01*
X1478000Y965763D01*
X1476508D01*
G01X1481346Y1126841D02*
X1479700Y1125195D01*
Y1118144D01*
X1479828Y1118016D01*
G01D02*
X1479901Y1117943D01*
X1485608D01*
G01D02*
Y1113628D01*
G01X1502300Y1176000D02*
X1502304Y1176004D01*
X1537303D01*
G01X1504700Y1156926D02*
Y1161700D01*
G01X1537303Y1146004D02*
X1503344D01*
X1503175Y1146173D01*
G01D02*
Y1150373D01*
G01D02*
Y1152017D01*
X1504700Y1153542D01*
Y1156926D01*
G01X1475953Y1162027D02*
Y1229669D01*
X1481175Y1234891D01*
Y1251700D01*
G01X1500838Y1167938D02*
X1504200Y1171300D01*
G01X1498700Y1161700D02*
Y1165800D01*
X1500838Y1167938D01*
G01X1485833Y1140369D02*
Y1144062D01*
G01X1480600Y1144400D02*
X1480300Y1144700D01*
Y1148323D01*
X1481593Y1149616D01*
Y1153308D01*
G01X1485833Y1144062D02*
X1480938D01*
X1480600Y1144400D01*
G01X1485221Y1134341D02*
X1489941D01*
X1493300Y1137700D01*
Y1159501D01*
X1491143Y1161658D01*
Y1211600D01*
G01X1485468Y1160808D02*
Y1179368D01*
X1487203Y1181103D01*
Y1234300D01*
G01X1491143Y1211600D02*
Y1274290D01*
G01Y1280040D02*
Y1282640D01*
X1490175Y1283608D01*
Y1289612D01*
X1486787Y1293000D01*
X1480663D01*
X1476175Y1288512D01*
Y1265600D01*
G01X1487203Y1280040D02*
Y1282728D01*
X1487975Y1283500D01*
Y1286600D01*
X1485875Y1288700D01*
X1483775D01*
X1481175Y1286100D01*
Y1251700D01*
G01X1487203Y1274290D02*
Y1234300D01*
G01X1532874Y100591D02*
X1574692D01*
X1589100Y114999D01*
Y146241D01*
G01X1532874Y106103D02*
X1576328D01*
X1585757Y115532D01*
Y121382D01*
G01X1559625Y178161D02*
X1565425D01*
G01X1570125Y178311D02*
X1569975Y178161D01*
X1565425D01*
G01X1556675Y186000D02*
Y191161D01*
G01X1552225Y175601D02*
X1549425D01*
X1547425Y177601D01*
Y183500D01*
X1549925Y186000D01*
X1556675D01*
G01Y195261D02*
Y200411D01*
X1556925Y200661D01*
G01X1556675Y191161D02*
Y195261D01*
G01X1559625Y180721D02*
X1562985D01*
X1564075Y181811D01*
X1570125D01*
G01D02*
X1574925D01*
G01X1570425Y169411D02*
X1565425D01*
G01D02*
X1560425D01*
G01X1555925D02*
Y177661D01*
X1555425Y178161D01*
X1552225D01*
G01X1560425Y169411D02*
X1555925D01*
G01X1570425Y165911D02*
X1575479D01*
G01X1559625Y630917D02*
X1565425D01*
G01X1570225Y631067D02*
X1570075Y630917D01*
X1565425D01*
G01X1551675Y650017D02*
Y645917D01*
G01Y640424D02*
Y645917D01*
G01Y640424D02*
Y638800D01*
X1547425Y634550D01*
Y630357D01*
X1549425Y628357D01*
X1552225D01*
G01X1566925Y642917D02*
X1569925D01*
X1571925Y640917D01*
Y639275D01*
X1574925Y636275D01*
Y634567D01*
G01X1559625Y633477D02*
X1562985D01*
X1564075Y634567D01*
X1570225D01*
G01D02*
X1574925D01*
G01X1567925Y649417D02*
X1566925Y648417D01*
Y642917D01*
G01X1570425Y622167D02*
X1565425D01*
G01D02*
X1560425D01*
G01X1555925D02*
Y630417D01*
X1555425Y630917D01*
X1552225D01*
G01X1560425Y622167D02*
X1555925D01*
G01X1570425Y618667D02*
X1575057D01*
G01X1551925Y655417D02*
X1551675Y655167D01*
Y650017D01*
G01X1572675Y649417D02*
X1567925D01*
G01X1552225Y1081113D02*
X1549425D01*
X1547425Y1083113D01*
Y1090973D01*
X1549425Y1092973D01*
G01X1570425Y1074923D02*
X1565425D01*
G01D02*
X1560425D01*
G01X1555925D02*
Y1083173D01*
X1555425Y1083673D01*
X1552225D01*
G01X1560425Y1074923D02*
X1555925D01*
G01X1570425Y1071423D02*
Y1067600D01*
G01D02*
Y1062000D01*
G01X1559625Y1083673D02*
X1565425D01*
G01X1570425Y1083923D02*
X1570175Y1083673D01*
X1565425D01*
G01X1549425Y1092973D02*
X1545100Y1097298D01*
Y1135600D01*
X1545873Y1136373D01*
X1549075D01*
G01Y1132273D02*
Y1125177D01*
X1549073Y1125175D01*
G01X1559625Y1086233D02*
X1562985D01*
X1564175Y1087423D01*
X1570425D01*
G01D02*
X1574925D01*
G01X1549075Y1136373D02*
Y1132273D01*
G01X1585757Y126254D02*
Y121382D01*
G01X1584925Y194661D02*
X1581175D01*
G01D02*
Y188411D01*
X1580925Y188161D01*
G01X1583675Y223661D02*
X1586425Y220911D01*
Y196161D01*
X1584925Y194661D01*
G01X1572925D02*
X1571925Y193661D01*
Y188161D01*
G01X1577675Y194661D02*
X1572925D01*
G01X1574925Y181811D02*
Y183875D01*
X1571925Y186875D01*
Y188161D01*
G01X1579371Y166019D02*
X1579263Y165911D01*
X1575479D01*
G01X1581925Y234161D02*
Y232411D01*
X1583675Y230661D01*
Y227761D01*
G01D02*
Y223661D01*
G01X1615356Y368779D02*
Y366479D01*
X1614507Y365630D01*
Y361388D01*
X1610719Y357600D01*
X1605195D01*
X1596407Y366388D01*
Y472700D01*
G01X1615356Y374529D02*
Y487800D01*
G01X1611416Y374529D02*
Y465200D01*
G01Y368779D02*
Y366479D01*
X1612307Y365588D01*
Y362300D01*
X1609807Y359800D01*
X1607200D01*
X1601101Y365899D01*
Y464367D01*
G01X1615807Y498000D02*
X1615356Y497549D01*
Y487800D01*
G01X1610807Y498000D02*
X1611416Y497391D01*
Y465200D01*
G01X1586992Y499356D02*
X1596407Y489941D01*
Y472700D01*
G01X1601101Y499355D02*
Y464367D01*
G01X1590867Y506856D02*
X1592144Y508133D01*
Y513510D01*
G01X1586608Y513387D02*
X1586596Y518723D01*
G01X1586608Y513387D02*
X1589077D01*
X1589200Y513510D01*
X1592144D01*
G01X1604976Y506855D02*
X1606660Y508539D01*
Y513418D01*
G01X1600745D02*
X1606660D01*
G01X1600745Y517561D02*
Y513418D01*
G01X1575925Y642917D02*
Y649167D01*
X1576175Y649417D01*
G01X1578926Y618657D02*
X1578916Y618667D01*
X1575057D01*
G01X1581925Y686917D02*
Y685167D01*
X1583675Y683417D01*
Y680517D01*
G01D02*
Y676417D01*
G01D02*
Y675196D01*
X1578976Y670497D01*
G01D02*
X1576175Y667696D01*
Y649417D01*
G01X1615356Y827284D02*
Y885149D01*
G01X1611416Y827284D02*
Y877400D01*
G01X1592128Y938753D02*
X1601300Y929581D01*
Y814250D01*
X1605195Y810355D01*
X1610719D01*
X1614507Y814143D01*
Y818385D01*
X1615356Y819234D01*
Y821534D01*
G01X1611416D02*
Y819234D01*
X1612307Y818343D01*
Y815055D01*
X1609807Y812555D01*
X1607545D01*
X1604967Y815133D01*
Y905900D01*
G01X1615356Y885149D02*
Y950304D01*
X1615807Y950755D01*
G01X1610807D02*
X1611416Y950146D01*
Y877400D01*
G01X1601228Y952278D02*
Y938451D01*
X1604967Y934712D01*
Y905900D01*
G01X1586680Y965809D02*
X1591926D01*
X1592102Y965633D01*
G01X1590911Y959737D02*
X1592102Y960928D01*
Y965633D01*
G01X1587829Y969191D02*
X1586680Y968042D01*
Y965809D01*
G01X1605103Y959778D02*
X1607000Y961675D01*
Y965689D01*
X1606800Y965889D01*
G01D02*
X1600821D01*
G01D02*
Y968604D01*
X1602187Y969970D01*
G01X1587036Y952237D02*
Y943845D01*
X1592128Y938753D01*
G01X1594025Y1093873D02*
X1602173D01*
X1607800Y1099500D01*
Y1112800D01*
X1605950Y1114650D01*
X1602200D01*
G01X1590275Y1093873D02*
Y1087623D01*
X1590025Y1087373D01*
G01X1594025Y1093873D02*
X1590275D01*
G01X1598400Y1114750D02*
X1602100D01*
X1602200Y1114650D01*
G01X1598400Y1114750D02*
X1598350Y1114700D01*
X1592100D01*
G01X1586775Y1093873D02*
X1582025D01*
G01D02*
X1581025Y1092873D01*
Y1087373D01*
G01X1574925Y1087423D02*
X1580975D01*
X1581025Y1087373D01*
G01X1620052Y1114449D02*
X1619308Y1113705D01*
Y1107701D01*
G01D02*
X1620255Y1106754D01*
X1624298D01*
G01X1615552Y1162206D02*
Y1170605D01*
X1610900Y1175257D01*
Y1212100D01*
X1605083Y1217917D01*
G01X1620236Y1162206D02*
Y1169120D01*
X1615900Y1173456D01*
Y1200200D01*
G01X1619446Y1138567D02*
Y1135939D01*
X1623034Y1132351D01*
G01X1623321Y1146067D02*
X1624622Y1147368D01*
Y1167846D01*
X1619940Y1172528D01*
Y1225400D01*
G01X1615356Y1280040D02*
Y1282640D01*
X1614388Y1283608D01*
Y1289612D01*
X1611000Y1293000D01*
X1604876D01*
X1601688Y1289812D01*
Y1221312D01*
X1605083Y1217917D01*
G01X1611416Y1280040D02*
Y1282728D01*
X1612188Y1283500D01*
Y1288700D01*
X1610088Y1290800D01*
X1605788D01*
X1603888Y1288900D01*
Y1228712D01*
X1615900Y1216700D01*
Y1200200D01*
G01X1615356Y1274290D02*
Y1256600D01*
G01X1623927Y1121949D02*
X1628837D01*
X1631700Y1124812D01*
Y1148904D01*
X1628800Y1151804D01*
Y1167700D01*
X1623000Y1173500D01*
Y1240200D01*
X1615356Y1247844D01*
Y1256600D01*
G01X1611416Y1274290D02*
X1610900Y1273774D01*
Y1244600D01*
X1619940Y1235560D01*
Y1225400D01*
G01X1628738Y256061D02*
Y250061D01*
G01X1661516Y240492D02*
X1629057D01*
X1628988Y240561D01*
G01D02*
Y244661D01*
G01D02*
Y249811D01*
X1628738Y250061D01*
G01X1622738Y260500D02*
Y264938D01*
G01Y256061D02*
Y260500D01*
G01X1628000Y270500D02*
X1628008Y270492D01*
X1661516D01*
G01X1627388Y693417D02*
X1627557Y693248D01*
X1661516D01*
G01X1627388Y697517D02*
Y693417D01*
G01X1626638Y722917D02*
X1626969Y723248D01*
X1661516D01*
G01X1627138Y708917D02*
Y702917D01*
G01D02*
X1627388Y702667D01*
Y697517D01*
G01X1621138Y714900D02*
Y719238D01*
G01Y708917D02*
Y714900D01*
G01X1624298Y1106754D02*
Y1111209D01*
X1624198Y1111309D01*
G01X1624063Y1128071D02*
Y1131322D01*
X1623034Y1132351D01*
G01X1620059Y1128071D02*
X1624063D01*
G01X1626000Y1176000D02*
X1626004Y1176004D01*
X1661516D01*
G01X1639188Y1146173D02*
X1639357Y1146004D01*
X1661516D01*
G01X1639138Y1161673D02*
Y1150323D01*
X1639188Y1150273D01*
G01D02*
Y1146173D01*
G01X1633138Y1161673D02*
Y1165673D01*
G01X1683838Y178161D02*
X1689638D01*
G01X1694438Y178311D02*
X1694288Y178161D01*
X1689638D01*
G01X1709138Y194661D02*
X1705388D01*
G01D02*
Y188411D01*
X1705138Y188161D01*
G01X1707888Y223661D02*
X1710638Y220911D01*
Y196161D01*
X1709138Y194661D01*
G01X1680888Y186300D02*
Y191161D01*
G01X1676438Y175601D02*
X1673638D01*
X1671638Y177601D01*
Y184800D01*
X1673138Y186300D01*
X1680888D01*
G01Y195261D02*
Y200411D01*
X1681138Y200661D01*
G01X1680888Y191161D02*
Y195261D01*
G01X1701888Y194661D02*
X1697138D01*
G01D02*
X1696138Y193661D01*
Y188161D01*
G01X1683838Y180721D02*
X1687198D01*
X1688288Y181811D01*
X1694438D01*
G01D02*
X1699138D01*
G01D02*
Y183462D01*
X1696138Y186462D01*
Y188161D01*
G01X1694638Y169411D02*
X1689638D01*
G01D02*
X1684638D01*
G01X1680138D02*
Y177661D01*
X1679638Y178161D01*
X1676438D01*
G01X1684638Y169411D02*
X1680138D01*
G01X1694638Y165911D02*
X1699692D01*
G01X1703584Y166019D02*
X1703476Y165911D01*
X1699692D01*
G01X1706138Y234161D02*
Y232411D01*
X1707888Y230661D01*
Y227761D01*
G01D02*
Y223661D01*
G01X1723619Y436700D02*
Y476381D01*
X1711457Y488543D01*
Y499103D01*
G01X1711061Y518470D02*
X1711073Y518458D01*
Y513134D01*
G01D02*
X1716486D01*
X1716609Y513257D01*
G01X1715332Y506603D02*
X1716609Y507880D01*
Y513257D01*
G01X1683838Y630917D02*
X1689638D01*
G01X1694438Y631067D02*
X1694288Y630917D01*
X1689638D01*
G01X1709138Y647417D02*
X1705388D01*
G01D02*
Y641167D01*
X1705138Y640917D01*
G01X1707888Y676417D02*
X1710053Y674252D01*
Y648332D01*
X1709138Y647417D01*
G01X1676438Y628357D02*
X1673638D01*
X1671638Y630357D01*
Y638917D01*
X1675138Y642417D01*
G01X1680888Y648017D02*
Y643917D01*
G01D02*
X1676638D01*
X1675138Y642417D01*
G01X1697138Y647417D02*
X1696138Y646417D01*
Y640917D01*
G01X1701888Y647417D02*
X1697138D01*
G01X1683838Y633477D02*
X1687198D01*
X1688288Y634567D01*
X1694438D01*
G01D02*
X1699138D01*
G01D02*
Y637917D01*
X1696138Y640917D01*
G01X1694638Y622167D02*
X1689638D01*
G01D02*
X1684638D01*
G01X1680138D02*
Y630417D01*
X1679638Y630917D01*
X1676438D01*
G01X1684638Y622167D02*
X1680138D01*
G01X1699788Y618667D02*
X1705000D01*
G01X1694638D02*
X1699788D01*
G01X1706138Y686917D02*
Y685167D01*
X1707888Y683417D01*
Y680517D01*
G01D02*
Y676417D01*
G01X1681138Y653417D02*
X1680888Y653167D01*
Y648017D01*
G01X1676438Y1081113D02*
X1673638D01*
X1671638Y1083113D01*
Y1091673D01*
X1675138Y1095173D01*
G01X1694638Y1074923D02*
X1689638D01*
G01D02*
X1684638D01*
G01X1680138D02*
Y1083173D01*
X1679638Y1083673D01*
X1676438D01*
G01X1684638Y1074923D02*
X1680138D01*
G01X1694638Y1071423D02*
Y1067600D01*
G01D02*
Y1063600D01*
G01X1683838Y1083673D02*
X1689638D01*
G01X1694438Y1083823D02*
X1694288Y1083673D01*
X1689638D01*
G01X1709138Y1100173D02*
X1705388D01*
G01X1707888Y1133273D02*
Y1129173D01*
G01X1705388Y1100173D02*
Y1093923D01*
X1705138Y1093673D01*
G01X1707888Y1129173D02*
X1710638Y1126423D01*
Y1101673D01*
X1709138Y1100173D01*
G01X1681138Y1106173D02*
X1680888Y1105923D01*
Y1100773D01*
G01D02*
Y1096673D01*
G01D02*
X1676638D01*
X1675138Y1095173D01*
G01X1697138Y1100173D02*
X1696138Y1099173D01*
Y1093673D01*
G01X1701888Y1100173D02*
X1697138D01*
G01X1683838Y1086233D02*
X1687198D01*
X1688288Y1087323D01*
X1694438D01*
G01D02*
X1699138D01*
G01D02*
Y1088862D01*
X1696138Y1091862D01*
Y1093673D01*
G01X1706138Y1139673D02*
Y1137923D01*
X1707888Y1136173D01*
Y1133273D01*
G01X1753550Y256061D02*
Y250061D01*
G01D02*
X1753800Y249811D01*
Y244661D01*
G01Y240561D02*
X1753869Y240492D01*
X1785728D01*
G01X1753800Y244661D02*
Y240561D01*
G01X1747550Y256061D02*
Y261100D01*
G01X1750900Y270500D02*
X1750908Y270492D01*
X1785728D01*
G01X1747550Y261100D02*
Y265000D01*
G01X1723619Y436700D02*
Y363388D01*
X1729407Y357600D01*
X1734931D01*
X1738719Y361388D01*
Y365630D01*
X1739568Y366479D01*
Y368779D01*
G01Y374529D02*
Y453500D01*
G01X1735628Y374529D02*
Y476630D01*
G01X1725566Y499102D02*
Y480116D01*
X1729179Y476503D01*
Y393700D01*
G01X1735628Y368779D02*
Y366479D01*
X1736519Y365588D01*
Y362300D01*
X1734019Y359800D01*
X1731700D01*
X1729179Y362321D01*
Y393700D01*
G01X1740019Y498000D02*
X1739568Y497549D01*
Y453500D01*
G01X1735019Y498000D02*
X1735628Y497391D01*
Y476630D01*
G01X1729441Y506602D02*
X1731125Y508286D01*
Y513165D01*
G01D02*
X1725210D01*
G01D02*
X1725100Y513275D01*
Y519300D01*
G01X1755459Y711160D02*
Y703354D01*
X1765565Y693248D01*
X1785728D01*
G01X1753000Y756000D02*
Y755039D01*
X1772829Y735210D01*
Y728766D01*
X1778347Y723248D01*
X1785728D01*
G01X1759750Y720500D02*
Y716500D01*
G01X1760500Y725000D02*
Y721250D01*
X1759750Y720500D01*
G01X1755459Y711160D02*
Y715210D01*
X1756749Y716500D01*
X1759750D01*
G01X1752000Y901047D02*
Y764115D01*
X1749986Y762101D01*
Y752116D01*
X1760500Y741602D01*
Y731000D01*
G01X1739568Y827284D02*
Y852900D01*
G01X1735628Y827284D02*
Y883800D01*
G01X1749573Y939015D02*
Y934338D01*
X1746518Y931283D01*
Y815237D01*
X1744941Y813660D01*
X1740315D01*
X1738719Y815256D01*
Y818385D01*
X1739568Y819234D01*
Y821534D01*
G01X1749145Y918827D02*
Y815000D01*
X1745780Y811635D01*
X1739476D01*
X1736519Y814592D01*
Y818343D01*
X1735628Y819234D01*
Y821534D01*
G01X1740019Y950755D02*
X1739568Y950304D01*
Y852900D01*
G01X1735019Y950755D02*
X1735628Y950146D01*
Y883800D01*
G01X1752000Y929200D02*
Y901047D01*
G01X1763765Y952234D02*
Y945666D01*
X1749145Y931046D01*
Y918827D01*
G01X1749242Y970095D02*
X1749186Y970039D01*
Y965664D01*
G01X1755010Y966285D02*
Y969307D01*
X1754222Y970095D01*
X1749242D01*
G01X1749186Y965664D02*
Y963955D01*
X1753448Y959693D01*
G01X1767640Y959734D02*
X1763384Y963990D01*
Y965756D01*
G01D02*
Y969189D01*
X1764356Y970161D01*
G01X1768692Y966073D02*
Y968925D01*
X1767456Y970161D01*
X1764356D01*
G01X1749573Y939015D02*
Y952193D01*
G01X1728978Y1127935D02*
X1727481Y1126438D01*
Y1120480D01*
G01D02*
X1727834Y1120127D01*
X1733245D01*
G01D02*
Y1115503D01*
G01X1747400Y1176000D02*
X1747404Y1176004D01*
X1785728D01*
G01X1751600Y1155523D02*
Y1150273D01*
G01X1752700Y1161800D02*
Y1159300D01*
X1751600Y1158200D01*
Y1155523D01*
G01Y1146173D02*
X1751769Y1146004D01*
X1785728D01*
G01X1751600Y1150273D02*
Y1146173D01*
G01X1718117Y1162153D02*
Y1274820D01*
G01X1723117Y1162153D02*
Y1266400D01*
G01X1746700Y1161800D02*
Y1169200D01*
G01X1751400Y1173900D02*
X1746700Y1169200D01*
G01X1729121Y1153108D02*
X1727463Y1151450D01*
Y1145781D01*
G01D02*
X1727766Y1145478D01*
X1733441D01*
G01D02*
Y1142370D01*
X1732768Y1141697D01*
G01X1732853Y1135435D02*
X1735032D01*
X1742100Y1142503D01*
Y1175000D01*
X1739568Y1177532D01*
Y1209300D01*
G01X1732996Y1160608D02*
Y1212910D01*
X1735628Y1215542D01*
Y1226800D01*
G01X1739568Y1209300D02*
Y1274290D01*
G01X1735628D02*
Y1226800D01*
G01X1739568Y1280040D02*
Y1282640D01*
X1738600Y1283608D01*
Y1289612D01*
X1735212Y1293000D01*
X1723110D01*
X1718117Y1288007D01*
Y1274820D01*
G01X1735628Y1280040D02*
Y1282728D01*
X1736400Y1283500D01*
Y1286600D01*
X1734300Y1288700D01*
X1726222D01*
X1723117Y1285595D01*
Y1266400D01*
G01X1808050Y178161D02*
X1813850D01*
G01X1804897Y187050D02*
X1805100Y187253D01*
Y191161D01*
G01X1800650Y175601D02*
X1797850D01*
X1795850Y177601D01*
Y184000D01*
X1798900Y187050D01*
X1804897D01*
G01X1805100Y195261D02*
Y200411D01*
X1805350Y200661D01*
G01X1805100Y191161D02*
Y195261D01*
G01X1808050Y180721D02*
X1811410D01*
X1812500Y181811D01*
X1818650D01*
G01X1813850Y169411D02*
X1808850D01*
G01X1804350D02*
Y177661D01*
X1803850Y178161D01*
X1800650D01*
G01X1808850Y169411D02*
X1804350D01*
G01X1808050Y630917D02*
X1813850D01*
G01X1800650Y628357D02*
X1797850D01*
X1795850Y630357D01*
Y638917D01*
X1799350Y642417D01*
G01X1805100Y648017D02*
Y643917D01*
G01D02*
X1800850D01*
X1799350Y642417D01*
G01X1808050Y633477D02*
X1811410D01*
X1812500Y634567D01*
X1818650D01*
G01X1813850Y622167D02*
X1808850D01*
G01X1804350D02*
Y630417D01*
X1803850Y630917D01*
X1800650D01*
G01X1808850Y622167D02*
X1804350D01*
G01X1805350Y653417D02*
X1805100Y653167D01*
Y648017D01*
G01X1863781Y827284D02*
Y829218D01*
X1859456Y833543D01*
Y839346D01*
X1782666Y916136D01*
Y939436D01*
G01X1859841Y827284D02*
Y829920D01*
X1857210Y832551D01*
Y838508D01*
X1777666Y918052D01*
Y932748D01*
G01X1792236Y942480D02*
Y909646D01*
X1867972Y833910D01*
Y815653D01*
X1865653Y813334D01*
X1863741D01*
X1862932Y814143D01*
Y818385D01*
X1863781Y819234D01*
Y821534D01*
G01X1777666Y950744D02*
Y932748D01*
G01X1806452Y942675D02*
Y898512D01*
X1870427Y834537D01*
Y815182D01*
X1866379Y811134D01*
X1862829D01*
X1860732Y813231D01*
Y818343D01*
X1859841Y819234D01*
Y821534D01*
G01X1782666Y950744D02*
Y939436D01*
G01X1794767Y964624D02*
X1793888Y965503D01*
Y968689D01*
G01X1796111Y959351D02*
Y963280D01*
X1794767Y964624D01*
G01X1793888Y968689D02*
X1793999Y968800D01*
X1797315D01*
X1797463Y968652D01*
G01X1810327Y959610D02*
X1811581Y960864D01*
Y965390D01*
G01X1806077Y965626D02*
X1811345D01*
X1811581Y965390D01*
G01X1806077Y961860D02*
Y965626D01*
G01X1792236Y951851D02*
Y942480D01*
G01X1806452Y952110D02*
Y942675D01*
G01X1800650Y1081113D02*
X1797850D01*
X1795850Y1083113D01*
Y1091673D01*
X1799350Y1095173D01*
G01X1800750Y1074723D02*
Y1075851D01*
X1804400Y1079501D01*
Y1083100D01*
X1803827Y1083673D01*
X1800650D01*
G01X1815250Y1074723D02*
X1810250D01*
G01D02*
X1805250D01*
G01D02*
X1800750D01*
G01X1815250Y1071223D02*
X1812050D01*
G01X1808050Y1083673D02*
X1813850D01*
G01X1803350Y1106173D02*
Y1103569D01*
X1805100Y1101819D01*
Y1100773D01*
G01D02*
Y1096673D01*
G01D02*
X1800850D01*
X1799350Y1095173D01*
G01X1808050Y1086233D02*
X1811410D01*
X1812500Y1087323D01*
X1818650D01*
G01X1841021Y156822D02*
Y161721D01*
X1841017Y161725D01*
G01X1841021Y156822D02*
Y152968D01*
G01X1818650Y178311D02*
X1818500Y178161D01*
X1813850D01*
G01X1851717Y173575D02*
X1848867D01*
X1845667Y176775D01*
G01X1845567Y181175D02*
Y176875D01*
X1845667Y176775D01*
G01X1833350Y194661D02*
X1829600D01*
G01D02*
Y188411D01*
X1829350Y188161D01*
G01X1832100Y223661D02*
X1834850Y220911D01*
Y196161D01*
X1833350Y194661D01*
G01X1851919Y199644D02*
Y210461D01*
G01Y199644D02*
X1851767Y199492D01*
Y194075D01*
G01D02*
Y188225D01*
X1852417Y187575D01*
G01X1851919Y210461D02*
Y214661D01*
G01X1859117Y176135D02*
Y193744D01*
G01D02*
Y199017D01*
X1859719Y199619D01*
Y204961D01*
G01Y209161D02*
Y215711D01*
X1865669Y221661D01*
Y227661D01*
G01X1859719Y204961D02*
Y209161D01*
G01X1821350Y194661D02*
X1820350Y193661D01*
Y188161D01*
G01X1826100Y194661D02*
X1821350D01*
G01X1818650Y181811D02*
X1823350D01*
G01D02*
Y185161D01*
X1820350Y188161D01*
G01X1851717Y171015D02*
X1843727D01*
X1842167Y172575D01*
G01X1843417Y187575D02*
Y193425D01*
X1843917Y193925D01*
G01X1843417Y187575D02*
Y184417D01*
X1842067Y183067D01*
Y181175D01*
G01D02*
Y172675D01*
X1842167Y172575D01*
G01X1843917Y193925D02*
X1844067Y194075D01*
X1848267D01*
G01X1818850Y169411D02*
X1813850D01*
G01X1841017Y165225D02*
X1845517D01*
G01X1850517D02*
X1855517D01*
G01D02*
Y172175D01*
X1856917Y173575D01*
X1859117D01*
G01X1845517Y165225D02*
X1850517D01*
G01X1818850Y165911D02*
X1823904D01*
G01X1827796Y166019D02*
X1827688Y165911D01*
X1823904D01*
G01X1830350Y234161D02*
Y232411D01*
X1832100Y230661D01*
Y227761D01*
G01D02*
Y223661D01*
G01X1851919Y214661D02*
X1857669Y220411D01*
Y225661D01*
G01X1863781Y368779D02*
Y366479D01*
X1862932Y365630D01*
Y361388D01*
X1859144Y357600D01*
X1853620D01*
X1844832Y366388D01*
Y446400D01*
G01X1859841Y374529D02*
Y452000D01*
G01Y368779D02*
Y366479D01*
X1860732Y365588D01*
Y362300D01*
X1858232Y359800D01*
X1855700D01*
X1853392Y362108D01*
Y476500D01*
G01X1859232Y498000D02*
X1859841Y497391D01*
Y452000D01*
G01X1835292Y499230D02*
Y494708D01*
X1844832Y485168D01*
Y446400D01*
G01X1849401Y499229D02*
Y487506D01*
X1853392Y483515D01*
Y476500D01*
G01X1834908Y513261D02*
X1839739D01*
X1840000Y513000D01*
G01D02*
X1840444Y512556D01*
Y508007D01*
X1839167Y506730D01*
G01X1834908Y513261D02*
X1834896Y513273D01*
Y518597D01*
G01X1849045Y513292D02*
X1854608D01*
X1854800Y513100D01*
G01X1849045Y517435D02*
Y513292D01*
G01X1854800Y513100D02*
X1854960Y512940D01*
Y508413D01*
X1853276Y506729D01*
G01X1818650Y631067D02*
X1818500Y630917D01*
X1813850D01*
G01X1845667Y629531D02*
Y633931D01*
G01X1851717Y626331D02*
X1848867D01*
X1845667Y629531D01*
G01X1833350Y647417D02*
X1829600D01*
G01D02*
Y641167D01*
X1829350Y640917D01*
G01X1832100Y676417D02*
X1835780Y672737D01*
Y649847D01*
X1833350Y647417D01*
G01X1852417Y640331D02*
Y643000D01*
X1851767Y643650D01*
Y646831D01*
G01D02*
Y652400D01*
X1851667Y652500D01*
G01X1859117Y628891D02*
Y646500D01*
G01D02*
Y650317D01*
X1859719Y650919D01*
Y657817D01*
G01X1821350Y647417D02*
X1820350Y646417D01*
Y640917D01*
G01X1826100Y647417D02*
X1821350D01*
G01X1818650Y634567D02*
X1823350D01*
G01D02*
Y636250D01*
X1820350Y639250D01*
Y640917D01*
G01X1851717Y623771D02*
X1843727D01*
X1842167Y625331D01*
G01D02*
Y633931D01*
G01X1843417Y640331D02*
Y646181D01*
X1843917Y646681D01*
G01X1842167Y633931D02*
Y636581D01*
X1843417Y637831D01*
Y640331D01*
G01X1843917Y646681D02*
X1844067Y646831D01*
X1848267D01*
G01X1818850Y622167D02*
X1813850D01*
G01X1850417Y617981D02*
X1845417D01*
G01X1850417D02*
X1855417D01*
G01D02*
Y624831D01*
X1856917Y626331D01*
X1859117D01*
G01X1845417Y617981D02*
X1840917D01*
G01X1827667Y618703D02*
X1827631Y618667D01*
X1823543D01*
G01X1818850D02*
X1823543D01*
G01X1840891Y610086D02*
Y606236D01*
X1840855Y606200D01*
G01X1840917Y614481D02*
X1840891Y614455D01*
Y610086D01*
G01X1830350Y686917D02*
Y685167D01*
X1832100Y683417D01*
Y680517D01*
G01D02*
Y676417D01*
G01X1851667Y652500D02*
X1851919Y652752D01*
Y663317D01*
G01Y667417D02*
X1857669Y673167D01*
Y678417D01*
G01X1851919Y663317D02*
Y667417D01*
G01X1859719Y661917D02*
Y668467D01*
X1865669Y674417D01*
Y680417D01*
G01X1859719Y657817D02*
Y661917D01*
G01X1863630Y1079500D02*
X1860108D01*
X1858568Y1081040D01*
Y1084832D01*
X1857100Y1086300D01*
G01X1863630Y1076940D02*
X1858339D01*
X1849639Y1085640D01*
X1835997D01*
X1834691Y1086946D01*
Y1091365D01*
X1835771Y1092445D01*
X1838074D01*
G01X1818650Y1083823D02*
X1818500Y1083673D01*
X1813850D01*
G01X1838074Y1088945D02*
X1854455D01*
X1857100Y1086300D01*
G01X1833350Y1100173D02*
X1834850Y1101673D01*
Y1107750D01*
X1833045Y1109555D01*
Y1127628D01*
X1831700Y1128973D01*
G01X1833350Y1100173D02*
X1829600D01*
G01D02*
Y1093923D01*
X1829350Y1093673D01*
G01X1831700Y1128973D02*
Y1133173D01*
G01X1851981Y1103613D02*
Y1099048D01*
X1851746Y1098813D01*
G01X1858277Y1125264D02*
Y1117573D01*
X1858456Y1117394D01*
G01D02*
Y1113294D01*
G01X1851746Y1098813D02*
Y1095554D01*
X1852896Y1094404D01*
Y1092413D01*
G01X1858456Y1113294D02*
X1851981Y1106819D01*
Y1103613D01*
G01X1865779Y1117763D02*
Y1114854D01*
X1859974Y1109049D01*
G01D02*
X1859941Y1109016D01*
Y1102987D01*
G01D02*
Y1098887D01*
X1859841Y1098787D01*
G01D02*
X1861178Y1097450D01*
Y1089850D01*
X1863018Y1088010D01*
X1869390D01*
X1871030Y1086370D01*
Y1082060D01*
G01X1826100Y1100173D02*
X1821350D01*
G01D02*
X1820350Y1099173D01*
Y1093673D01*
G01X1818650Y1087323D02*
X1823350D01*
G01D02*
Y1090673D01*
X1820350Y1093673D01*
G01X1844432Y1099891D02*
X1840433D01*
G01X1848246Y1098813D02*
X1847168Y1099891D01*
X1844432D01*
G01X1843896Y1092413D02*
X1838106D01*
X1838074Y1092445D01*
G01X1840433Y1099891D02*
Y1098626D01*
X1843896Y1095163D01*
Y1092413D01*
G01X1836200Y1130000D02*
Y1133170D01*
G01X1831700Y1133173D02*
Y1136300D01*
X1830350Y1137650D01*
Y1139673D01*
G01X1836400Y1161700D02*
X1837344Y1162644D01*
Y1233956D01*
X1844138Y1240750D01*
G01X1841084Y1161721D02*
X1839684Y1163121D01*
Y1228284D01*
X1845845Y1234445D01*
G01X1836200Y1133170D02*
X1839900Y1136870D01*
Y1147874D01*
X1841626Y1149600D01*
X1858741D01*
X1860667Y1151526D01*
Y1153308D01*
G01X1836431Y1147909D02*
X1840175Y1151653D01*
X1840585D01*
G01D02*
X1844969D01*
X1846602Y1153286D01*
G01X1864542Y1160808D02*
Y1164388D01*
X1855400Y1173530D01*
Y1224800D01*
X1860457Y1229857D01*
G01X1850477Y1160786D02*
Y1226977D01*
X1856642Y1233142D01*
G01X1863781Y1280040D02*
Y1282119D01*
X1862800Y1283100D01*
Y1287612D01*
X1859712Y1290700D01*
X1853388D01*
X1850000Y1287312D01*
Y1246612D01*
X1844138Y1240750D01*
G01X1859841Y1280040D02*
Y1282441D01*
X1860600Y1283200D01*
Y1286700D01*
X1858800Y1288500D01*
X1854300D01*
X1852200Y1286400D01*
Y1240800D01*
X1845845Y1234445D01*
G01X1863781Y1274290D02*
Y1233181D01*
X1860457Y1229857D01*
G01X1859841Y1274290D02*
Y1236341D01*
X1856642Y1233142D01*
G01X1869500Y190744D02*
X1874400D01*
G01D02*
X1874650Y190994D01*
X1878900D01*
G01X1883000D02*
X1883750D01*
X1885500Y192744D01*
Y226744D01*
X1899248Y240492D01*
X1909941D01*
G01X1878900Y190994D02*
X1883000D01*
G01X1869500Y184744D02*
X1865644D01*
X1864775Y183875D01*
Y182057D01*
G01X1869500Y179134D02*
X1865866D01*
X1864775Y180225D01*
Y182057D01*
G01X1877400Y265200D02*
X1893956D01*
X1899248Y270492D01*
X1909941D01*
G01X1863781Y374529D02*
Y429200D01*
G01X1864232Y498000D02*
X1863781Y497549D01*
Y429200D01*
G01X1869500Y643500D02*
X1874500D01*
G01X1909941Y693248D02*
X1899248D01*
X1885500Y679500D01*
Y645500D01*
X1883750Y643750D01*
X1883000D01*
G01D02*
X1878900D01*
G01D02*
X1874750D01*
X1874500Y643500D01*
G01X1869500Y633500D02*
X1864731D01*
X1864000Y634231D01*
Y638000D01*
G01X1869500Y637500D02*
X1867600Y639400D01*
X1865400D01*
X1864000Y638000D01*
G01X1874807Y707280D02*
X1885349Y717822D01*
X1894188D01*
X1899614Y723248D01*
X1909941D01*
G01X1881332Y1054227D02*
X1881335Y1054230D01*
Y1059938D01*
G01D02*
Y1064038D01*
G01X1909941Y1146004D02*
X1901998D01*
X1900555Y1144561D01*
Y1140598D01*
X1900552Y1140595D01*
Y1136895D01*
X1890934Y1127277D01*
X1887148D01*
X1885752Y1125881D01*
Y1089801D01*
X1883907Y1087956D01*
X1878235D01*
X1875800Y1085521D01*
Y1071554D01*
X1876555Y1070799D01*
G01X1881335Y1064038D02*
Y1066019D01*
X1876555Y1070799D01*
G01X1868100Y1062250D02*
X1867190Y1063160D01*
Y1077914D01*
X1868776Y1079500D01*
X1871030D01*
G01X1868100Y1062250D02*
X1872088D01*
X1872162Y1062176D01*
G01X1872967Y1067014D02*
X1875800D01*
X1876662Y1066152D01*
Y1062176D01*
G01X1872162D02*
Y1066209D01*
X1872967Y1067014D01*
G01X1887332Y1054227D02*
Y1050263D01*
X1887402Y1050193D01*
G01X1872162Y1058676D02*
Y1055426D01*
G01X1887000Y1170756D02*
X1894000D01*
X1899248Y1176004D01*
X1909941D01*
G54D113*
X1488900Y530900D03*
G54D20*
X59937Y187361D03*
Y640117D03*
Y1092873D03*
X108363Y998925D03*
X112500Y998980D03*
X184149Y187461D03*
X175063Y586925D03*
X179200Y586980D03*
X188649Y629617D03*
X306955Y71879D03*
X314370Y125341D03*
X308362Y187461D03*
X308262Y640217D03*
Y1092973D03*
X323813Y125322D03*
X328321Y125299D03*
X318909Y125343D03*
X333021Y125355D03*
X365162Y84670D03*
X432574Y187461D03*
Y640117D03*
X447173Y1075426D03*
X442473D03*
X556787Y187361D03*
X549279Y520031D03*
X553279D03*
X556787Y640117D03*
Y1092973D03*
X580279Y520031D03*
X557279Y567031D03*
X592779Y574031D03*
X579718Y574097D03*
X571540Y574065D03*
X615100Y520300D03*
X611910Y565974D03*
X637213Y589355D03*
X681000Y187361D03*
X685500Y640117D03*
X680400Y1101000D03*
X878673Y811303D03*
X883400Y811332D03*
X881448Y1358507D03*
X881420Y1350388D03*
X882000Y1439200D03*
X873000D03*
X893050Y1486000D03*
X879321Y1485961D03*
X883947Y1485970D03*
X860000Y1504700D03*
X850500D03*
X914600Y912400D03*
X927861Y962907D03*
X921600Y981900D03*
X916500Y962800D03*
X925053Y1032085D03*
X916769Y1032139D03*
X936959Y1366990D03*
X936964Y1353312D03*
X932294Y1376548D03*
X922500Y1506400D03*
X918500D03*
X941000Y1560400D03*
X926500Y1553400D03*
X957000Y911700D03*
X970500D03*
X952500D03*
X954900Y957100D03*
X950400D03*
X959400D03*
X955000Y982700D03*
X964000D03*
X945790Y953862D03*
X955700Y1027500D03*
X951200D03*
X946700D03*
X947159Y1365287D03*
X951525Y1376357D03*
X950300Y1506400D03*
X988573Y1509912D03*
X962000Y1560400D03*
X949000D03*
X972413Y1556866D03*
X1038712Y-38558D03*
X1004100Y-70032D03*
X1035973Y830903D03*
X1034400Y908400D03*
X1002194Y981540D03*
X1006694D03*
X1007849Y1030543D03*
X1003194Y1030540D03*
X993649Y1030543D03*
X1012494Y1030640D03*
X998439Y1030537D03*
X1028000Y1073700D03*
X1022400Y1121500D03*
X1031400D03*
X1026900D03*
X1017800Y1144200D03*
X1008700D03*
X995000D03*
X1009500Y1187700D03*
X1014500D03*
X1004500D03*
X1061325Y-44000D03*
X1074400Y-42332D03*
X1040773Y830903D03*
X1054419Y835653D03*
X1048400Y908400D03*
X1057700D03*
X1064918Y942349D03*
X1069918D03*
X1087000Y1073700D03*
X1078000D03*
X1041500D03*
X1087700Y1122600D03*
X1074500Y1122700D03*
X1079000D03*
X1070155Y1122703D03*
X1083355D03*
X1115200Y1073800D03*
X1128900D03*
X1119500Y1121900D03*
X1124100D03*
X1115000D03*
X1176100Y266200D03*
X1176835Y614632D03*
X1192300Y268568D03*
X1194600Y296100D03*
X1197100Y275900D03*
X1250410Y236409D03*
X1327921Y86155D03*
X1299569Y90891D03*
X1315115Y133800D03*
X1324207Y133803D03*
X1319797Y133788D03*
X1328534D03*
X1312000Y169361D03*
X1322000D03*
X1326400Y181761D03*
X1321900D03*
X1312000Y622117D03*
X1322000D03*
X1326500Y634517D03*
X1322000D03*
X1309600Y1074873D03*
X1317400Y1074900D03*
X1326500Y1087273D03*
X1322000D03*
X1332934Y133788D03*
X1421969Y531357D03*
X1436213Y169361D03*
X1446213D03*
X1450713Y181761D03*
X1446013D03*
X1463085Y506585D03*
X1452200Y575800D03*
X1470700D03*
X1437200Y566300D03*
X1436213Y622117D03*
X1446213D03*
X1450713Y634517D03*
X1446013D03*
X1436213Y1074873D03*
X1446213D03*
X1450713Y1087273D03*
X1446013D03*
X1502400Y550850D03*
X1481938Y506470D03*
X1560425Y169361D03*
X1570425D03*
X1570125Y181761D03*
X1560425Y622117D03*
X1570425D03*
X1570225Y634517D03*
X1560425Y1074873D03*
X1570425D03*
Y1087373D03*
X1574925Y181761D03*
Y634517D03*
Y1087373D03*
X1684638Y169361D03*
X1694638D03*
X1699138Y181761D03*
X1694438D03*
X1684638Y622117D03*
X1694638D03*
X1699138Y634517D03*
X1694438D03*
X1684638Y1074873D03*
X1694638D03*
X1699138Y1087273D03*
X1694438D03*
X1750163Y1010925D03*
X1754300Y1010980D03*
X1808850Y169361D03*
Y622117D03*
X1805250Y1074673D03*
X1818850Y169361D03*
X1823350Y181761D03*
X1818650D03*
X1845517Y165175D03*
X1841017D03*
X1818850Y622117D03*
X1823350Y634517D03*
X1818650D03*
X1845417Y617931D03*
X1840917D03*
X1815250Y1074673D03*
X1823350Y1087273D03*
X1818650D03*
X1838074Y1092395D03*
X1836200Y1136620D03*
X1878900Y190944D03*
Y643700D03*
X1876662Y1062126D03*
X1872162D03*
G54D11*
X24508Y5500D03*
X5500Y61492D03*
Y56492D03*
Y51492D03*
Y46492D03*
Y41492D03*
Y66492D03*
Y81492D03*
Y76492D03*
Y96492D03*
Y91492D03*
Y86492D03*
Y71492D03*
Y101492D03*
Y111492D03*
Y116492D03*
Y106492D03*
Y126492D03*
Y121492D03*
Y141492D03*
Y151492D03*
Y161492D03*
Y156492D03*
Y146492D03*
Y131492D03*
Y136492D03*
Y181492D03*
Y191492D03*
Y201492D03*
Y211492D03*
Y171492D03*
Y206492D03*
Y196492D03*
Y176492D03*
Y166492D03*
Y186492D03*
Y231492D03*
Y241492D03*
Y251492D03*
Y261492D03*
Y221492D03*
Y256492D03*
Y246492D03*
Y226492D03*
Y216492D03*
Y236492D03*
Y281492D03*
Y291492D03*
Y301492D03*
Y271492D03*
Y306492D03*
Y296492D03*
Y286492D03*
Y276492D03*
Y266492D03*
Y331492D03*
Y341492D03*
Y351492D03*
Y311492D03*
Y321492D03*
Y356492D03*
Y346492D03*
Y336492D03*
Y326492D03*
Y316492D03*
Y381492D03*
Y391492D03*
Y401492D03*
Y361492D03*
Y371492D03*
Y406492D03*
Y396492D03*
Y386492D03*
Y376492D03*
Y366492D03*
Y451492D03*
Y441492D03*
Y431492D03*
Y421492D03*
Y411492D03*
Y416492D03*
Y436492D03*
Y446492D03*
Y426492D03*
Y501492D03*
Y456492D03*
Y496492D03*
Y531492D03*
Y551492D03*
Y541492D03*
Y521492D03*
Y511492D03*
Y536492D03*
Y546492D03*
Y506492D03*
Y516492D03*
Y526492D03*
Y581492D03*
Y591492D03*
Y571492D03*
Y561492D03*
Y586492D03*
Y596492D03*
Y556492D03*
Y566492D03*
Y576492D03*
Y631492D03*
Y641492D03*
Y621492D03*
Y611492D03*
Y601492D03*
Y636492D03*
Y646492D03*
Y606492D03*
Y616492D03*
Y626492D03*
Y681492D03*
Y691492D03*
Y671492D03*
Y661492D03*
Y651492D03*
Y686492D03*
Y696492D03*
Y656492D03*
Y666492D03*
Y676492D03*
Y731492D03*
Y741492D03*
Y721492D03*
Y711492D03*
Y701492D03*
Y736492D03*
Y706492D03*
Y716492D03*
Y726492D03*
Y781492D03*
Y791492D03*
Y771492D03*
Y761492D03*
Y751492D03*
Y786492D03*
Y746492D03*
Y756492D03*
Y766492D03*
Y776492D03*
Y831492D03*
Y841492D03*
Y821492D03*
Y811492D03*
Y801492D03*
Y836492D03*
Y796492D03*
Y806492D03*
Y816492D03*
Y826492D03*
Y881492D03*
Y871492D03*
Y861492D03*
Y851492D03*
Y886492D03*
Y846492D03*
Y856492D03*
Y866492D03*
Y876492D03*
Y931492D03*
Y921492D03*
Y911492D03*
Y901492D03*
Y891492D03*
Y936492D03*
Y896492D03*
Y906492D03*
Y916492D03*
Y926492D03*
Y976492D03*
Y981492D03*
Y986492D03*
Y966492D03*
Y956492D03*
Y961492D03*
Y971492D03*
Y951492D03*
Y941492D03*
Y946492D03*
Y991492D03*
Y996492D03*
Y1001492D03*
Y1006492D03*
Y1026492D03*
Y1016492D03*
Y1011492D03*
Y1021492D03*
Y1031492D03*
Y1036492D03*
Y1066492D03*
Y1056492D03*
Y1046492D03*
Y1041492D03*
Y1051492D03*
Y1061492D03*
Y1071492D03*
Y1081492D03*
Y1076492D03*
Y1121492D03*
Y1131492D03*
Y1111492D03*
Y1101492D03*
Y1091492D03*
Y1086492D03*
Y1096492D03*
Y1106492D03*
Y1116492D03*
Y1126492D03*
Y1171492D03*
Y1161492D03*
Y1151492D03*
Y1141492D03*
Y1136492D03*
Y1146492D03*
Y1156492D03*
Y1166492D03*
Y1176492D03*
Y1221492D03*
Y1211492D03*
Y1201492D03*
Y1191492D03*
Y1181492D03*
Y1186492D03*
Y1196492D03*
Y1206492D03*
Y1216492D03*
Y1226492D03*
Y1271492D03*
Y1261492D03*
Y1251492D03*
Y1241492D03*
Y1231492D03*
Y1236492D03*
Y1246492D03*
Y1256492D03*
Y1266492D03*
Y1276492D03*
Y1321492D03*
Y1311492D03*
Y1301492D03*
Y1291492D03*
Y1281492D03*
Y1286492D03*
Y1296492D03*
Y1306492D03*
Y1316492D03*
X8983Y1368303D03*
X13983D03*
X18983D03*
X23983D03*
X5500Y1361492D03*
Y1351492D03*
Y1341492D03*
Y1331492D03*
Y1336492D03*
Y1346492D03*
Y1356492D03*
Y1326492D03*
X29508Y5500D03*
X39508D03*
X34508D03*
X44508D03*
X64508D03*
X69508D03*
X54508D03*
X49508D03*
X59508D03*
X28983Y1368303D03*
X33983D03*
X38983D03*
X43983D03*
X48983D03*
X53983D03*
X58983D03*
X63983D03*
X68983D03*
X114508Y5500D03*
X119508D03*
X104508D03*
X94508D03*
X84508D03*
X74508D03*
X79508D03*
X89508D03*
X99508D03*
X109508D03*
X119763Y550725D03*
Y546225D03*
Y555225D03*
X83100Y984800D03*
X78600D03*
X83100Y980300D03*
X78600D03*
Y989300D03*
X83100D03*
X73983Y1368303D03*
X78983D03*
X83983D03*
X88983D03*
X93983D03*
X98983D03*
X107374Y1369303D03*
X112374D03*
X117374D03*
X134508Y5500D03*
X124508D03*
X129508D03*
X169508D03*
X159508D03*
X149508D03*
X139508D03*
X154508D03*
X164508D03*
X144508D03*
X124263Y546225D03*
Y550725D03*
Y555225D03*
X141978Y958572D03*
X142006Y978425D03*
X122374Y1369303D03*
X127374D03*
X132374D03*
X137374D03*
X142374D03*
X147374D03*
X152374D03*
X157374D03*
X162374D03*
X167374D03*
X209508Y5500D03*
X199508D03*
X189508D03*
X179508D03*
X204508D03*
X214508D03*
X174508D03*
X184508D03*
X194508D03*
X209863Y566625D03*
X199102Y969717D03*
Y974717D03*
X183584Y974789D03*
Y969789D03*
X199392Y985113D03*
X183551Y984789D03*
X212063Y976725D03*
X203063D03*
X207563D03*
X216563D03*
X212063Y981725D03*
X216563D03*
X207563D03*
X203063D03*
X199392Y990113D03*
X183551Y989789D03*
X172374Y1369303D03*
X177374D03*
X182374D03*
X187374D03*
X192374D03*
X197374D03*
X202374D03*
X207374D03*
X212374D03*
X217374D03*
X259508Y5500D03*
X249508D03*
X239508D03*
X229508D03*
X219508D03*
X224508D03*
X234508D03*
X244508D03*
X254508D03*
X264508D03*
X250650Y556997D03*
Y561997D03*
X265545Y556794D03*
Y561794D03*
X250661Y572936D03*
Y577936D03*
X265590Y572801D03*
Y577801D03*
X225563Y976725D03*
X221063D03*
X225563Y981725D03*
X221063D03*
X222374Y1369303D03*
X227374D03*
X232374D03*
X237374D03*
X242374D03*
X247374D03*
X252374D03*
X257374D03*
X262374D03*
X309508Y5500D03*
X299508D03*
X289508D03*
X279508D03*
X269508D03*
X304508D03*
X314508D03*
X274508D03*
X284508D03*
X294508D03*
X269763Y569725D03*
X287763D03*
X292263D03*
X274263D03*
X283263D03*
X278763D03*
X283263Y564725D03*
X287763D03*
X292263D03*
X274263D03*
X269763D03*
X278763D03*
X267374Y1369303D03*
X272374D03*
X277374D03*
X282374D03*
X287374D03*
X292374D03*
X297374D03*
X302374D03*
X307374D03*
X312374D03*
X359508Y5500D03*
X349508D03*
X339508D03*
X329508D03*
X319508D03*
X324508D03*
X334508D03*
X344508D03*
X354508D03*
X333983Y1368303D03*
X338983D03*
X343983D03*
X348983D03*
X353983D03*
X358983D03*
X363983D03*
X317374Y1369303D03*
X322374D03*
X327374D03*
X395075Y18639D03*
Y13639D03*
X389508Y5500D03*
X379508D03*
X369508D03*
X364508D03*
X374508D03*
X384508D03*
X394508D03*
X395075Y43639D03*
Y38639D03*
Y33639D03*
Y28639D03*
Y23639D03*
X399000Y62000D03*
X396000Y55500D03*
X396075Y50248D03*
X368983Y1368303D03*
X373983D03*
X378983D03*
X383983D03*
X388983D03*
X393983D03*
X398983D03*
X403983D03*
X408983D03*
X413983D03*
X418983D03*
X423983D03*
X428983D03*
X433983D03*
X438983D03*
X443983D03*
X448983D03*
X453983D03*
X458983D03*
X463983D03*
X468983D03*
X473983D03*
X478983D03*
X483983D03*
X488983D03*
X493983D03*
X498983D03*
X503983D03*
X508983D03*
X517374Y1369303D03*
X522374D03*
X527374D03*
X532374D03*
X537374D03*
X542374D03*
X547374D03*
X552374D03*
X557374D03*
X597051Y7699D03*
Y12699D03*
Y17699D03*
X604146Y5500D03*
X597051Y22699D03*
Y27699D03*
Y32699D03*
Y37699D03*
Y42699D03*
X589000Y64000D03*
X594000Y61500D03*
X596000Y56500D03*
X596051Y51090D03*
X567374Y1369303D03*
X572374D03*
X577374D03*
X582374D03*
X587374D03*
X592374D03*
X597374D03*
X602374D03*
X562374D03*
X609146Y5500D03*
X619146D03*
X614146D03*
X629146D03*
X639146D03*
X649146D03*
X654146D03*
X644146D03*
X634146D03*
X624146D03*
X637592Y593186D03*
X641792D03*
Y597386D03*
X637592D03*
X633392Y593186D03*
Y597386D03*
X629192Y593186D03*
Y597386D03*
X641792Y605786D03*
Y601586D03*
X637592D03*
Y605786D03*
X633392D03*
Y601586D03*
X629192D03*
Y605786D03*
X617374Y1369303D03*
X622374D03*
X627374D03*
X632374D03*
X637374D03*
X642374D03*
X647374D03*
X652374D03*
X607374D03*
X612374D03*
X679146Y5500D03*
X689146D03*
X694146D03*
X684146D03*
X659146D03*
X669146D03*
X664146D03*
X674146D03*
X699146D03*
X675913Y586555D03*
Y592955D03*
Y598155D03*
X672082Y582834D03*
X666882D03*
X661682D03*
X656482D03*
X695413Y600755D03*
X699613D03*
X669482Y613934D03*
Y609734D03*
X665282D03*
Y613934D03*
X661082D03*
Y609734D03*
X656882Y613934D03*
Y609734D03*
X675913Y603355D03*
X695413Y604955D03*
X691213Y613355D03*
X695413D03*
X699613D03*
X691213Y609155D03*
X695413D03*
X699613Y604955D03*
Y609155D03*
X702483Y945989D03*
X667374Y1369303D03*
X672374D03*
X677374D03*
X682374D03*
X687374D03*
X692374D03*
X697374D03*
X702374D03*
X657374D03*
X662374D03*
X749146Y5500D03*
X709146D03*
X719146D03*
X729146D03*
X739146D03*
X744146D03*
X734146D03*
X724146D03*
X714146D03*
X704146D03*
X703813Y592355D03*
Y596555D03*
Y600755D03*
X704399Y626799D03*
Y618399D03*
Y622599D03*
X703813Y613355D03*
Y609155D03*
Y604955D03*
X721552Y951317D03*
X725852Y951067D03*
X747374Y1369303D03*
X742374D03*
X717374D03*
X722374D03*
X727374D03*
X732374D03*
X737374D03*
X707374D03*
X712374D03*
X795969Y-1374D03*
X759146Y5500D03*
X769146D03*
X774146D03*
X764146D03*
X754146D03*
X779146D03*
X755500Y1374500D03*
X752500Y1370500D03*
X757287Y1380873D03*
Y1385873D03*
Y1390873D03*
Y1395873D03*
Y1400873D03*
Y1405873D03*
Y1410873D03*
Y1415873D03*
Y1420873D03*
Y1425873D03*
Y1430873D03*
Y1435873D03*
Y1440873D03*
Y1445873D03*
X766156Y1462004D03*
X771156D03*
X790500Y1466500D03*
X786000Y1463500D03*
X756287Y1459264D03*
Y1454264D03*
X779547Y1463004D03*
X792902Y1477964D03*
Y1487964D03*
Y1497964D03*
Y1507964D03*
Y1517964D03*
Y1512964D03*
Y1472964D03*
Y1482964D03*
Y1492964D03*
Y1502964D03*
Y1562964D03*
Y1527964D03*
Y1537964D03*
Y1547964D03*
Y1557964D03*
Y1567964D03*
Y1522964D03*
Y1532964D03*
Y1542964D03*
Y1552964D03*
Y1612964D03*
Y1602964D03*
Y1592964D03*
Y1582964D03*
Y1572964D03*
Y1577964D03*
Y1587964D03*
Y1597964D03*
Y1607964D03*
X797902Y1652964D03*
X792902D03*
Y1642964D03*
Y1632964D03*
Y1622964D03*
Y1627964D03*
Y1637964D03*
Y1647964D03*
Y1617964D03*
X872642Y-140575D03*
Y-135575D03*
Y-130575D03*
Y-125575D03*
X890264Y-147256D03*
X880264D03*
X875264D03*
X885264D03*
X895264D03*
X872642Y-80575D03*
Y-120575D03*
Y-115575D03*
Y-110575D03*
Y-105575D03*
Y-100575D03*
Y-95575D03*
Y-90575D03*
Y-85575D03*
Y-30575D03*
Y-35575D03*
Y-40575D03*
Y-45575D03*
Y-50575D03*
Y-55575D03*
Y-60575D03*
Y-65575D03*
Y-70575D03*
Y-75575D03*
Y-20575D03*
Y-25575D03*
X940264Y-147256D03*
X930264D03*
X925264D03*
X935264D03*
X920264D03*
X910264D03*
X900264D03*
X905264D03*
X915264D03*
X960264D03*
X950264D03*
X955264D03*
X965264D03*
X945264D03*
X990264D03*
X980264D03*
X970264D03*
X975264D03*
X985264D03*
X1010264D03*
X1000264D03*
X1005264D03*
X1015264D03*
X995264D03*
X1040264D03*
X1030264D03*
X1020264D03*
X1025264D03*
X1035264D03*
X1060264D03*
X1050264D03*
X1055264D03*
X1065264D03*
X1045264D03*
X1080264D03*
X1070264D03*
X1075264D03*
X1085264D03*
X1078098Y1652768D03*
X1073098D03*
X1083098D03*
X1088098D03*
X1110264Y-147256D03*
X1100264D03*
X1090264D03*
X1105264D03*
X1095264D03*
X1130264D03*
X1120264D03*
X1115264D03*
X1125264D03*
X1135264D03*
X1093098Y1652768D03*
X1133098D03*
X1123098D03*
X1113098D03*
X1103098D03*
X1108098D03*
X1118098D03*
X1128098D03*
X1098098D03*
X1170264Y-147256D03*
X1155264D03*
X1175602Y-137594D03*
Y-127594D03*
X1160264Y-147256D03*
X1150264D03*
X1140264D03*
X1145264D03*
X1175602Y-132594D03*
Y-142594D03*
X1165264Y-147256D03*
X1175602Y-117594D03*
Y-107594D03*
Y-97594D03*
Y-87594D03*
Y-77594D03*
Y-82594D03*
Y-92594D03*
Y-102594D03*
Y-112594D03*
Y-122594D03*
Y-67594D03*
Y-57594D03*
Y-47594D03*
Y-37594D03*
Y-32594D03*
Y-42594D03*
Y-52594D03*
Y-62594D03*
Y-72594D03*
Y-17594D03*
Y-27594D03*
X1180500Y4000D03*
X1176500Y-500D03*
X1175602Y-22594D03*
Y-12594D03*
Y-7594D03*
X1162000Y1371500D03*
X1169783Y1369303D03*
X1179783D03*
X1174783D03*
X1184783D03*
X1158673Y1417067D03*
Y1407067D03*
Y1397067D03*
Y1387067D03*
Y1377067D03*
Y1412067D03*
Y1402067D03*
Y1392067D03*
Y1382067D03*
Y1422067D03*
Y1442067D03*
Y1452067D03*
X1158500Y1468500D03*
X1158673Y1457067D03*
Y1447067D03*
Y1437067D03*
Y1427067D03*
Y1462067D03*
Y1432067D03*
X1161000Y1474500D03*
X1166673Y1477941D03*
X1171673D03*
X1181673D03*
X1176673D03*
X1143098Y1652768D03*
X1183098D03*
X1173098D03*
X1163098D03*
X1153098D03*
X1158098D03*
X1168098D03*
X1178098D03*
X1138098D03*
X1148098D03*
X1191382Y5500D03*
X1196382D03*
X1186382D03*
X1201382D03*
X1211382D03*
X1221382D03*
X1231382D03*
X1226382D03*
X1216382D03*
X1206382D03*
X1199783Y1369303D03*
X1209783D03*
X1219783D03*
X1229783D03*
X1189783D03*
X1224783D03*
X1214783D03*
X1204783D03*
X1194783D03*
X1191673Y1477941D03*
X1201673D03*
X1214972Y1482642D03*
Y1517642D03*
Y1487642D03*
Y1497642D03*
Y1507642D03*
Y1512642D03*
Y1502642D03*
Y1492642D03*
X1206673Y1477941D03*
X1196673D03*
X1186673D03*
X1211673D03*
X1214972Y1567642D03*
Y1527642D03*
Y1537642D03*
Y1547642D03*
Y1557642D03*
Y1562642D03*
Y1552642D03*
Y1542642D03*
Y1532642D03*
Y1522642D03*
Y1577642D03*
Y1587642D03*
Y1597642D03*
Y1607642D03*
Y1612642D03*
Y1602642D03*
Y1592642D03*
Y1582642D03*
Y1572642D03*
Y1617642D03*
Y1627642D03*
Y1637642D03*
X1213098Y1652768D03*
X1193098D03*
X1203098D03*
X1208098D03*
X1214972Y1642642D03*
Y1632642D03*
X1188098Y1652768D03*
X1198098D03*
X1214972Y1622642D03*
Y1647642D03*
X1251382Y5500D03*
X1261382D03*
X1271382D03*
X1281382D03*
X1276382D03*
X1266382D03*
X1256382D03*
X1241382D03*
X1246382D03*
X1236382D03*
X1249783Y1369303D03*
X1259783D03*
X1269783D03*
X1279783D03*
X1239783D03*
X1274783D03*
X1264783D03*
X1254783D03*
X1234783D03*
X1244783D03*
X1301382Y5500D03*
X1311382D03*
X1296382D03*
X1316382D03*
X1306382D03*
X1291382D03*
X1286382D03*
X1326382D03*
X1321382D03*
X1299783Y1369303D03*
X1309783D03*
X1319783D03*
X1329783D03*
X1289783D03*
X1324783D03*
X1314783D03*
X1304783D03*
X1294783D03*
X1284783D03*
X1363579Y19821D03*
Y14821D03*
Y9821D03*
X1351382Y5500D03*
X1356382D03*
X1346382D03*
X1336382D03*
X1341382D03*
X1331382D03*
X1363579Y44821D03*
Y39821D03*
Y34821D03*
Y29821D03*
Y24821D03*
X1374000Y64500D03*
X1363579Y51618D03*
X1370200Y550500D03*
X1366000D03*
X1378100Y530200D03*
Y534400D03*
X1365500Y538600D03*
X1369700D03*
X1365500Y534400D03*
X1369700D03*
X1373900D03*
X1365500Y530200D03*
X1369700D03*
X1373900D03*
X1375900Y568500D03*
X1366000Y563100D03*
X1370200D03*
Y554700D03*
X1366000D03*
X1370200Y558900D03*
X1366000D03*
X1373700Y582900D03*
X1369500D03*
X1377900Y587100D03*
Y591300D03*
Y595500D03*
X1373700D03*
Y591300D03*
Y587100D03*
X1369500Y595500D03*
Y591300D03*
Y587100D03*
X1377900Y599700D03*
X1373700D03*
X1369500D03*
X1349783Y1369303D03*
X1359783D03*
X1369783D03*
X1339783D03*
X1374783D03*
X1364783D03*
X1354783D03*
X1344783D03*
X1334783D03*
X1396500Y549500D03*
X1386500Y534400D03*
Y530200D03*
X1382300D03*
Y534400D03*
X1396500Y559900D03*
Y554700D03*
Y565100D03*
X1393000Y568500D03*
X1387300D03*
X1381600D03*
X1382100Y587100D03*
X1386300D03*
X1399783Y1369303D03*
X1409783D03*
X1419783D03*
X1379783D03*
X1389783D03*
X1404783D03*
X1414783D03*
X1424783D03*
X1394783D03*
X1384783D03*
X1434441Y590424D03*
X1434581Y586136D03*
X1449783Y1369303D03*
X1459783D03*
X1469783D03*
X1429783D03*
X1439783D03*
X1444783D03*
X1454783D03*
X1464783D03*
X1474783D03*
X1434783D03*
X1499783D03*
X1509783D03*
X1519783D03*
X1479783D03*
X1489783D03*
X1494783D03*
X1484783D03*
X1504783D03*
X1514783D03*
X1565555Y16517D03*
X1568030Y5500D03*
X1565555Y21517D03*
Y26517D03*
Y31517D03*
Y36517D03*
Y41517D03*
X1557000Y64500D03*
X1561500Y62000D03*
X1564000Y57500D03*
X1564555Y52124D03*
X1549783Y1369303D03*
X1559783D03*
X1569783D03*
X1529783D03*
X1539783D03*
X1524783D03*
X1534783D03*
X1544783D03*
X1554783D03*
X1564783D03*
X1603030Y5500D03*
X1613030D03*
X1573030D03*
X1583030D03*
X1593030D03*
X1618030D03*
X1608030D03*
X1598030D03*
X1588030D03*
X1578030D03*
X1614783Y1369303D03*
X1604783D03*
X1599783D03*
X1609783D03*
X1619783D03*
X1579783D03*
X1589783D03*
X1574783D03*
X1584783D03*
X1594783D03*
X1653030Y5500D03*
X1663030D03*
X1623030D03*
X1633030D03*
X1643030D03*
X1668030D03*
X1658030D03*
X1648030D03*
X1638030D03*
X1628030D03*
X1664783Y1369303D03*
X1654783D03*
X1644783D03*
X1634783D03*
X1624783D03*
X1649783D03*
X1659783D03*
X1629783D03*
X1639783D03*
X1703030Y5500D03*
X1713030D03*
X1673030D03*
X1683030D03*
X1693030D03*
X1718030D03*
X1708030D03*
X1698030D03*
X1688030D03*
X1678030D03*
X1697261Y1004347D03*
X1692761D03*
Y999847D03*
Y995347D03*
X1697261D03*
Y999847D03*
X1714783Y1369303D03*
X1704783D03*
X1694783D03*
X1684783D03*
X1674783D03*
X1699783D03*
X1709783D03*
X1669783D03*
X1679783D03*
X1689783D03*
X1753030Y5500D03*
X1763030D03*
X1723030D03*
X1733030D03*
X1743030D03*
X1758030D03*
X1748030D03*
X1738030D03*
X1728030D03*
X1764783Y1369303D03*
X1754783D03*
X1744783D03*
X1734783D03*
X1724783D03*
X1749783D03*
X1759783D03*
X1719783D03*
X1729783D03*
X1739783D03*
X1778030Y5500D03*
X1793030D03*
X1803030D03*
X1813030D03*
X1808030D03*
X1798030D03*
X1783030D03*
X1788030D03*
X1773030D03*
X1768030D03*
X1783806Y989468D03*
X1804783Y1369303D03*
X1794783D03*
X1784783D03*
X1774783D03*
X1799783D03*
X1809783D03*
X1769783D03*
X1779783D03*
X1789783D03*
X1843030Y5500D03*
X1853030D03*
X1863030D03*
X1838030D03*
X1858030D03*
X1848030D03*
X1823030D03*
X1833030D03*
X1828030D03*
X1818030D03*
X1862652Y846508D03*
X1850263Y964540D03*
X1850370Y960239D03*
X1845870D03*
X1845763Y964540D03*
Y956040D03*
X1850263D03*
X1825741Y969210D03*
Y974210D03*
X1840683Y969318D03*
Y974318D03*
X1825744Y986011D03*
X1840578Y985885D03*
X1844863Y983125D03*
X1853863D03*
X1858363D03*
X1849363D03*
X1862863D03*
X1853863Y978125D03*
X1844863D03*
X1849363D03*
X1862863D03*
X1858363D03*
X1825744Y991011D03*
X1840578Y990885D03*
X1854783Y1369303D03*
X1844783D03*
X1834783D03*
X1824783D03*
X1814783D03*
X1849783D03*
X1859783D03*
X1819783D03*
X1829783D03*
X1839783D03*
X1878030Y5500D03*
X1883030D03*
X1873030D03*
X1868030D03*
X1909030D03*
X1888030D03*
X1873099Y817150D03*
X1878099D03*
X1873099Y821650D03*
X1878099D03*
X1873099Y826150D03*
X1878099D03*
X1877512Y831377D03*
X1882512D03*
X1865202Y831559D03*
X1873012Y831377D03*
X1878099Y812650D03*
X1873099D03*
X1878099Y808150D03*
X1873099D03*
X1878099Y803650D03*
X1873099D03*
X1878373Y846472D03*
X1883373D03*
X1867652Y846508D03*
X1867363Y983125D03*
Y978125D03*
X1904783Y1369303D03*
X1894783D03*
X1884783D03*
X1874783D03*
X1864783D03*
X1899783D03*
X1909783D03*
X1869783D03*
X1879783D03*
X1889783D03*
X1929343Y16525D03*
Y11525D03*
Y6525D03*
X1914030Y5500D03*
X1919030D03*
X1924030D03*
X1929343Y46525D03*
Y41525D03*
Y36525D03*
Y31525D03*
Y26525D03*
Y21525D03*
Y66525D03*
Y61525D03*
Y56525D03*
Y51525D03*
Y116525D03*
Y111525D03*
Y106525D03*
Y101525D03*
Y96525D03*
Y91525D03*
Y86525D03*
Y81525D03*
Y76525D03*
Y71525D03*
Y121525D03*
Y126525D03*
Y136525D03*
Y146525D03*
Y156525D03*
Y161525D03*
Y151525D03*
Y141525D03*
Y131525D03*
Y176525D03*
Y186525D03*
Y196525D03*
Y206525D03*
Y166525D03*
Y211525D03*
Y201525D03*
Y191525D03*
Y181525D03*
Y171525D03*
Y226525D03*
Y236525D03*
Y246525D03*
Y256525D03*
Y216525D03*
Y261525D03*
Y251525D03*
Y241525D03*
Y231525D03*
Y221525D03*
Y276525D03*
Y286525D03*
Y296525D03*
Y306525D03*
Y266525D03*
Y301525D03*
Y291525D03*
Y281525D03*
Y271525D03*
Y326525D03*
Y336525D03*
Y346525D03*
Y356525D03*
Y316525D03*
Y351525D03*
Y341525D03*
Y331525D03*
Y321525D03*
Y311525D03*
Y376525D03*
Y386525D03*
Y396525D03*
Y406525D03*
Y366525D03*
Y401525D03*
Y391525D03*
Y381525D03*
Y371525D03*
Y361525D03*
Y426525D03*
Y436525D03*
Y446525D03*
Y416525D03*
Y451525D03*
Y441525D03*
Y431525D03*
Y421525D03*
Y411525D03*
Y476525D03*
Y486525D03*
Y496525D03*
Y456525D03*
Y466525D03*
Y501525D03*
Y491525D03*
Y481525D03*
Y471525D03*
Y461525D03*
Y526525D03*
Y536525D03*
Y546525D03*
Y506525D03*
Y516525D03*
Y551525D03*
Y541525D03*
Y531525D03*
Y521525D03*
Y511525D03*
Y576525D03*
Y586525D03*
Y596525D03*
Y556525D03*
Y566525D03*
Y591525D03*
Y581525D03*
Y571525D03*
Y561525D03*
Y626525D03*
Y636525D03*
Y646525D03*
Y606525D03*
Y616525D03*
Y641525D03*
Y631525D03*
Y621525D03*
Y611525D03*
Y601525D03*
Y676525D03*
Y686525D03*
Y696525D03*
Y656525D03*
Y666525D03*
Y691525D03*
Y681525D03*
Y671525D03*
Y661525D03*
Y651525D03*
Y726525D03*
Y736525D03*
Y706525D03*
Y716525D03*
Y741525D03*
Y731525D03*
Y721525D03*
Y711525D03*
Y701525D03*
Y776525D03*
Y786525D03*
Y746525D03*
Y756525D03*
Y766525D03*
Y791525D03*
Y781525D03*
Y771525D03*
Y761525D03*
Y751525D03*
Y826525D03*
Y836525D03*
Y796525D03*
Y806525D03*
Y816525D03*
Y841525D03*
Y831525D03*
Y821525D03*
Y811525D03*
Y801525D03*
Y876525D03*
Y886525D03*
Y846525D03*
Y856525D03*
Y866525D03*
Y881525D03*
Y871525D03*
Y861525D03*
Y851525D03*
Y926525D03*
Y896525D03*
Y906525D03*
Y916525D03*
Y931525D03*
Y921525D03*
Y911525D03*
Y901525D03*
Y891525D03*
Y936525D03*
Y973863D03*
Y978863D03*
Y983863D03*
Y951525D03*
Y956525D03*
Y961525D03*
Y966525D03*
Y946525D03*
Y941525D03*
Y988863D03*
Y993863D03*
Y998863D03*
Y1003863D03*
Y1008863D03*
Y1033863D03*
Y1028863D03*
Y1023863D03*
Y1018863D03*
Y1013863D03*
Y1073863D03*
Y1083863D03*
Y1043863D03*
Y1053863D03*
Y1063863D03*
Y1078863D03*
Y1068863D03*
Y1058863D03*
Y1048863D03*
Y1038863D03*
Y1123863D03*
Y1093863D03*
Y1103863D03*
Y1113863D03*
Y1128863D03*
Y1118863D03*
Y1108863D03*
Y1098863D03*
Y1088863D03*
Y1173863D03*
Y1133863D03*
Y1143863D03*
Y1153863D03*
Y1163863D03*
Y1178863D03*
Y1168863D03*
Y1158863D03*
Y1148863D03*
Y1138863D03*
Y1223863D03*
Y1183863D03*
Y1193863D03*
Y1203863D03*
Y1213863D03*
Y1228863D03*
Y1218863D03*
Y1208863D03*
Y1198863D03*
Y1188863D03*
Y1273863D03*
Y1233863D03*
Y1243863D03*
Y1253863D03*
Y1263863D03*
Y1268863D03*
Y1258863D03*
Y1248863D03*
Y1238863D03*
Y1323863D03*
Y1283863D03*
Y1293863D03*
Y1303863D03*
Y1313863D03*
Y1318863D03*
Y1308863D03*
Y1298863D03*
Y1288863D03*
Y1278863D03*
Y1333863D03*
Y1343863D03*
Y1353863D03*
X1924783Y1369303D03*
X1914783D03*
X1919783D03*
X1929343Y1358863D03*
Y1348863D03*
Y1338863D03*
Y1328863D03*
Y1363863D03*
G54D104*
X1104804Y1588583D03*
X1123032D03*
X1104804Y1601181D03*
X1123032D03*
G54D114*
G01X338971Y64135D02*
Y58753D01*
X338979Y58745D01*
G01X353001Y87515D02*
Y81799D01*
G01X351000Y70700D02*
X349555Y69255D01*
X345471D01*
G01X575700Y528831D02*
Y533081D01*
G01X904941Y1450061D02*
Y1456941D01*
G01X944921Y1515200D02*
Y1519450D01*
G01X1014800Y-62100D02*
X1016540Y-60360D01*
Y-56732D01*
G01X1054593Y-51122D02*
Y-57597D01*
G01X1183115Y264900D02*
Y260200D01*
X1182590Y259675D01*
Y257688D01*
G01X1183115Y274100D02*
Y277585D01*
X1181515Y279185D01*
Y281343D01*
G01X1186090Y257688D02*
Y260000D01*
X1185085Y261005D01*
Y264900D01*
G01X1351201Y96135D02*
Y90099D01*
G01X1452279Y563600D02*
Y559350D01*
G54D30*
X68037Y209361D03*
Y662017D03*
Y1114773D03*
X142028Y966735D03*
X192249Y209061D03*
X208728Y554735D03*
X191949Y1110473D03*
X316462Y209161D03*
Y661917D03*
Y1114773D03*
X440674Y209161D03*
X440774Y661917D03*
X508274Y1114573D03*
X564987Y209161D03*
Y661917D03*
X564887Y1114673D03*
X689100Y209261D03*
Y662017D03*
X688800Y1110373D03*
X874563Y818831D03*
X873463Y1487165D03*
X1036030Y834829D03*
X1013500Y939000D03*
X1181565Y281343D03*
X1186140Y257688D03*
X1232492Y225125D03*
X1256800Y240661D03*
X1254800Y693417D03*
Y1146173D03*
X1381013Y240661D03*
X1379013Y693417D03*
Y1146173D03*
X1503325Y240561D03*
X1503225Y693417D03*
Y1146173D03*
X1629038Y240561D03*
X1627438Y693417D03*
X1639238Y1146173D03*
X1753850Y240561D03*
X1751650Y1146173D03*
X1783828Y978735D03*
X1859769Y209161D03*
Y661917D03*
X1859991Y1102987D03*
G54D105*
X1181145Y274100D03*
X1183115D03*
Y264900D03*
X1181145D03*
X1185085Y274100D03*
X1187055D03*
Y264900D03*
X1185085D03*
G54D21*
X59937Y183961D03*
Y636717D03*
Y1089473D03*
X108363Y995525D03*
X112500Y995580D03*
X184149Y184061D03*
X175063Y583525D03*
X179200Y583580D03*
X188649Y626217D03*
X306955Y68479D03*
X314370Y121941D03*
X308362Y184061D03*
X308262Y636817D03*
Y1089573D03*
X323813Y121922D03*
X328321Y121899D03*
X318909Y121943D03*
X333021Y121955D03*
X365162Y81270D03*
X432574Y184061D03*
Y636717D03*
X447173Y1072026D03*
X442473D03*
X556787Y183961D03*
X549279Y516631D03*
X553279D03*
X556787Y636717D03*
Y1089573D03*
X580279Y516631D03*
X557279Y563631D03*
X592779Y570631D03*
X579718Y570697D03*
X571540Y570665D03*
X615100Y516900D03*
X611910Y562574D03*
X637213Y585955D03*
X681000Y183961D03*
X685500Y636717D03*
X680400Y1097600D03*
X878673Y807903D03*
X883400Y807932D03*
X881448Y1355107D03*
X881420Y1346988D03*
X882000Y1435800D03*
X873000D03*
X893050Y1482600D03*
X879321Y1482561D03*
X883947Y1482570D03*
X860000Y1501300D03*
X850500D03*
X914600Y909000D03*
X927861Y959507D03*
X921600Y978500D03*
X916500Y959400D03*
X925053Y1028685D03*
X916769Y1028739D03*
X936959Y1363590D03*
X932294Y1373148D03*
X936964Y1349912D03*
X922500Y1503000D03*
X918500D03*
X941000Y1557000D03*
X926500Y1550000D03*
X957000Y908300D03*
X970500D03*
X952500D03*
X954900Y953700D03*
X950400D03*
X959400D03*
X955000Y979300D03*
X964000D03*
X945790Y950462D03*
X955700Y1024100D03*
X951200D03*
X946700D03*
X951525Y1372957D03*
X947159Y1361887D03*
X950300Y1503000D03*
X988573Y1506512D03*
X962000Y1557000D03*
X949000D03*
X972413Y1553466D03*
X1038712Y-41958D03*
X1004100Y-73432D03*
X1035973Y827503D03*
X1034400Y905000D03*
X1002194Y978140D03*
X1006694D03*
X1007849Y1027143D03*
X1003194Y1027140D03*
X993649Y1027143D03*
X1012494Y1027240D03*
X998439Y1027137D03*
X1028000Y1070300D03*
X1022400Y1118100D03*
X1031400D03*
X1026900D03*
X1017800Y1140800D03*
X1008700D03*
X995000D03*
X1009500Y1184300D03*
X1014500D03*
X1004500D03*
X1061325Y-47400D03*
X1074400Y-45732D03*
X1040773Y827503D03*
X1054419Y832253D03*
X1048400Y905000D03*
X1057700D03*
X1064918Y938949D03*
X1069918D03*
X1087000Y1070300D03*
X1078000D03*
X1041500D03*
X1087700Y1119200D03*
X1074500Y1119300D03*
X1079000D03*
X1070155Y1119303D03*
X1083355D03*
X1115200Y1070400D03*
X1128900D03*
X1119500Y1118500D03*
X1124100D03*
X1115000D03*
X1176100Y262800D03*
X1176835Y611232D03*
X1192300Y265168D03*
X1194600Y292700D03*
X1197100Y272500D03*
X1250410Y233009D03*
X1327921Y82755D03*
X1299569Y87491D03*
X1315115Y130400D03*
X1324207Y130403D03*
X1319797Y130388D03*
X1328534D03*
X1312000Y165961D03*
X1322000D03*
X1326400Y178361D03*
X1321900D03*
X1312000Y618717D03*
X1322000D03*
X1326500Y631117D03*
X1322000D03*
X1309600Y1071473D03*
X1317400Y1071500D03*
X1326500Y1083873D03*
X1322000D03*
X1332934Y130388D03*
X1421969Y527957D03*
X1436213Y165961D03*
X1446213D03*
X1450713Y178361D03*
X1446013D03*
X1463085Y503185D03*
X1452200Y572400D03*
X1470700D03*
X1437200Y562900D03*
X1436213Y618717D03*
X1446213D03*
X1450713Y631117D03*
X1446013D03*
X1436213Y1071473D03*
X1446213D03*
X1450713Y1083873D03*
X1446013D03*
X1481938Y503070D03*
X1502400Y547450D03*
X1560425Y165961D03*
X1570425D03*
X1570125Y178361D03*
X1560425Y618717D03*
X1570425D03*
X1570225Y631117D03*
X1560425Y1071473D03*
X1570425D03*
Y1083973D03*
X1574925Y178361D03*
Y631117D03*
Y1083973D03*
X1684638Y165961D03*
X1694638D03*
X1699138Y178361D03*
X1694438D03*
X1684638Y618717D03*
X1694638D03*
X1699138Y631117D03*
X1694438D03*
X1684638Y1071473D03*
X1694638D03*
X1699138Y1083873D03*
X1694438D03*
X1750163Y1007525D03*
X1754300Y1007580D03*
X1808850Y165961D03*
Y618717D03*
X1805250Y1071273D03*
X1845517Y161775D03*
X1841017D03*
X1818850Y165961D03*
X1823350Y178361D03*
X1818650D03*
X1818850Y618717D03*
X1823350Y631117D03*
X1818650D03*
X1845417Y614531D03*
X1840917D03*
X1815250Y1071273D03*
X1823350Y1083873D03*
X1818650D03*
X1838074Y1088995D03*
X1836200Y1133220D03*
X1878900Y187544D03*
Y640300D03*
X1876662Y1058726D03*
X1872162D03*
G54D12*
X20000Y60000D03*
Y80000D03*
Y100000D03*
Y120000D03*
Y140000D03*
Y160000D03*
Y180000D03*
Y200000D03*
Y220000D03*
Y240000D03*
Y260000D03*
Y280000D03*
Y300000D03*
Y320000D03*
Y340000D03*
Y360000D03*
Y380000D03*
Y400000D03*
Y420000D03*
Y440000D03*
X15000Y930000D03*
Y920000D03*
X25000Y930000D03*
Y920000D03*
X15000Y980000D03*
Y970000D03*
Y960000D03*
Y950000D03*
Y940000D03*
X25000D03*
Y950000D03*
Y960000D03*
Y970000D03*
Y980000D03*
X15000Y1030000D03*
Y1020000D03*
Y1010000D03*
Y1000000D03*
Y990000D03*
X25000D03*
Y1000000D03*
Y1010000D03*
Y1020000D03*
Y1040000D03*
Y1080000D03*
Y1070000D03*
Y1060000D03*
Y1050000D03*
Y1090000D03*
X19712Y1176350D03*
X25000Y1190400D03*
X17500Y1270000D03*
Y1260000D03*
Y1250000D03*
Y1240000D03*
Y1290000D03*
Y1280000D03*
Y1300000D03*
Y1310000D03*
Y1320000D03*
Y1360000D03*
Y1350000D03*
Y1330000D03*
Y1340000D03*
X60000Y20000D03*
Y40000D03*
X40000D03*
X60000Y60000D03*
X40000D03*
Y80000D03*
X60000D03*
Y100000D03*
X40000D03*
X60000Y120000D03*
X40000D03*
Y140000D03*
X60000D03*
Y160000D03*
X40000D03*
X38500Y202000D03*
X64487Y212761D03*
Y201761D03*
X53087Y179561D03*
X56000Y237000D03*
X73437Y247161D03*
X49437Y254661D03*
X73437Y234661D03*
X49937Y219661D03*
X54437D03*
X58937D03*
X62000Y276500D03*
X40000Y280000D03*
Y300000D03*
X60000D03*
Y320000D03*
X40000D03*
X60000Y340000D03*
X40000D03*
Y360000D03*
X35000Y446500D03*
X50500Y545500D03*
X58346Y516473D03*
X54088Y512336D03*
X39853Y512373D03*
X44111Y516510D03*
X47607Y527511D03*
X61834Y527515D03*
X72500Y508600D03*
X67500D03*
X40000Y560000D03*
Y580000D03*
Y600000D03*
Y620000D03*
X39000Y646000D03*
X53087Y632317D03*
X30697Y679553D03*
X73437Y687417D03*
X64487Y665417D03*
X31043Y689115D03*
X30676Y663764D03*
X58937Y672417D03*
X54437D03*
X49937D03*
X64487Y654417D03*
X27143Y663071D03*
X27510Y688422D03*
X49500Y729000D03*
X49437Y707417D03*
X73437Y699917D03*
X31064Y704904D03*
X69500Y777000D03*
X51000Y755500D03*
X38500Y800500D03*
X39000Y834500D03*
X49000Y811000D03*
X51000Y846000D03*
X40000Y930000D03*
Y920000D03*
Y970000D03*
Y960000D03*
Y950000D03*
Y940000D03*
X58175Y981325D03*
X67500Y961355D03*
X72500D03*
X50000Y1030000D03*
X70000Y1020000D03*
X40000Y1000000D03*
Y990000D03*
X50000Y1060000D03*
X47000Y1107500D03*
X64487Y1118173D03*
X30256Y1116731D03*
X30670Y1132472D03*
X58937Y1125173D03*
X54437D03*
X49937D03*
X64487Y1107173D03*
X53027Y1085073D03*
X39325Y1131400D03*
X26723Y1116038D03*
X30644Y1157871D03*
X49437Y1160173D03*
X73437Y1140173D03*
Y1152673D03*
X30623Y1142082D03*
X36848Y1173600D03*
X27090Y1141389D03*
X52000Y1186000D03*
X71500Y1205000D03*
X31500Y1224000D03*
X39425Y1226200D03*
X30000Y1190400D03*
X37225Y1230100D03*
X45800Y1306100D03*
X37500Y1360000D03*
X27500D03*
X45518Y1336366D03*
X41381Y1335567D03*
X80000Y80000D03*
X100000D03*
X120000D03*
Y100000D03*
X100000D03*
X80000D03*
X120000Y120000D03*
X100000D03*
X80000D03*
X86500Y157500D03*
X80000Y140000D03*
X118437Y141870D03*
X78500Y169500D03*
X111437Y195492D03*
X106937Y198543D03*
Y207992D03*
X111437Y165492D03*
Y180492D03*
X74937Y187461D03*
X92287Y194661D03*
X86637Y194861D03*
X95437Y176661D03*
Y181161D03*
X73937Y201661D03*
X78937D03*
X83937D03*
X88937D03*
X82000Y219000D03*
X111437Y245492D03*
Y235492D03*
X106937Y217441D03*
X111437Y265492D03*
Y275492D03*
X89237Y276861D03*
X95437Y300161D03*
X96000Y336500D03*
X80000Y320000D03*
Y340000D03*
X118437Y314114D03*
X89000Y403500D03*
X100000Y420000D03*
X120000Y440000D03*
X100000D03*
Y460000D03*
X120000D03*
Y480000D03*
X100000D03*
X120000Y500000D03*
X100000D03*
X104500Y515500D03*
X120500Y524000D03*
X86500Y522000D03*
X100000Y541500D03*
X87000Y541000D03*
X89000Y557500D03*
X108500Y572000D03*
X88000Y577500D03*
X118753Y594626D03*
X88000Y602500D03*
X111437Y648248D03*
Y633248D03*
Y618248D03*
X92287Y647417D03*
X86637Y647617D03*
X74937Y640217D03*
X85146Y621637D03*
X95437Y633917D03*
X81500Y672000D03*
X106937Y670197D03*
X111437Y688248D03*
X106937Y660748D03*
Y651299D03*
X88937Y654417D03*
X83937D03*
X78937D03*
X73937D03*
X111437Y728248D03*
Y718248D03*
Y698248D03*
X89237Y729617D03*
X75500Y757500D03*
X94000Y789000D03*
X118437Y766870D03*
X95437Y752917D03*
X89500Y802500D03*
X90000Y858000D03*
X100000Y880000D03*
Y900000D03*
X120000D03*
Y920000D03*
X100000D03*
X120000Y940000D03*
X111800Y987200D03*
Y983200D03*
X115800Y979200D03*
X119800Y971200D03*
Y975200D03*
Y979200D03*
X115800Y975200D03*
X119800Y987200D03*
Y983200D03*
X115800Y971200D03*
Y983200D03*
Y987200D03*
X119163Y959625D03*
X100000Y940000D03*
X97063Y973225D03*
X98563Y977225D03*
X120000Y1025000D03*
X85000Y1020000D03*
X121914Y1003491D03*
X114100Y1002600D03*
X99700Y991400D03*
X108063Y991925D03*
X114300Y992362D03*
X104230Y992209D03*
X74000Y1074000D03*
X85000Y1060000D03*
X111437Y1071004D03*
X118437Y1047382D03*
X95537Y1082173D03*
X81000Y1124500D03*
X106937Y1122953D03*
Y1113504D03*
Y1104055D03*
X111437Y1101004D03*
Y1086004D03*
X92287Y1100173D03*
X86637Y1100373D03*
X74937Y1092973D03*
X95537Y1086673D03*
X73937Y1107173D03*
X78937D03*
X83937D03*
X88937D03*
X111437Y1171004D03*
Y1151004D03*
Y1141004D03*
X118437Y1219626D03*
X111437Y1181004D03*
X89237Y1182373D03*
X95437Y1205673D03*
X98500Y1241000D03*
X90000Y1252500D03*
X86000Y1282000D03*
X93000Y1319000D03*
X160000Y20000D03*
Y60000D03*
Y40000D03*
X140000D03*
Y60000D03*
X160000Y100000D03*
Y80000D03*
X140000D03*
Y100000D03*
X160000Y140000D03*
X140000D03*
X160000Y120000D03*
X140000D03*
X156500Y170500D03*
X130500Y211500D03*
X160500Y190000D03*
X160000Y180000D03*
X129000Y259000D03*
X142687Y237161D03*
Y248100D03*
X128000Y288500D03*
X160000Y280000D03*
X140000Y300000D03*
X160000D03*
X145437Y265561D03*
X140000Y320000D03*
X160000D03*
X140000Y440000D03*
Y460000D03*
Y480000D03*
Y500000D03*
X142500Y515500D03*
X150000Y526500D03*
X164107Y512331D03*
X168365Y516368D03*
X135000Y588000D03*
X153263Y568725D03*
X146263D03*
X144263Y573225D03*
X138763Y568725D03*
X148763Y576225D03*
X166400Y579400D03*
X163763Y561225D03*
X165263Y565225D03*
X167000Y613000D03*
X147500Y605500D03*
X142687Y689917D03*
X135200Y738400D03*
X153705Y744831D03*
X153714Y720741D03*
X153757Y710653D03*
X140372Y732370D03*
X150253Y709713D03*
X145437Y717617D03*
X142687Y700767D03*
X140364Y749807D03*
X160000Y880000D03*
Y900000D03*
X140000Y920000D03*
X160000D03*
Y940000D03*
X140000D03*
X130463Y983925D03*
X156000Y1032000D03*
X133063Y1012725D03*
X137063Y993725D03*
X131110Y993257D03*
X134000Y1064000D03*
X153000Y1105000D03*
X132000Y1117000D03*
X148400Y1086900D03*
X142687Y1142673D03*
X154363Y1161725D03*
X153716Y1174793D03*
X145437Y1165673D03*
X150862Y1152723D03*
X142687Y1153523D03*
X170000Y1190500D03*
X153824Y1197248D03*
X153932Y1182940D03*
X148300Y1228800D03*
X148311Y1182767D03*
X135422Y1190937D03*
X140422D03*
X163500Y1345200D03*
X200000Y20000D03*
X180000D03*
X200000Y40000D03*
X180000D03*
X200000Y60000D03*
X180000D03*
Y80000D03*
X200000D03*
Y100000D03*
X180000D03*
Y120000D03*
X200000D03*
Y140000D03*
X180000D03*
X216500Y194756D03*
X210849Y194861D03*
X199149Y187461D03*
X188699Y212561D03*
Y200561D03*
X177399Y179661D03*
X198149Y201661D03*
X203149D03*
X208149D03*
X213149D03*
X206000Y219000D03*
X180500Y237000D03*
X197649Y234661D03*
X173649Y254661D03*
X197649Y247161D03*
X174149Y219661D03*
X178649D03*
X183149D03*
X180000Y300000D03*
X213449Y276861D03*
X180000Y320000D03*
Y340000D03*
X200000D03*
X178342Y512294D03*
X182600Y516331D03*
X171861Y527469D03*
X186088Y527473D03*
X196712Y508600D03*
X191712D03*
X210263Y546725D03*
X188614Y591491D03*
X182500Y559200D03*
Y571200D03*
Y575200D03*
X178500D03*
Y571200D03*
X182500Y567200D03*
X186500Y559200D03*
Y563200D03*
Y567200D03*
X182500Y563200D03*
X186500Y575200D03*
Y571200D03*
X180800Y590600D03*
X207313Y598113D03*
X203763Y581725D03*
X197810Y581257D03*
X174763Y579925D03*
X181000Y580362D03*
X170930Y580209D03*
X197163Y571925D03*
X210000Y644000D03*
X216499Y636917D03*
X199149Y631217D03*
X210849Y638617D03*
X185149Y617949D03*
X199763Y600725D03*
X206000Y672000D03*
X197649Y687417D03*
X210000Y650000D03*
X182259Y672559D03*
X177759D03*
X173259D03*
X198149Y654417D03*
X203149D03*
X208149D03*
X213149D03*
X213449Y729617D03*
X173649Y707417D03*
X197649Y699917D03*
X180000Y860000D03*
Y880000D03*
Y920000D03*
Y900000D03*
X199900Y923200D03*
X188706Y941328D03*
X194206D03*
X184017Y951112D03*
Y945612D03*
X198463Y945525D03*
Y951025D03*
X216712Y961155D03*
X184295Y1009469D03*
Y1014969D03*
X198741Y1014882D03*
Y1009382D03*
X188552Y1019166D03*
X215563Y1001225D03*
X203563D03*
X207563D03*
X211563D03*
X194052Y1019166D03*
X211000Y1065000D03*
X203500Y1124500D03*
X216499Y1100173D03*
X210849Y1100373D03*
X199149Y1092973D03*
X188399Y1113873D03*
Y1102873D03*
X183149Y1125173D03*
X178649D03*
X174149D03*
X177105Y1094839D03*
X195100Y1096800D03*
X198149Y1107173D03*
X203149D03*
X208149D03*
X213149D03*
X175000Y1143000D03*
X173649Y1160173D03*
X193423Y1140945D03*
X197649Y1152673D03*
X213449Y1182373D03*
X181000Y1261000D03*
X190000Y1320000D03*
X200000D03*
X210000D03*
Y1300000D03*
Y1310000D03*
X200000D03*
X190000D03*
X260000Y20000D03*
X220000D03*
X240000D03*
X260000Y60000D03*
Y40000D03*
X240000D03*
X220000D03*
Y60000D03*
X240000D03*
X260000Y100000D03*
Y80000D03*
X240000D03*
X220000D03*
Y100000D03*
X240000D03*
X260000Y140000D03*
Y120000D03*
X240000D03*
X220000D03*
X242649Y141870D03*
X262000Y209000D03*
X235649Y195492D03*
X231991Y198543D03*
X231149Y207992D03*
X235649Y165492D03*
Y180492D03*
X219749Y176661D03*
Y181361D03*
X253000Y260000D03*
X266899Y237161D03*
X235649Y245492D03*
Y235492D03*
X231149Y217441D03*
X266899Y248011D03*
X255000Y280000D03*
X235649Y265492D03*
Y275492D03*
X219649Y300161D03*
X242649Y314114D03*
X220000Y360000D03*
X240000Y380000D03*
X220000D03*
Y400000D03*
X240000D03*
Y420000D03*
X220000D03*
Y440000D03*
X240000D03*
Y460000D03*
X220000D03*
Y480000D03*
X240000D03*
Y500000D03*
X220000D03*
X265392Y539225D03*
Y533725D03*
X250586Y533920D03*
Y539420D03*
X260703Y529168D03*
X255203D03*
X220000Y520000D03*
X265275Y596896D03*
X250974Y597308D03*
X243051Y594626D03*
X265275Y602396D03*
X250974Y602808D03*
X255410Y607833D03*
X235649Y648248D03*
Y633248D03*
Y618248D03*
X260910Y607833D03*
X219749Y618917D03*
Y623417D03*
X255500Y664500D03*
X231149Y670197D03*
X235649Y688248D03*
X231149Y660748D03*
Y651299D03*
X266899Y689917D03*
X235649Y728248D03*
Y718248D03*
Y698248D03*
X264739Y732114D03*
X258600Y715500D03*
X266899Y700767D03*
X242649Y766870D03*
X219649Y752917D03*
X248500Y788500D03*
X264731Y749551D03*
X225000Y840000D03*
X245000D03*
X265000Y795000D03*
X225000Y815000D03*
Y880000D03*
X245000D03*
X225000Y860000D03*
X245000D03*
X225000Y900000D03*
X245000D03*
X223100Y920600D03*
X245000Y940000D03*
X239000Y985600D03*
X221712Y961155D03*
X263000Y1023000D03*
X219563Y1001225D03*
X223563D03*
X252100Y990100D03*
X244600Y1004600D03*
X261100Y1005700D03*
X227063Y994925D03*
X263000Y1047000D03*
X235649Y1071004D03*
X242649Y1047382D03*
X219749Y1082173D03*
X231149Y1122953D03*
Y1113504D03*
Y1104055D03*
X235649Y1101004D03*
Y1086004D03*
X264864Y1120500D03*
X219749Y1086873D03*
X235649Y1171004D03*
Y1151004D03*
X235300Y1142700D03*
X266899Y1141173D03*
X255000Y1207500D03*
X242649Y1219626D03*
X235649Y1181004D03*
X219649Y1205673D03*
X264594Y1190768D03*
X259594D03*
X257000Y1253000D03*
X220000Y1270000D03*
Y1320000D03*
X230000D03*
X240000D03*
X250000D03*
X260000D03*
X220000Y1280000D03*
X230000D03*
X250000Y1290000D03*
X240000D03*
X230000D03*
X220000D03*
Y1300000D03*
X230000D03*
X240000D03*
X250000D03*
X260000D03*
Y1310000D03*
X250000D03*
X240000D03*
X230000D03*
X220000D03*
X300000Y20000D03*
X280000D03*
X300000Y40000D03*
X280000Y60000D03*
Y40000D03*
X312079Y68379D03*
X303029Y68429D03*
X280000Y100000D03*
Y80000D03*
X313312Y98705D03*
X312355Y72855D03*
X313628Y112926D03*
X303000Y73500D03*
X280000Y140000D03*
Y120000D03*
X314370Y118452D03*
X314439Y133669D03*
X270000Y179500D03*
X285500Y189500D03*
X283000Y181000D03*
X314329Y212420D03*
X312912Y201661D03*
X301612Y179661D03*
X304500Y237000D03*
X297862Y254661D03*
X298362Y219661D03*
X302862D03*
X307362D03*
X300000Y300000D03*
X269649Y266261D03*
X300000Y320000D03*
Y340000D03*
X295000Y400000D03*
Y440000D03*
X291601Y418503D03*
X295000Y460000D03*
X292153Y486059D03*
X306388Y486022D03*
X302513Y512294D03*
X306771Y516331D03*
X292536Y516368D03*
X288278Y512331D03*
X296032Y527469D03*
X310259Y527473D03*
X282263Y589225D03*
X270263D03*
X274263D03*
X286263D03*
X290263D03*
X278263D03*
X293763Y582925D03*
X277000Y618500D03*
X275000Y647000D03*
X294500Y607500D03*
X284000D03*
X301612Y632417D03*
X312912Y665417D03*
X307362Y672417D03*
X302862D03*
X298362D03*
X312912Y654417D03*
X277972Y744575D03*
X297862Y707417D03*
X277981Y720485D03*
X278024Y710397D03*
X274520Y709457D03*
X286000Y810500D03*
X268100Y982300D03*
X273300Y981700D03*
X280800Y1011900D03*
X281200Y1033000D03*
X305200Y1068400D03*
X295200Y1078400D03*
Y1058400D03*
X271100Y1063200D03*
X281500Y1036744D03*
X281000Y1105000D03*
X312912Y1118273D03*
X307362Y1125173D03*
X302862D03*
X298362D03*
X313232Y1106499D03*
X301327Y1085173D03*
X304500Y1142500D03*
X302452Y1165162D03*
X278577Y1161725D03*
X277930Y1175001D03*
X269649Y1165673D03*
X275385Y1152596D03*
X271165Y1147172D03*
X306000Y1182500D03*
X278076Y1197355D03*
X278146Y1182940D03*
X315500Y1216700D03*
X276100Y1229100D03*
X273243Y1182915D03*
X286925Y1201945D03*
X301000Y1231000D03*
X295900Y1339700D03*
X296100Y1335100D03*
X279900Y1328300D03*
X283700D03*
X286100Y1349659D03*
X292600Y1337367D03*
X289510Y1342259D03*
X360000Y20000D03*
X340000D03*
X320000D03*
X360000Y40000D03*
X340000D03*
X320000D03*
X355200Y58400D03*
X346245Y58745D03*
X354100Y62100D03*
X322500Y68345D03*
X334845Y58745D03*
X317812Y98905D03*
X353001Y81799D03*
X351000Y70700D03*
X322545Y72845D03*
X361776Y70842D03*
X335081Y104081D03*
X339219Y95188D03*
X339914Y82415D03*
X344304Y82439D03*
X345321Y102400D03*
X347647Y95614D03*
X353001Y114815D03*
X347881Y114881D03*
X351416Y95788D03*
X337641Y114910D03*
X334947Y94605D03*
X342761Y114861D03*
X328000Y150500D03*
X333021Y129679D03*
X350441Y117541D03*
X337721Y129821D03*
X323813Y118512D03*
X341114Y123622D03*
X345321Y118921D03*
X323813Y133722D03*
X359862Y165492D03*
Y180492D03*
Y195492D03*
X355362Y198543D03*
Y207992D03*
X323362Y187461D03*
X340712Y194661D03*
X335062Y194861D03*
X344062Y176461D03*
X343962Y181161D03*
X322362Y201661D03*
X327362D03*
X332362D03*
X337362D03*
X333500Y219000D03*
X359862Y245492D03*
Y235492D03*
X355362Y217441D03*
X321862Y234661D03*
Y247161D03*
X359862Y265492D03*
Y275492D03*
X337662Y276861D03*
X343862Y300161D03*
X352000Y331000D03*
X320000Y340000D03*
X320474Y379474D03*
X316534D03*
X320474Y363234D03*
X316534D03*
X350000Y440000D03*
X330000D03*
X350000Y500000D03*
Y480000D03*
Y460000D03*
X330000D03*
X320925Y485385D03*
X315925D03*
X330000Y540000D03*
X350000D03*
Y520000D03*
X320925Y508600D03*
X315925D03*
X333000Y560000D03*
Y580000D03*
X350000Y560000D03*
X333000Y604000D03*
X359862Y648248D03*
Y633248D03*
Y618248D03*
X340712Y647517D03*
X335062Y647617D03*
X323362Y640217D03*
X333682Y621858D03*
X343862Y633917D03*
X330000Y672000D03*
X355362Y670197D03*
X359862Y688248D03*
X355362Y660748D03*
Y651299D03*
X321862Y687417D03*
X322362Y654417D03*
X327362D03*
X332362D03*
X337362D03*
X359862Y728248D03*
Y718248D03*
Y698248D03*
X337662Y729617D03*
X321862Y699917D03*
X355000Y780500D03*
X320000Y750000D03*
X330000Y770000D03*
X347000Y788500D03*
X343862Y752917D03*
X320474Y832229D03*
X316534D03*
X361500Y901500D03*
X330000Y900000D03*
X320925Y938140D03*
X315600Y933600D03*
X335300Y926900D03*
X360000Y960000D03*
Y940000D03*
X330000Y960000D03*
X337100Y972100D03*
X320925Y961355D03*
X315925D03*
X322000Y988500D03*
X362000Y1017000D03*
X344737Y995637D03*
X350673Y1031200D03*
X328000Y1061000D03*
X359862Y1071004D03*
X344062Y1082073D03*
X355362Y1122953D03*
Y1113504D03*
Y1104055D03*
X359862Y1101004D03*
Y1086004D03*
X340812Y1100273D03*
X335062Y1100373D03*
X323362Y1092973D03*
X344062Y1086773D03*
X322362Y1107173D03*
X327362D03*
X332362D03*
X337362D03*
X358518Y1171114D03*
X359862Y1151004D03*
Y1141004D03*
X321862Y1140173D03*
Y1152673D03*
X331679Y1175800D03*
X327500Y1197000D03*
X359862Y1181004D03*
X337662Y1182373D03*
X343862Y1205673D03*
X353000Y1231000D03*
X330000Y1302000D03*
X380000Y20000D03*
Y60000D03*
Y40000D03*
X401000Y89000D03*
X400000Y80000D03*
X365162Y88731D03*
Y77731D03*
X377144Y84720D03*
X377944Y95929D03*
X388500Y153500D03*
X395500Y160500D03*
X366862Y141870D03*
X386000Y209000D03*
X390312Y237161D03*
X390412Y248011D03*
X389000Y289000D03*
X386800Y263800D03*
X385500Y313000D03*
X366862Y314114D03*
X390000Y500000D03*
X370000D03*
X390000Y540000D03*
Y520000D03*
X370000D03*
Y540000D03*
X389000Y594500D03*
X390000Y560000D03*
X370000D03*
X366862Y594626D03*
X395000Y631000D03*
X388000Y607000D03*
X410000Y692500D03*
X379000Y664000D03*
X391112Y689917D03*
X402129Y744503D03*
X388796Y732042D03*
X402138Y720413D03*
X402181Y710325D03*
X393862Y719917D03*
X398677Y709385D03*
X391112Y700767D03*
X402500Y780500D03*
X366862Y766870D03*
X388788Y749479D03*
X407714Y761291D03*
X398254Y763517D03*
X397000Y911000D03*
X380000Y960000D03*
Y940000D03*
X393500Y988500D03*
Y1017000D03*
X408672Y1008038D03*
X390000Y1055000D03*
X366862Y1047382D03*
X388888Y1118173D03*
X391112Y1142673D03*
X399474Y1166787D03*
X385210Y1166347D03*
X393679Y1157480D03*
X383191Y1170203D03*
X391112Y1153500D03*
X366862Y1219626D03*
X406037Y1192706D03*
X402403Y1188312D03*
X398527Y1188659D03*
X383849Y1190833D03*
X388849Y1191148D03*
X398527Y1233336D03*
X437124Y212661D03*
X447574Y187461D03*
X437124Y201661D03*
X429224Y176300D03*
X446951Y213656D03*
X451951D03*
X456951D03*
X446074Y247161D03*
X422300Y254661D03*
X446074Y234661D03*
X431574Y219661D03*
X427074D03*
X422574D03*
X441645Y288847D03*
Y284647D03*
X456190Y354105D03*
X444687Y379474D03*
X440747D03*
X444687Y363234D03*
X440747D03*
X452800Y420912D03*
X418600Y445462D03*
X421700Y450200D03*
X445138Y487743D03*
X440138D03*
X447533Y475900D03*
X458679Y470700D03*
X450500Y459562D03*
X416303Y486022D03*
X430538Y485985D03*
X430000Y545500D03*
X460000Y540000D03*
X426663Y512257D03*
X430921Y516294D03*
X416686Y516331D03*
X412428Y512294D03*
X420182Y527432D03*
X434409Y527436D03*
X440138Y508600D03*
X445138D03*
X460000Y600000D03*
X445000D03*
X440000Y560000D03*
X460000D03*
X440000Y613000D03*
X459274Y647617D03*
X447574Y640217D03*
X425824Y632317D03*
X457853Y622091D03*
X417000Y652500D03*
X454500Y672000D03*
X446074Y687417D03*
X437224Y665417D03*
Y654417D03*
X431574Y672417D03*
X427074D03*
X422574D03*
X456574Y654417D03*
X451574D03*
X446574D03*
X452500Y744500D03*
X437500Y744000D03*
X422074Y707417D03*
X446074Y699917D03*
X455000Y780000D03*
X445000D03*
X440000Y760000D03*
X445000Y798000D03*
X444687Y832229D03*
X440747D03*
X444687Y816765D03*
X440747D03*
X445138Y938140D03*
X440138D03*
X435082Y915200D03*
X437600Y917800D03*
X445582Y925352D03*
X449137Y967757D03*
X440138Y961355D03*
X445138D03*
X428000Y988500D03*
X429613Y1017920D03*
X432657Y1015102D03*
X442600Y998300D03*
X413000Y1054200D03*
X442473Y1068726D03*
X447173D03*
X424000Y1105000D03*
X453473Y1089300D03*
X456919Y1121725D03*
X447919D03*
X452419D03*
X441976Y1107576D03*
X446627Y1112973D03*
X418500Y1176800D03*
X437104Y1160696D03*
X441400Y1169400D03*
X450500Y1208500D03*
X424000Y1206000D03*
X416900Y1221800D03*
X454500Y1248500D03*
X460000Y1320000D03*
X440000D03*
X460000Y1300000D03*
X412300Y1326200D03*
X415422Y1352000D03*
X422373Y1359747D03*
X418922Y1356522D03*
X476319Y144481D03*
X506750Y165324D03*
X480159Y201245D03*
X500184Y200328D03*
X497785Y178034D03*
X478306Y195593D03*
X461122Y194861D03*
X462200Y173109D03*
X468472Y182441D03*
X461951Y213656D03*
X484074Y245492D03*
X478651Y220734D03*
X484074Y235492D03*
Y275492D03*
X481174Y265492D03*
X461874Y276861D03*
X468074Y300161D03*
X491074Y314114D03*
X470000Y400000D03*
Y380000D03*
Y430000D03*
X465000Y491000D03*
X462133Y473300D03*
X481533Y480875D03*
X506746Y512331D03*
X497351Y531531D03*
X501023Y534941D03*
X499000Y553000D03*
X491074Y594626D03*
X472022Y582062D03*
X484074Y648248D03*
Y633248D03*
Y618248D03*
X464924Y647417D03*
X468174Y633917D03*
X479574Y670197D03*
X484074Y688248D03*
X479574Y660748D03*
Y651299D03*
X461574Y654417D03*
X484074Y728248D03*
Y718248D03*
Y698248D03*
X461874Y729617D03*
X461500Y769500D03*
X491074Y766870D03*
X468074Y752917D03*
X500000Y960000D03*
Y940000D03*
X480000Y960000D03*
Y940000D03*
X504000Y988500D03*
X462000D03*
X465200Y1018200D03*
X468000Y1047000D03*
X484074Y1071004D03*
X491074Y1047382D03*
X460673Y1071976D03*
X460873Y1077526D03*
X506500Y1051900D03*
X465346Y1122953D03*
X479574Y1113504D03*
Y1104055D03*
X484074Y1101004D03*
Y1086004D03*
X504724Y1118073D03*
Y1107073D03*
X484074Y1171004D03*
Y1151004D03*
Y1141004D03*
X506700Y1141973D03*
X505874Y1134773D03*
X506700Y1145973D03*
X502500Y1211500D03*
X476373Y1219498D03*
X484074Y1181004D03*
X461874Y1182373D03*
X468074Y1205673D03*
X508103Y1190557D03*
X480000Y1320000D03*
X500000Y1300000D03*
X480000D03*
Y1280000D03*
X509180Y145419D03*
X546009Y187821D03*
X539584Y184694D03*
X542155Y187543D03*
X519868Y242334D03*
X557057Y220152D03*
X553674Y220121D03*
X550219Y220111D03*
X515324Y252511D03*
X515500Y301000D03*
X550987Y262810D03*
X553742Y267705D03*
X510700Y277200D03*
X548500Y343000D03*
X515000Y322500D03*
X534905Y354105D03*
X547500Y440000D03*
X539350Y487659D03*
X534350D03*
X510621Y486059D03*
X524856Y486022D03*
X520981Y512294D03*
X549279Y513331D03*
X525579Y538331D03*
X557279Y513331D03*
X525239Y516331D03*
X511004Y516368D03*
X518700Y548700D03*
X553279Y523331D03*
X514500Y524469D03*
X528727Y524973D03*
X553279Y513331D03*
X530130Y547167D03*
X534350Y508600D03*
X539350D03*
X540000Y583000D03*
Y600000D03*
X520000D03*
X533879Y566031D03*
X548767Y556819D03*
X520579Y553231D03*
X517499Y576931D03*
X557279Y570331D03*
X527179Y568731D03*
X528000Y611000D03*
X532000Y623000D03*
X549937Y632317D03*
X515324Y689917D03*
X555787Y672417D03*
X551287D03*
X546787D03*
X526225Y744756D03*
X546287Y707417D03*
X512892Y732295D03*
X526277Y710578D03*
X526234Y720666D03*
X509996Y716996D03*
X522773Y709638D03*
X515324Y700667D03*
X509000Y772000D03*
X512884Y749732D03*
X555500Y852000D03*
X551500Y888000D03*
X523500Y883500D03*
X525000Y937000D03*
X525500Y967000D03*
X530800Y1028300D03*
X515800Y1028000D03*
X523000Y1045000D03*
X528500Y1073500D03*
X556022Y1042817D03*
X552436Y1042494D03*
X546787Y1125173D03*
X551287D03*
X555787D03*
X549773Y1085173D03*
X514474Y1107073D03*
X519474D03*
X524474D03*
X529474D03*
X546287Y1160173D03*
X535320Y1152771D03*
X534874Y1139774D03*
X526523Y1177122D03*
X526501Y1166546D03*
X509037Y1136700D03*
X524828Y1159231D03*
X526388Y1197747D03*
X526367Y1183111D03*
X522867Y1190284D03*
X513103Y1190557D03*
X522867Y1231097D03*
X539000Y1309000D03*
X520600Y1324100D03*
X536000Y1359826D03*
X541362D03*
X518397Y1360000D03*
X512900Y1345600D03*
X553587Y1346026D03*
X527000Y1340600D03*
X521500Y1342800D03*
X603787Y207992D03*
X604517Y196263D03*
X603697Y182091D03*
X586719Y196888D03*
X568687Y187660D03*
X583487Y194861D03*
X566271Y167387D03*
X561437Y197249D03*
X592767Y179277D03*
X598236Y181981D03*
X582697Y200744D03*
X577697D03*
X572697D03*
X587697D03*
X588188Y216520D03*
X570287Y234661D03*
X563000Y217600D03*
X569009Y247887D03*
X592287Y300161D03*
X582758Y276861D03*
X590000Y342000D03*
X568899Y379474D03*
X564959D03*
X568899Y363234D03*
X564959D03*
X560000Y438500D03*
X594500Y462000D03*
X569529Y502127D03*
X575700Y528831D03*
X563279Y506731D03*
X602379Y547831D03*
X570779Y542831D03*
X568779Y512831D03*
X575779D03*
X593079Y516531D03*
Y512531D03*
X585479Y537731D03*
Y543994D03*
X572229Y520081D03*
X580279Y512831D03*
X592000Y595000D03*
X580000Y600000D03*
X560000D03*
X571408Y577450D03*
X584279Y577431D03*
X575779D03*
X579718D03*
X592779D03*
X588779D03*
X562279D03*
X567641Y577473D03*
X571529Y562951D03*
X579529D03*
X602779Y552331D03*
X586000Y611000D03*
X589137Y647417D03*
X583487Y647617D03*
X571787Y640217D03*
X592387Y629417D03*
Y634017D03*
X579000Y672000D03*
X603787Y670197D03*
Y660748D03*
Y651299D03*
X570287Y687417D03*
X561437Y665417D03*
Y654417D03*
X585787D03*
X580787D03*
X575787D03*
X570787D03*
X559000Y741000D03*
X586087Y729617D03*
X570287Y699917D03*
X603000Y781000D03*
X592287Y752917D03*
X568899Y832229D03*
X564959D03*
X593365Y877358D03*
X592614Y882300D03*
X604000Y897000D03*
X592000Y900500D03*
X569350Y941640D03*
X564350D03*
X569350Y961355D03*
X564350D03*
X589500Y988000D03*
X571000D03*
X571400Y1000100D03*
X575000Y1057500D03*
X586500Y1061500D03*
X586000Y1046500D03*
X575000Y1046000D03*
X592387Y1082173D03*
X561337Y1120873D03*
X583487Y1100373D03*
X571787Y1092973D03*
X589137Y1100173D03*
X603787Y1122953D03*
Y1113504D03*
Y1104055D03*
X561337Y1107173D03*
X592387Y1086873D03*
X570787Y1107173D03*
X575787D03*
X580787D03*
X585787D03*
X570287Y1140173D03*
Y1152673D03*
X600640Y1171000D03*
X567500Y1189500D03*
X586087Y1182373D03*
X592287Y1205673D03*
X592400Y1214456D03*
X590000Y1247000D03*
X613500Y66000D03*
X634500Y77000D03*
X629024Y107633D03*
X607929Y112329D03*
X619171D03*
X614967Y134777D03*
X606718Y168580D03*
X639537Y237161D03*
X608287Y245492D03*
Y235492D03*
X639537Y248011D03*
X649500Y285000D03*
X608287Y275492D03*
X607961Y263934D03*
X642287Y266461D03*
X650000Y322500D03*
X615287Y314114D03*
X649000Y429500D03*
X652663Y502400D03*
X647663D03*
X612000Y502300D03*
X624028Y503558D03*
X638263Y503494D03*
X643000Y549500D03*
X620153Y511994D03*
X634388Y511957D03*
X615100Y513287D03*
X638646Y515994D03*
X624411Y516031D03*
X615119Y551586D03*
X627000Y538581D03*
Y542909D03*
X609334Y538306D03*
Y543306D03*
X619560Y547201D03*
X627863Y522000D03*
X642509Y520667D03*
X652663Y516600D03*
X647663D03*
X615287Y594626D03*
X615147Y565956D03*
X637213Y582155D03*
X623236Y562574D03*
X608287Y648248D03*
Y633248D03*
Y618248D03*
Y688248D03*
X639537Y689917D03*
X650659Y744673D03*
X608287Y728248D03*
Y718248D03*
Y698248D03*
X637326Y732212D03*
X650668Y720583D03*
X650711Y710495D03*
X642287Y719817D03*
X647207Y709555D03*
X639537Y700767D03*
X631500Y774000D03*
X615287Y766870D03*
X637318Y749649D03*
X642000Y889500D03*
X632000Y936000D03*
X654000Y911000D03*
X646500Y898500D03*
X634000Y988000D03*
X638500Y1046500D03*
X608287Y1071004D03*
X615287Y1047382D03*
X645200Y1067800D03*
X608287Y1101004D03*
Y1086004D03*
X643000Y1146173D03*
X608287Y1171004D03*
Y1151004D03*
Y1141004D03*
X651216Y1164051D03*
X636803Y1167864D03*
X642942Y1156818D03*
X632603Y1136225D03*
X647716Y1154150D03*
X639537Y1153523D03*
X615238Y1218951D03*
X608287Y1181004D03*
X650644Y1197038D03*
X650626Y1182447D03*
X627632Y1217300D03*
X647126Y1189513D03*
X632316Y1190474D03*
X637316D03*
X700000Y60000D03*
X675000Y75500D03*
X697457Y107247D03*
X697483Y111500D03*
X661965Y106177D03*
X687566Y109568D03*
X663449Y115606D03*
X690807Y103298D03*
X658500Y184500D03*
X695137Y189130D03*
X685545Y212806D03*
X677450Y185669D03*
X685250Y199493D03*
X699950Y200846D03*
X694950D03*
X689426Y236628D03*
X694500Y247161D03*
X670500Y254661D03*
X674313Y220374D03*
X669813D03*
X673500Y344000D03*
X689232Y355251D03*
X693112Y385976D03*
X689172D03*
Y358978D03*
X698500Y415500D03*
X695500Y462500D03*
X670000Y531500D03*
X658646Y515180D03*
X696787Y580633D03*
X658681Y571798D03*
X654681D03*
X683341Y580479D03*
X689747D03*
X696000Y641717D03*
X682000Y628449D03*
X694500Y687417D03*
X685550Y665417D03*
Y654417D03*
X679929Y673058D03*
X675429D03*
X670929D03*
X700000Y654417D03*
X695000D03*
X670500Y707417D03*
X694500Y699917D03*
X691500Y778000D03*
X692500Y790500D03*
X678500Y776500D03*
X673500Y752000D03*
X658574Y930100D03*
X677457Y944796D03*
X688563Y961355D03*
X693563D03*
X663800Y1018300D03*
X682200Y1026500D03*
X674300Y1001620D03*
X696000Y1092973D03*
X685250Y1113673D03*
Y1102873D03*
X680000Y1125173D03*
X675500D03*
X671000D03*
X674700Y1098500D03*
X695000Y1107173D03*
X700000D03*
X667700Y1160173D03*
X694500Y1140173D03*
X692671Y1152747D03*
X668000Y1195000D03*
X680500Y1208500D03*
X698500Y1306500D03*
X664000Y1278100D03*
X673000Y1354100D03*
X740000Y40000D03*
X720000D03*
Y60000D03*
X740000D03*
X724645Y138941D03*
X732500Y180492D03*
Y165492D03*
X728000Y207992D03*
Y198543D03*
X732100Y198373D03*
X707700Y194861D03*
X713350Y194661D03*
X747242Y197553D03*
X717188Y176461D03*
X716600Y181161D03*
X709950Y200846D03*
X704950D03*
X728000Y217441D03*
X732500Y245492D03*
X731048Y238563D03*
X738361Y306612D03*
X732500Y275492D03*
Y265492D03*
X710300Y276861D03*
X716500Y300161D03*
X724000Y338500D03*
X748000Y368500D03*
X726000Y369000D03*
X732000Y374500D03*
Y383000D03*
X748500Y409000D03*
X721500Y462500D03*
X727500Y476000D03*
X705348Y478425D03*
X724000Y583500D03*
X702500Y563000D03*
X739500Y594626D03*
X732500Y648248D03*
Y633248D03*
Y618248D03*
X713350Y647417D03*
X716600Y629417D03*
Y633917D03*
X704500Y672000D03*
X728000Y670197D03*
X732500Y688248D03*
X728000Y660748D03*
Y651299D03*
X707700Y649117D03*
X710000Y654417D03*
X705000D03*
X732500Y728248D03*
Y718248D03*
Y698248D03*
X710300Y729617D03*
X748000Y783000D03*
X739500Y766870D03*
X716500Y752917D03*
X745000Y833000D03*
X704500Y795000D03*
X730882Y888502D03*
X716233Y868219D03*
X733422Y857828D03*
X708683Y876958D03*
X747656Y876717D03*
X724283Y860689D03*
X741883Y861389D03*
X709500Y894500D03*
X733883Y935689D03*
X736883Y938689D03*
Y929189D03*
Y933689D03*
X733883Y940689D03*
X736462Y948996D03*
X736883Y943189D03*
X712000Y1046000D03*
X732500Y1071004D03*
X739500Y1047382D03*
X716600Y1081973D03*
X728000Y1122953D03*
Y1113504D03*
Y1104055D03*
X732500Y1101004D03*
Y1086004D03*
X713350Y1100173D03*
X707700Y1100373D03*
X716600Y1086673D03*
X705000Y1107173D03*
X710000D03*
X716000Y1136000D03*
X732500Y1171004D03*
Y1151004D03*
Y1141004D03*
X739500Y1219626D03*
X732500Y1181004D03*
X710300Y1182373D03*
X716500Y1205673D03*
X728174Y1275611D03*
X725678Y1272799D03*
X722790Y1270557D03*
X720446Y1267427D03*
X748500Y1287500D03*
X731500Y1277811D03*
X789045Y11615D03*
X780000Y40000D03*
X760000D03*
Y60000D03*
X780000D03*
X757020Y159692D03*
X752950Y213450D03*
X758619Y168537D03*
X767405Y210364D03*
X763188Y172500D03*
X771500Y311000D03*
X789739Y365493D03*
X764000Y439500D03*
X767500Y463500D03*
X772000Y479500D03*
X787000Y514000D03*
X798140Y630220D03*
X798210Y626440D03*
X798367Y622400D03*
X751750Y685300D03*
X754500Y668741D03*
X755000Y677700D03*
X793000Y828000D03*
Y851000D03*
X765124Y864089D03*
X766707Y872260D03*
X762453Y872413D03*
X765025Y867802D03*
X757664Y868974D03*
X753883Y929689D03*
Y937689D03*
X763883Y907689D03*
X755883D03*
X750883Y903689D03*
X753883Y945689D03*
X776400Y956500D03*
X780800Y959300D03*
X778000Y988500D03*
X762500D03*
X786800Y1016000D03*
X784000Y1024000D03*
X763000Y1075000D03*
X759500Y1056100D03*
X756250Y1140250D03*
X752500Y1167500D03*
X756250Y1151750D03*
X752000Y1197500D03*
X756000Y1225500D03*
X770000Y1231500D03*
X769500Y1283500D03*
X792336Y1319537D03*
X782230Y1323670D03*
X769728Y1325747D03*
X785340Y1320410D03*
X789549Y1322310D03*
X777009Y1322690D03*
X781000Y1373000D03*
X781290Y1328490D03*
X772900Y1328550D03*
X790290Y1328410D03*
X785640Y1328370D03*
X784000Y1443000D03*
X796848Y1469724D03*
X829921Y-458D03*
X825984D03*
X833724Y-3346D03*
X833671Y254D03*
X806299Y-458D03*
X802362D03*
X814173D03*
X810236D03*
X822047D03*
X818110D03*
X845661Y-3642D03*
X843463Y530D03*
X802102Y51075D03*
X799102Y48575D03*
X802102Y46075D03*
X799102Y43575D03*
X802102Y41075D03*
X845961Y61762D03*
Y56762D03*
Y52762D03*
X838521Y41568D03*
X838043Y37217D03*
X806314Y35952D03*
X802350Y35923D03*
X842470Y41295D03*
X841733Y36654D03*
X818300Y39845D03*
X814300D03*
Y43845D03*
X818300D03*
X846000Y116500D03*
X810301Y78654D03*
X805301D03*
X802801Y75654D03*
X807801D03*
X812801D03*
X811500Y372000D03*
X800000Y400000D03*
X811500Y469500D03*
X846400Y469300D03*
Y473900D03*
X839000Y541000D03*
X839500Y508500D03*
Y560000D03*
X800867Y619400D03*
X803367Y622400D03*
X809015Y661000D03*
X804015D03*
X808920Y652340D03*
Y656460D03*
X806515Y664000D03*
X827500Y922500D03*
X827000Y1168000D03*
X802036Y1164244D03*
X803438Y1139700D03*
X802500Y1194500D03*
X807500D03*
X812500D03*
X810000Y1191500D03*
X805000D03*
X809600Y1236300D03*
X804600D03*
X802100Y1233300D03*
X807100D03*
X812100D03*
X806952Y1460496D03*
X806568Y1464275D03*
X802433Y1461619D03*
X800900Y1465234D03*
X800462Y1469231D03*
X839414Y1520763D03*
X834813Y1528889D03*
X834974Y1533243D03*
X882000Y-105500D03*
X885046Y20384D03*
X886322Y69D03*
X867080Y393D03*
X886427Y3802D03*
X873892Y287D03*
X886418Y-7350D03*
X849484Y649D03*
X886351Y-3735D03*
X857513Y659D03*
X861101Y66680D03*
X862099Y61626D03*
Y56626D03*
X861961Y52762D03*
X852769Y66957D03*
X848769D03*
X856769D03*
X853961Y52762D03*
X849961D03*
X857961D03*
X874244Y37026D03*
Y44935D03*
X885448Y37380D03*
X877265Y52540D03*
X881265D03*
X885265D03*
X873265D03*
X869265D03*
X869459Y56626D03*
Y61626D03*
X869044Y66985D03*
X873044D03*
X877139Y66926D03*
X885265Y60540D03*
Y56540D03*
X881750Y37397D03*
X858496Y37121D03*
X854180Y36996D03*
X852995Y40965D03*
X856995D03*
X852769Y74957D03*
X856769D03*
X861142Y71026D03*
X852810Y71303D03*
X856810D03*
X853900Y89701D03*
X886073Y78824D03*
X885464Y83201D03*
X878549Y78905D03*
Y82905D03*
X869044Y70985D03*
X873044D03*
X882549Y76905D03*
Y80905D03*
X888500Y260500D03*
X872796Y251714D03*
X850500Y266000D03*
X866000Y315000D03*
X881549Y326304D03*
X890982Y349498D03*
X874800Y355798D03*
X856500Y373000D03*
X858632Y399200D03*
X855032D03*
Y395600D03*
X858632D03*
X855032Y392000D03*
X858632D03*
X852832Y406400D03*
Y402800D03*
X856432Y406400D03*
Y402800D03*
X887100Y359100D03*
X887500Y378495D03*
X875132Y399200D03*
X878732D03*
Y395600D03*
X875132D03*
X878732Y392000D03*
X875132D03*
X880932Y406400D03*
Y402800D03*
X877332Y406400D03*
Y402800D03*
X874807Y375193D03*
X852832Y410000D03*
X856432D03*
X866276Y454900D03*
X866317Y446725D03*
X880932Y410000D03*
X877332D03*
X857300Y454300D03*
X862000Y453600D03*
X852000Y454200D03*
X866321Y451300D03*
X855500Y499500D03*
X871487Y463589D03*
X878500Y476000D03*
X878193Y467707D03*
X866278Y459562D03*
X870600Y476900D03*
X851800Y477200D03*
X860092Y542405D03*
X867500Y643000D03*
X877000Y664500D03*
X868500Y665000D03*
X868100Y685600D03*
X871700D03*
X875300D03*
X884600Y688800D03*
X881000D03*
X877400D03*
X891000Y743500D03*
X874715Y707651D03*
X871115D03*
X867515D03*
X884700Y705200D03*
X881100D03*
X877500D03*
X870500Y762500D03*
X885600Y824400D03*
X870163Y836153D03*
X865663Y834403D03*
X867663Y818831D03*
X887600Y811900D03*
X891200Y838200D03*
X878673Y804527D03*
X874569Y811300D03*
X885882Y861618D03*
X894965Y843500D03*
X877673Y868873D03*
X888962Y843262D03*
X873647Y861653D03*
X882333Y896320D03*
X895616Y985932D03*
X863800Y1309876D03*
X885301Y1358557D03*
X884746Y1350438D03*
X873495Y1370213D03*
X885300Y1371050D03*
X872164Y1350464D03*
X873259Y1365805D03*
X872181Y1354764D03*
X886792Y1404100D03*
X873918Y1411149D03*
X873800Y1418200D03*
X871432Y1420932D03*
X874900Y1421900D03*
X877406Y1419124D03*
X875740Y1415070D03*
X882226Y1404197D03*
X873694Y1404575D03*
X873700Y1375746D03*
X873570Y1380401D03*
X877300Y1432400D03*
X886500Y1432500D03*
X872192Y1424492D03*
X882000Y1432600D03*
X870921Y1432300D03*
X893158Y1516542D03*
X893050Y1489500D03*
X868791Y1478782D03*
X888800Y1493500D03*
X876514Y1514948D03*
X863851Y1501681D03*
X877828Y1500379D03*
X892966Y1508549D03*
X893036Y1512600D03*
X877946Y1496527D03*
X876096Y1505499D03*
X889002Y1489638D03*
X873972Y1472467D03*
X873922Y1477766D03*
X860179Y1491170D03*
X892682Y1520718D03*
X855092Y1535821D03*
X866621Y1544206D03*
X893020Y1566530D03*
X876200Y1553900D03*
X892700Y1543900D03*
X892558Y1528458D03*
X889300Y1551000D03*
X876190Y1537187D03*
X876100Y1549000D03*
X876200Y1558400D03*
X892700Y1524700D03*
X848551Y1542440D03*
X910500Y-137500D03*
X928600Y-115200D03*
X902000Y-58000D03*
X922687Y93D03*
X928138Y-8453D03*
X909000Y89000D03*
X898000Y133000D03*
X911000Y305500D03*
X898000Y268000D03*
X942000Y752850D03*
X897000Y839000D03*
X915000Y879000D03*
X903000Y842500D03*
X926185Y928342D03*
X924974Y933041D03*
X895869Y932822D03*
X914876Y901029D03*
X937621Y915324D03*
X920810Y902210D03*
X928100Y900650D03*
X900615Y909723D03*
X902571Y906534D03*
X903368Y934568D03*
X904594Y931141D03*
X916204Y938572D03*
X917550Y934742D03*
X901540Y937712D03*
X896679Y927505D03*
X896420Y916712D03*
X898468Y912970D03*
X931085Y936172D03*
X941274Y900845D03*
X924563Y962945D03*
X919759Y970868D03*
X938009Y987330D03*
X941868Y952101D03*
X934142Y974344D03*
X939481Y980230D03*
X912994Y971921D03*
X910397Y979189D03*
X902991Y982230D03*
X909826Y982874D03*
X905271Y974586D03*
X899846Y971468D03*
X898617Y975434D03*
X895837Y978389D03*
X896629Y982285D03*
X935623Y971054D03*
X898920Y1020000D03*
X916446Y1035438D03*
X941640Y995820D03*
X904601Y998556D03*
X910040Y1006613D03*
X911807Y1002342D03*
X919656Y998764D03*
X939544Y1003485D03*
X903442Y1003265D03*
X896371Y1002112D03*
X936378Y1035722D03*
X929257Y1035883D03*
X920770Y1067389D03*
X921149Y1062424D03*
X914948Y1063255D03*
X908477Y1061823D03*
X910387Y1055344D03*
X904875Y1051177D03*
X906000Y1222000D03*
X924500Y1236000D03*
X942925Y1369010D03*
X928384Y1346435D03*
X932559Y1360137D03*
X928439Y1360167D03*
X932564Y1346100D03*
X896500Y1341800D03*
X936959Y1360143D03*
X896212Y1345788D03*
X932294Y1379995D03*
X928194D03*
X895900Y1390100D03*
X896200Y1386000D03*
X896100Y1393800D03*
X896200Y1397900D03*
Y1405300D03*
X896100Y1401600D03*
X923829Y1389012D03*
X936994Y1379895D03*
X927601Y1384433D03*
X923486Y1384268D03*
X904941Y1456941D03*
X906600Y1461600D03*
X909400Y1459200D03*
X910000Y1464900D03*
X905500Y1467161D03*
X932500Y1493200D03*
X926500Y1499700D03*
X918500D03*
X938000Y1499200D03*
X942000Y1499500D03*
X922500Y1499700D03*
X908742Y1477427D03*
X908542Y1481127D03*
X922500Y1509700D03*
X906000Y1543700D03*
X918505Y1530405D03*
X918800Y1534500D03*
X941000Y1564200D03*
X937000D03*
X926500Y1556700D03*
X931500Y1564200D03*
X913250Y1547700D03*
X940000Y1529200D03*
X940750Y1549200D03*
X900000Y1526500D03*
X897400Y1574000D03*
X897038Y1577600D03*
X911516Y1573202D03*
X911616Y1576802D03*
X911710Y1582375D03*
X911094Y1585923D03*
X924059Y1647700D03*
X986713Y-115570D03*
X971713D03*
X981700Y-115500D03*
X976713Y-115570D03*
X991713Y-115413D03*
X989316Y-94984D03*
X992185Y-54411D03*
X989050Y-70850D03*
X975500Y11500D03*
X990565Y130230D03*
Y135230D03*
Y125230D03*
X974000Y402000D03*
X985688Y362549D03*
X974000Y523000D03*
X985500Y613500D03*
X978000Y677000D03*
X977794Y695103D03*
X952200Y742600D03*
X957100Y742900D03*
X977622Y699464D03*
X953200Y736700D03*
X956900Y737600D03*
X949048Y755225D03*
X952476Y753652D03*
X951300Y747900D03*
X956200Y748200D03*
X957320Y769818D03*
X947866Y763541D03*
X957629Y766231D03*
X952820Y769518D03*
X944500Y760750D03*
X962900Y905000D03*
X981580Y932678D03*
X953967Y933635D03*
X961100Y931640D03*
X960503Y936185D03*
X967583Y933607D03*
X968698Y928957D03*
X974484Y935078D03*
X976419Y931628D03*
X976460Y927891D03*
X981679Y936678D03*
X976213Y938846D03*
X966000Y937500D03*
X976580Y986180D03*
X948942Y974655D03*
X961134Y976191D03*
X959400Y960300D03*
X953013Y960147D03*
X947174Y957150D03*
X979020Y960000D03*
Y956200D03*
X973900Y960000D03*
Y956200D03*
X968780Y960000D03*
Y956200D03*
X987734Y979575D03*
X946138Y1006299D03*
X987970Y1004157D03*
X955700Y1030700D03*
X951200D03*
X946700D03*
X947759Y998726D03*
X961220Y1001600D03*
Y1005400D03*
X966340Y1001600D03*
Y1005400D03*
X971460Y1001600D03*
Y1005400D03*
X974020Y1026200D03*
Y1022400D03*
X968900Y1026200D03*
Y1022400D03*
X963780Y1026200D03*
Y1022400D03*
X956600Y1001700D03*
Y1005700D03*
X977400Y1157900D03*
X964537Y1160310D03*
X958870Y1163617D03*
X962941Y1165929D03*
X967497Y1168802D03*
X957871Y1171219D03*
X963000Y1174427D03*
X969463Y1177599D03*
X972924Y1158033D03*
X954395Y1145604D03*
X977500Y1182300D03*
X982387Y1183598D03*
X962500Y1298500D03*
X947125Y1369010D03*
X951525Y1369107D03*
X955500Y1369000D03*
X944921Y1515200D03*
X988624Y1502923D03*
X951815Y1491459D03*
X946300Y1499300D03*
X969198Y1505851D03*
X969472Y1501978D03*
X950300Y1499500D03*
X975813Y1556916D03*
X953500Y1563200D03*
X962000Y1564200D03*
X958000D03*
X949000D03*
X945000D03*
X972001Y1533926D03*
X975813Y1545916D03*
X954700Y1524100D03*
Y1530363D03*
X974787Y1525100D03*
Y1529300D03*
X948750Y1549200D03*
X979963Y1545689D03*
X1034916Y-82413D03*
Y-87913D03*
X1011984Y-83066D03*
X1012174Y-88726D03*
X1004213Y-95837D03*
X998045Y-79300D03*
X993816Y-95184D03*
X1036713Y-115500D03*
X1015582Y-69800D03*
X1014800Y-62100D03*
X999300Y-64400D03*
X1009100Y-48600D03*
X1035000Y-66800D03*
X1022618Y-36900D03*
X1023300Y-44200D03*
X1032053Y-34953D03*
X1038712Y-34812D03*
X1007582Y-39418D03*
X1000300Y-74200D03*
X1032080Y-45980D03*
X1004082Y-38200D03*
X1000418Y-69982D03*
X993000Y-60600D03*
X1019118Y-34382D03*
X1019082Y-71000D03*
X1026717Y-11646D03*
X1021086Y-11682D03*
X1017600Y63600D03*
Y58900D03*
Y54200D03*
X1010650Y49950D03*
Y67650D03*
X993000Y108000D03*
X1036003Y93543D03*
X1038503Y97543D03*
X1033503D03*
Y102543D03*
Y107543D03*
Y112543D03*
X993000Y157000D03*
X1030775Y130016D03*
X1030890Y137780D03*
X993565Y137730D03*
Y132730D03*
Y127730D03*
X1030774Y133840D03*
X1030758Y126274D03*
X1030825Y122335D03*
X993000Y329000D03*
X1020250Y357188D03*
X998000Y378000D03*
X995000Y455000D03*
X1040180Y437510D03*
X995000Y488000D03*
X1018322Y545207D03*
X1018300Y550000D03*
X993000Y635000D03*
X1025000Y817000D03*
X1028472Y834829D03*
X1027063Y850703D03*
X1031563Y852453D03*
X1038215Y877191D03*
X1034271Y876911D03*
X1011100Y904600D03*
X1025000Y897700D03*
X1036431Y929752D03*
X1037083Y933300D03*
X1016842Y916445D03*
X1014891Y943357D03*
X1013713Y974651D03*
X997694Y974940D03*
X1035947Y948800D03*
X1025774Y1001538D03*
X992994Y1005740D03*
X1012494Y1033840D03*
X1028657Y1009103D03*
X1020654Y1023940D03*
X1018094Y1021240D03*
X1015534Y1023840D03*
X1007849Y1033743D03*
X996600D03*
X1012974Y1021240D03*
X1013700Y1007640D03*
X1009509Y1009850D03*
X1037282Y995028D03*
X1005294Y997940D03*
Y1001740D03*
X1010414Y997940D03*
Y1001740D03*
X1023214Y1007140D03*
X1007372Y1023832D03*
X1017194Y1033840D03*
X1018000Y1076500D03*
X1037000Y1067100D03*
X1032500D03*
X1017000Y1093950D03*
X1021200Y1094300D03*
X1031400Y1124700D03*
X1026900Y1129466D03*
X1022400Y1129183D03*
X1036160Y1095500D03*
Y1091700D03*
Y1111900D03*
X1019000Y1178000D03*
X1013400Y1137500D03*
X1021991Y1141526D03*
X1004294Y1137600D03*
X994923Y1137488D03*
X997500Y1192500D03*
X1006800Y1191200D03*
X995948Y1184250D03*
X1017354Y1196124D03*
X1021061Y1198543D03*
X1032500Y1248000D03*
X993500Y1317000D03*
X1016835Y1323916D03*
X1025335Y1324216D03*
X1031000Y1350500D03*
X1031474Y1354526D03*
X1016672Y1338228D03*
X1025284Y1341216D03*
X1025335Y1337616D03*
Y1330916D03*
X1016600Y1332000D03*
X1033000Y1416125D03*
X1028000Y1404700D03*
Y1411000D03*
X1031500Y1408000D03*
X1020854Y1455075D03*
X1016854D03*
X1065621Y-85082D03*
X1046713Y-115570D03*
X1076713D03*
X1084200Y-82300D03*
X1074400Y-81000D03*
X1051713Y-114887D03*
X1056713Y-115413D03*
X1086713Y-115570D03*
X1081713D03*
X1071713D03*
X1066713D03*
X1041713Y-115465D03*
X1085300Y-90700D03*
X1070500Y-67900D03*
X1074400Y-39100D03*
X1079600Y-50700D03*
X1087700Y-37886D03*
X1045800Y-75936D03*
X1058333Y-72770D03*
X1061325Y-40378D03*
X1054625Y-40278D03*
X1079455Y-30742D03*
X1043000Y-67600D03*
X1043112Y-34912D03*
X1066600Y-72800D03*
X1066225Y-40278D03*
X1054593Y-51122D03*
X1078900Y-45782D03*
X1085800Y-57100D03*
X1070918Y-73618D03*
X1076000Y-10500D03*
X1043303Y-27685D03*
X1045873Y-24660D03*
X1043513Y-21696D03*
X1077505Y22405D03*
X1076418Y31082D03*
X1076944Y35182D03*
X1077260Y42612D03*
X1077400Y52000D03*
X1077082Y38982D03*
X1076905Y46195D03*
X1076299Y27282D03*
X1054800Y22405D03*
X1078500Y99000D03*
X1043703Y112543D03*
Y107543D03*
Y102543D03*
X1041003Y93543D03*
X1043703Y97543D03*
X1062854Y83434D03*
X1078500Y135500D03*
X1043500Y310500D03*
X1048500Y346000D03*
X1058500Y368500D03*
X1045000Y364000D03*
X1050100Y392600D03*
Y397600D03*
Y402600D03*
X1044600Y392500D03*
Y397500D03*
Y402500D03*
X1041500Y382858D03*
X1078100Y392600D03*
Y397600D03*
Y402600D03*
X1072600Y392500D03*
Y397500D03*
Y402500D03*
X1045292Y384688D03*
X1044600Y407500D03*
X1050100Y407600D03*
X1042833Y434409D03*
X1074425Y447225D03*
X1071950Y453288D03*
X1072600Y407500D03*
X1078100Y407600D03*
X1043674Y451921D03*
X1043500Y446600D03*
X1042800Y442000D03*
X1047000Y492000D03*
X1079000Y477000D03*
X1058000D03*
X1069018Y456900D03*
X1065985Y460500D03*
X1045106Y561249D03*
X1058000Y616000D03*
X1073000Y676000D03*
X1047000Y751000D03*
X1045163Y840400D03*
X1082000Y815500D03*
X1054419Y839493D03*
Y828081D03*
X1050763Y829163D03*
X1086600Y833200D03*
X1054000Y866000D03*
X1075500Y848000D03*
X1044680Y921400D03*
X1053200Y901703D03*
X1043882Y901568D03*
X1044101Y927130D03*
X1083633Y932172D03*
X1073408Y942399D03*
X1058571Y943852D03*
X1072000Y1035000D03*
X1053099Y1021657D03*
X1048512Y1021378D03*
X1041616Y997225D03*
X1052000Y1054000D03*
X1082500Y1067100D03*
X1073500D03*
X1054080Y1077680D03*
X1069000Y1067100D03*
X1064500Y1096150D03*
X1068700Y1096600D03*
X1087700Y1125800D03*
X1083355Y1125903D03*
X1070155D03*
X1048960Y1113900D03*
Y1117700D03*
X1041280Y1121500D03*
Y1113900D03*
Y1117700D03*
X1081078Y1095362D03*
X1083660Y1092700D03*
X1041280Y1095500D03*
Y1091700D03*
Y1100500D03*
X1048960Y1095500D03*
Y1091700D03*
Y1099300D03*
X1054080Y1113900D03*
Y1117700D03*
X1068700Y1108700D03*
X1083355Y1116103D03*
X1070155D03*
X1075600Y1179090D03*
X1053743Y1174221D03*
X1046900Y1168000D03*
X1052522Y1145153D03*
X1076032Y1191144D03*
X1070000Y1184100D03*
X1079500Y1276100D03*
X1047000Y1258687D03*
X1051300Y1253300D03*
X1077300Y1271700D03*
X1042343Y1324216D03*
X1048251Y1349992D03*
X1046372Y1356326D03*
X1042343Y1337616D03*
X1042443Y1342668D03*
X1042343Y1330916D03*
X1076754Y1455075D03*
X1072754D03*
X1044654D03*
X1048654D03*
X1134500Y-103500D03*
X1117535Y-115157D03*
X1115000Y-77500D03*
X1097600Y-82462D03*
X1107700Y-76800D03*
X1100929Y-90371D03*
X1116600Y-85538D03*
X1106300Y-94800D03*
X1089318Y-91682D03*
X1114400Y-55662D03*
X1093900Y-64500D03*
X1113300Y-44100D03*
X1101246Y-31005D03*
X1124024Y-30840D03*
X1128765Y-34297D03*
X1094200Y-38400D03*
X1111254Y-31020D03*
X1105328Y-31005D03*
X1094300Y-60300D03*
X1103300Y-60000D03*
X1115603Y-60293D03*
X1134110Y176500D03*
X1136203Y167600D03*
X1089300Y836100D03*
X1119159Y878130D03*
Y873130D03*
Y868130D03*
X1116159Y870630D03*
Y875630D03*
X1119419Y888607D03*
X1100847Y905617D03*
X1105847D03*
X1110847D03*
X1108347Y902617D03*
X1103347D03*
X1116419Y896107D03*
Y891107D03*
X1119419Y893607D03*
Y898607D03*
X1110447Y944217D03*
X1105447D03*
X1100447D03*
X1102947Y947217D03*
X1107947D03*
X1119700Y1067200D03*
X1124500D03*
X1091400Y1070900D03*
X1091494Y1075994D03*
X1097800Y1070700D03*
X1097500Y1075100D03*
X1103800Y1070600D03*
Y1075600D03*
X1128900Y1067200D03*
X1101580Y1091120D03*
X1107100Y1096050D03*
X1111600Y1097800D03*
X1124100Y1125100D03*
X1119500D03*
X1115000D03*
X1123600Y1096400D03*
X1123838Y1092800D03*
X1123600Y1100000D03*
X1133981Y1096283D03*
X1134002Y1092600D03*
X1134103Y1099881D03*
X1137436Y1124750D03*
X1128800Y1125100D03*
X1092200Y1125800D03*
X1103064Y1113626D03*
X1099020Y1112276D03*
X1096460Y1115125D03*
X1092742Y1113462D03*
X1134100Y1433300D03*
X1090818Y1531620D03*
X1092927Y1558887D03*
Y1555087D03*
X1095938Y1531620D03*
Y1535420D03*
X1090818D03*
X1096547Y1558887D03*
Y1555087D03*
X1139500Y-58500D03*
X1150000Y-63000D03*
X1146768Y-31238D03*
X1139808Y-31171D03*
X1149699Y-35153D03*
X1142293Y-37522D03*
X1181568Y55168D03*
X1181868Y50568D03*
Y45568D03*
X1181568Y60168D03*
X1178268Y64068D03*
X1183268D03*
X1184088Y101360D03*
X1184141Y96794D03*
X1178268Y85068D03*
Y69068D03*
Y89068D03*
X1183268Y85068D03*
Y69068D03*
Y89068D03*
X1178656Y104637D03*
X1176952Y93390D03*
X1177500Y153500D03*
X1140550Y179200D03*
X1142800Y174637D03*
X1140500Y171400D03*
X1182590Y254388D03*
X1171749Y259163D03*
X1175400Y258800D03*
X1174037Y281343D03*
X1176300Y284500D03*
X1180953Y284800D03*
X1185588Y285035D03*
X1185000Y281343D03*
X1176100Y270603D03*
X1176300Y288600D03*
X1173500Y397000D03*
X1156500Y467000D03*
X1166500Y635000D03*
X1156500Y619000D03*
X1176835Y618934D03*
X1156500Y650000D03*
X1169768Y730300D03*
Y723100D03*
Y726700D03*
X1175568Y712300D03*
X1171968D03*
X1175568Y715900D03*
X1171968D03*
X1173368Y730300D03*
X1171968Y719500D03*
X1175568D03*
X1173368Y726700D03*
Y723100D03*
X1181000Y814000D03*
X1156500Y813000D03*
X1179000Y829500D03*
X1166500D03*
X1138198Y832424D03*
X1158500Y868500D03*
X1172736Y1031786D03*
X1177036Y1032086D03*
X1144580Y1078680D03*
X1170140Y1043939D03*
X1172564Y1118373D03*
X1152880Y1097672D03*
X1152682Y1091138D03*
X1149984Y1115804D03*
X1143550Y1120317D03*
X1139524Y1121817D03*
X1152800Y1223062D03*
X1152700Y1216213D03*
X1150420Y1229800D03*
X1181400Y1266100D03*
X1184000Y1260100D03*
X1149823Y1233373D03*
X1144000Y1310000D03*
X1150232Y1316358D03*
X1154500Y1327500D03*
X1150911Y1329500D03*
X1147900Y1421500D03*
X1143900Y1431000D03*
X1142400Y1427700D03*
X1146002Y1427906D03*
X1145007Y1424446D03*
X1148556Y1425056D03*
X1153000Y1496000D03*
X1163000Y1612000D03*
X1141000Y1632000D03*
X1228500Y12500D03*
X1204768Y64368D03*
X1199768D03*
X1209768D03*
X1204068Y50368D03*
Y45368D03*
X1203768Y60568D03*
Y55568D03*
X1188268Y64068D03*
X1224000Y104000D03*
X1199768Y69368D03*
X1204768D03*
X1209768D03*
X1204768Y85368D03*
X1199768D03*
X1209768D03*
Y89368D03*
X1199768D03*
X1204768D03*
X1188268Y85068D03*
Y69068D03*
Y89068D03*
X1215795Y181242D03*
X1186500Y220500D03*
X1224800Y225200D03*
X1219917Y239646D03*
X1215600Y261800D03*
X1219962Y244739D03*
X1186600Y253200D03*
X1215547Y246355D03*
X1194700Y261700D03*
X1189700Y308527D03*
X1190200Y285023D03*
X1201835Y305319D03*
X1193800Y307857D03*
X1198100Y306858D03*
X1194600Y288237D03*
X1197000Y279400D03*
X1226045Y431102D03*
X1232500Y541000D03*
X1197868Y730300D03*
X1194268D03*
Y723100D03*
Y726700D03*
X1197868Y723100D03*
Y726700D03*
X1192068Y712300D03*
X1195668D03*
X1192068Y715900D03*
X1195668D03*
Y719500D03*
X1192068D03*
X1188000Y753000D03*
X1192000Y869000D03*
X1232700Y950400D03*
X1194000Y1037900D03*
X1229691Y1148580D03*
X1232842Y1140722D03*
X1198130Y1151410D03*
X1205303Y1227604D03*
X1214500Y1320500D03*
X1220500Y1311000D03*
X1194000Y1499000D03*
X1240500Y20000D03*
X1254000Y105000D03*
X1281500Y103500D03*
X1278421Y205974D03*
X1281603Y203340D03*
X1282106Y180492D03*
X1280800Y167200D03*
X1282287Y243489D03*
X1277606Y217441D03*
X1282106Y235492D03*
X1248193Y242618D03*
X1255600Y237300D03*
X1250016Y247017D03*
X1253300Y227700D03*
X1273200Y263700D03*
X1276200Y277400D03*
X1262075Y297100D03*
X1250500Y266600D03*
X1280000Y430000D03*
X1235796Y517450D03*
X1250011Y516707D03*
X1239362Y524168D03*
X1253511Y517606D03*
X1264878Y508068D03*
X1282106Y648248D03*
Y633248D03*
Y618248D03*
X1253800Y689600D03*
X1277606Y670197D03*
X1282106Y688248D03*
X1277606Y660748D03*
Y651299D03*
X1282106Y728248D03*
Y718248D03*
Y698248D03*
X1268400Y716100D03*
X1265891Y699583D03*
X1263250Y823436D03*
X1243200Y933700D03*
X1259808Y927260D03*
X1250475Y969248D03*
X1271296Y986867D03*
X1274413Y984613D03*
X1279599Y976407D03*
X1253338Y980784D03*
X1253975Y970147D03*
X1264269Y981248D03*
X1263618Y990606D03*
X1268378Y990608D03*
X1239900Y1024000D03*
X1256142Y1029316D03*
X1279081Y1071085D03*
X1252400Y1054100D03*
X1277606Y1122953D03*
Y1113504D03*
Y1104055D03*
X1282106Y1101004D03*
Y1086004D03*
X1251250Y1141700D03*
X1282106Y1171004D03*
Y1151004D03*
Y1141004D03*
X1246557Y1148155D03*
X1249600Y1155800D03*
X1272755Y1137293D03*
X1260300Y1169000D03*
X1240314Y1139741D03*
X1268948Y1150173D03*
X1282106Y1181004D03*
X1254800Y1269600D03*
X1257000Y1300000D03*
X1263500Y1318500D03*
X1240276Y1356700D03*
X1319000Y12000D03*
X1309000Y45500D03*
X1318500Y34500D03*
X1323829Y55929D03*
X1328295Y55800D03*
X1320055Y68000D03*
X1319100Y78800D03*
X1323521Y79179D03*
X1312999Y107280D03*
X1317661Y107896D03*
X1299569Y84272D03*
X1304563Y84309D03*
Y100771D03*
X1299569Y100639D03*
X1312263Y95463D03*
X1327921Y78900D03*
X1308228Y93399D03*
X1315961Y98112D03*
X1289000Y145400D03*
X1314794Y162944D03*
X1324134Y126967D03*
X1313127Y120839D03*
X1315118Y126967D03*
X1324207Y138756D03*
X1315102Y137903D03*
X1302074Y183779D03*
X1311200Y172661D03*
X1304293Y165909D03*
X1315838Y188804D03*
X1297507Y195492D03*
X1330807Y181473D03*
X1311750Y187911D03*
X1326637Y226568D03*
X1316637D03*
X1321637D03*
X1298700Y272800D03*
X1298500Y302900D03*
X1305000Y299400D03*
X1313000Y302900D03*
X1313915Y263541D03*
X1289000Y309500D03*
X1311000Y321000D03*
X1303500Y434000D03*
X1287000Y456000D03*
X1310000Y597000D03*
X1289106Y594626D03*
X1303800Y636417D03*
X1311200Y625417D03*
X1307500Y615417D03*
X1315400Y648017D03*
X1326500Y627917D03*
X1311750Y640667D03*
X1312000Y615417D03*
X1318000Y680417D03*
X1323000D03*
X1328000D03*
X1302500Y718917D03*
X1314000Y717417D03*
X1298500Y752417D03*
X1305000D03*
X1313000D03*
X1289106Y766870D03*
X1316000Y772200D03*
X1310500Y774700D03*
X1312767Y885535D03*
X1286000Y982200D03*
X1284695Y956586D03*
X1305000Y1041500D03*
X1289114Y1048624D03*
X1311200Y1078173D03*
X1305100Y1068173D03*
X1326500Y1080673D03*
X1317400Y1068000D03*
X1309600Y1068173D03*
X1303800Y1089173D03*
X1315300Y1100773D03*
X1311750Y1093423D03*
X1302500Y1171673D03*
X1313950Y1165990D03*
X1328000Y1133173D03*
X1318000D03*
X1323000D03*
X1300065Y1206008D03*
X1305000Y1205173D03*
X1313000D03*
X1289106Y1219626D03*
X1357500Y43500D03*
X1347500Y21000D03*
X1332500Y56500D03*
X1351200Y68600D03*
X1359350Y66350D03*
X1351201Y90099D03*
X1358355Y81488D03*
X1338215Y107586D03*
X1336034Y82542D03*
X1334383Y75892D03*
X1340961Y78811D03*
X1343521Y85472D03*
X1347607Y101337D03*
X1346081Y80671D03*
X1348641Y83326D03*
X1352351Y101724D03*
X1350779Y106496D03*
X1348641Y110550D03*
X1333281Y85133D03*
X1341922Y105649D03*
X1354500Y75400D03*
X1332934Y137712D03*
X1349931Y138361D03*
X1338400Y126015D03*
X1333988Y161471D03*
X1358971Y129978D03*
X1362685Y130109D03*
X1351665Y128325D03*
X1343112Y128997D03*
X1364017Y123277D03*
X1337662Y137188D03*
X1334500Y202548D03*
Y207548D03*
Y212548D03*
X1377463Y237100D03*
X1334500Y217548D03*
X1372274Y272874D03*
X1355991Y275272D03*
X1374338Y292900D03*
X1358573Y290900D03*
X1372000Y335000D03*
X1375700Y413400D03*
X1338000Y546500D03*
X1346363Y516578D03*
X1332148Y517321D03*
X1357316Y542311D03*
X1346057Y529857D03*
X1338100Y520300D03*
X1353500Y518900D03*
X1359882Y508014D03*
X1364882D03*
X1337500Y576500D03*
X1355700Y587600D03*
X1359700D03*
X1372272Y573560D03*
X1336000Y627000D03*
X1375463Y689917D03*
X1334000Y666417D03*
Y661917D03*
Y657417D03*
Y652917D03*
X1373553Y700994D03*
X1347600Y734078D03*
X1344062Y737800D03*
X1339500Y794000D03*
X1354500Y747304D03*
X1360920Y749829D03*
X1334300Y771200D03*
X1338729Y776131D03*
X1338700Y771500D03*
X1334329Y775831D03*
X1373519Y761900D03*
X1341219Y933282D03*
X1346080Y907004D03*
X1344000Y987500D03*
X1362000Y987000D03*
X1331070Y966090D03*
X1348796Y969488D03*
X1378100Y972100D03*
X1339404Y969600D03*
X1353762Y969886D03*
X1367382Y961355D03*
X1362382D03*
X1349829Y1014840D03*
X1365551Y1028250D03*
X1368935Y1123365D03*
X1361074Y1114565D03*
X1334500Y1104700D03*
Y1111173D03*
Y1116173D03*
Y1121173D03*
X1365461Y1136100D03*
X1375463Y1142673D03*
X1364713Y1143791D03*
X1360238Y1143867D03*
X1370716Y1148037D03*
X1351321Y1152553D03*
X1355733Y1241900D03*
X1369600Y1330100D03*
X1373700Y1330000D03*
X1365551Y1353500D03*
X1413268Y146062D03*
X1401819Y207992D03*
X1394705Y195413D03*
X1406319Y180492D03*
X1405100Y166000D03*
X1427663Y167032D03*
X1403963Y245492D03*
X1385051Y218684D03*
X1406000Y236700D03*
X1384475Y255839D03*
X1426713Y266161D03*
X1426400Y307400D03*
X1406319Y275492D03*
Y265492D03*
X1398493Y314114D03*
X1384713Y323200D03*
X1400000Y406000D03*
X1427000Y380000D03*
X1414882Y397271D03*
X1395300Y438500D03*
X1418225Y421700D03*
X1425000Y480000D03*
X1405000D03*
Y460000D03*
X1385000Y480000D03*
X1396500Y511000D03*
X1383500Y509500D03*
X1418493Y531407D03*
X1425600Y544600D03*
X1418507Y517007D03*
X1407936Y552099D03*
Y548099D03*
X1425200Y540100D03*
X1414319Y523900D03*
X1413319Y594626D03*
X1413400Y575000D03*
X1396297Y573397D03*
X1421239Y558029D03*
X1396297Y579803D03*
X1421239Y562229D03*
X1406319Y648248D03*
Y633248D03*
Y618248D03*
X1421500Y664000D03*
X1401819Y670197D03*
X1406319Y688248D03*
X1401819Y660748D03*
Y651299D03*
X1426713Y718917D03*
X1406319Y728248D03*
Y718248D03*
Y698248D03*
X1383952Y717435D03*
X1422713Y752417D03*
X1398245Y766870D03*
X1395000Y791500D03*
X1392355Y886696D03*
X1391000Y932400D03*
X1380300Y930200D03*
X1390000Y955500D03*
X1384800Y1002666D03*
X1390500Y1048000D03*
X1406319Y1071004D03*
X1413319Y1047382D03*
X1406319Y1086004D03*
Y1101004D03*
X1401819Y1104055D03*
X1385494Y1113504D03*
X1401819Y1122953D03*
X1406319Y1141004D03*
Y1151004D03*
Y1171004D03*
X1426713Y1171673D03*
X1383899Y1166690D03*
X1406319Y1181004D03*
X1413319Y1219626D03*
X1422713Y1205173D03*
X1388500Y1224900D03*
X1413000Y1241500D03*
X1387000Y1243500D03*
X1386500Y1258000D03*
X1418000Y1291500D03*
X1400000Y1320000D03*
X1420000D03*
X1381800Y1329600D03*
X1431713Y162661D03*
X1463804Y138605D03*
X1436204Y159247D03*
X1428013Y185956D03*
X1445994Y174086D03*
X1440300Y188000D03*
X1435963Y183833D03*
X1450713Y173049D03*
X1456373Y168971D03*
X1458764Y212625D03*
Y208025D03*
Y203425D03*
X1438186Y261287D03*
X1442213Y227661D03*
X1447213D03*
X1452213D03*
X1458764Y217225D03*
X1463000Y307000D03*
X1439300Y301500D03*
X1429800Y302500D03*
X1447170Y337890D03*
X1466500Y338100D03*
X1444238Y349852D03*
X1439654D03*
X1441770Y365790D03*
X1461100Y366000D03*
X1441970Y403990D03*
X1461300Y404200D03*
X1431909Y359311D03*
X1439500Y421500D03*
X1440000Y460000D03*
X1449576Y495482D03*
X1468605Y493549D03*
X1463000Y490638D03*
X1457200Y549600D03*
X1470700Y522100D03*
X1456439Y515000D03*
X1448261D03*
X1435200D03*
X1443700D03*
X1460200D03*
X1452200D03*
X1465700D03*
X1439200D03*
X1442500Y548400D03*
X1456450Y529600D03*
X1448450D03*
X1452279Y563600D03*
X1464700Y585600D03*
X1470000Y580000D03*
X1460274Y592498D03*
X1459200Y579600D03*
X1452200D03*
X1442500Y554700D03*
X1455750Y572350D03*
X1474700Y569100D03*
X1447700Y579600D03*
X1474700Y579100D03*
X1428013Y636417D03*
X1435413Y625417D03*
X1431713Y615417D03*
X1439713Y647917D03*
X1450713Y627817D03*
X1435963Y640667D03*
X1455202Y618557D03*
X1436213Y615417D03*
X1442213Y680417D03*
X1447213D03*
X1452213D03*
X1458713Y658417D03*
Y663417D03*
Y668417D03*
Y652217D03*
X1449000Y698000D03*
X1438087Y713756D03*
X1429213Y752417D03*
X1437213D03*
X1474083Y764750D03*
X1471608Y768500D03*
X1432000Y831000D03*
X1459500Y814000D03*
X1450500Y802500D03*
X1459500Y796500D03*
X1473000Y798000D03*
X1433500Y864500D03*
X1435300Y882700D03*
X1440500Y893500D03*
X1448000Y910000D03*
X1457500Y987500D03*
X1440000Y986500D03*
X1473008Y969646D03*
X1458967Y969535D03*
X1463616Y969265D03*
X1451800Y1004700D03*
X1433500Y1044000D03*
X1456000D03*
X1435413Y1078173D03*
X1431713Y1068173D03*
X1450713Y1080673D03*
X1446213Y1062300D03*
X1436213Y1068173D03*
X1428013Y1089173D03*
X1439713Y1100773D03*
X1442213Y1132173D03*
X1447213D03*
X1452213D03*
X1439750Y1096673D03*
X1461713Y1123173D03*
Y1118173D03*
Y1113173D03*
X1461700Y1107200D03*
X1438213Y1170173D03*
X1470953Y1152427D03*
X1475953D03*
X1429213Y1205173D03*
X1437213D03*
X1467000Y1221800D03*
X1458000Y1265500D03*
X1473600Y1242777D03*
X1460000Y1300000D03*
Y1320000D03*
X1440000D03*
X1511177Y125412D03*
X1498900Y235800D03*
X1499775Y248061D03*
X1508925Y323200D03*
X1505000Y378500D03*
X1520000Y421500D03*
X1481938Y489926D03*
X1479212Y535612D03*
X1494100Y526400D03*
X1507900Y539100D03*
X1481938Y512568D03*
X1485932Y522335D03*
X1500600Y523300D03*
X1502400Y544100D03*
X1497849Y545264D03*
X1486594Y508098D03*
X1491594D03*
X1513200Y519700D03*
X1509800Y516100D03*
X1509911Y553511D03*
X1478700Y579100D03*
X1502400Y554100D03*
X1494400Y560400D03*
Y556100D03*
X1494462Y692179D03*
X1500539Y739639D03*
X1498000Y743000D03*
X1505900Y717600D03*
X1495480Y704558D03*
X1489000Y723000D03*
X1515000Y789000D03*
X1520000Y776000D03*
X1499500Y774000D03*
X1476558Y759088D03*
X1479033Y762259D03*
X1486600Y786559D03*
X1499500Y831000D03*
X1510500Y878000D03*
X1510000Y860500D03*
X1505900Y930400D03*
X1521200Y928000D03*
X1512500Y949000D03*
X1503394Y968179D03*
X1477974Y970044D03*
X1491594Y961355D03*
X1486594D03*
X1508500Y1028500D03*
X1484000Y992315D03*
X1481500Y995758D03*
X1478194Y1017166D03*
X1481529Y1030500D03*
X1508500Y1050500D03*
X1488500Y1096000D03*
X1489096Y1131456D03*
X1489108Y1121674D03*
X1485608Y1113628D03*
X1499675Y1142673D03*
X1489333Y1147664D03*
X1504200Y1171300D03*
X1485833Y1140369D03*
X1495900Y1149000D03*
X1480000Y1320000D03*
X1491662Y1351300D03*
X1494662Y1336000D03*
X1497200Y1342500D03*
X1501600Y1342300D03*
X1525336Y149369D03*
X1555925Y162661D03*
X1545383Y164116D03*
X1560000Y140000D03*
X1560425Y162661D03*
X1552225Y183661D03*
X1559625Y172661D03*
X1563925Y195261D03*
X1526031Y207992D03*
Y198543D03*
X1530531Y195492D03*
Y180492D03*
X1560175Y187911D03*
X1530531Y245492D03*
X1526031Y217441D03*
X1530142Y238021D03*
X1566425Y227661D03*
X1571425D03*
X1550925Y266161D03*
X1546925Y299661D03*
X1553425D03*
X1561425D03*
X1562425Y264661D03*
X1530531Y275492D03*
Y265492D03*
X1537531Y314114D03*
X1545000Y455000D03*
X1560000D03*
X1525000D03*
X1568500Y438500D03*
X1545000Y475000D03*
X1560000D03*
Y500000D03*
Y525000D03*
X1568500Y544100D03*
X1568000Y548500D03*
X1552000Y584500D03*
X1566000Y595000D03*
X1537531Y594626D03*
X1552225Y636417D03*
X1559625Y625417D03*
X1555925Y615417D03*
X1530531Y648248D03*
Y633248D03*
Y618248D03*
X1555175Y642667D03*
X1560425Y615417D03*
X1558925Y650017D03*
X1526031Y670197D03*
X1530531Y688248D03*
X1526031Y660748D03*
Y651299D03*
X1566425Y677417D03*
X1571425D03*
X1565593Y654856D03*
X1565618Y660773D03*
Y665773D03*
Y670773D03*
X1550925Y718917D03*
X1562425Y717417D03*
X1530531Y728248D03*
Y718248D03*
Y698248D03*
X1526000Y728000D03*
X1555000Y770000D03*
X1546925Y752417D03*
X1553425D03*
X1561425D03*
X1537531Y766870D03*
X1525000Y878000D03*
X1570500Y888400D03*
X1564500Y931000D03*
X1548500Y933000D03*
X1564000Y949000D03*
X1552500Y1028000D03*
X1557500Y1043500D03*
X1537531Y1047382D03*
X1559625Y1078173D03*
X1555925Y1068173D03*
X1530531Y1071004D03*
X1570425Y1062000D03*
X1560425Y1068173D03*
X1552225Y1089173D03*
X1526031Y1122953D03*
Y1113504D03*
Y1104055D03*
X1530531Y1101004D03*
Y1086004D03*
X1547800Y1098819D03*
X1552800D03*
X1557800D03*
X1562800D03*
X1550925Y1171673D03*
X1552575Y1139700D03*
X1562425Y1170173D03*
X1530531Y1171004D03*
Y1151004D03*
X1528723Y1138918D03*
X1556231Y1134920D03*
X1546898Y1204827D03*
X1553425Y1208897D03*
X1561425Y1205173D03*
X1537879Y1219626D03*
X1530531Y1181004D03*
X1558650Y1217426D03*
X1600000Y20000D03*
X1620000D03*
X1580000D03*
X1600000Y60000D03*
X1620000Y40000D03*
X1600000D03*
X1580000D03*
Y60000D03*
X1620000Y100000D03*
X1600000Y80000D03*
X1620000D03*
X1580000D03*
X1620000Y140000D03*
Y120000D03*
X1585757Y134147D03*
X1607000Y199000D03*
X1574925Y175061D03*
X1579371Y166019D03*
X1582925Y210661D03*
Y205661D03*
Y200661D03*
X1595500Y258500D03*
X1621100Y240561D03*
X1608000Y256000D03*
X1576425Y227661D03*
X1621100Y244661D03*
X1582925Y215661D03*
X1600000Y340000D03*
X1620000D03*
Y320000D03*
X1600000D03*
X1579500Y331000D03*
X1597245Y516662D03*
X1583030Y517405D03*
X1586596Y518723D03*
X1600745Y517561D03*
X1615807Y508600D03*
X1610807D03*
X1573000Y565500D03*
X1574925Y627817D03*
X1578926Y618657D03*
X1576425Y677417D03*
X1620469Y697517D03*
X1580000Y780000D03*
X1576500Y928500D03*
X1584800Y895800D03*
X1587400Y912200D03*
X1608200Y914400D03*
X1618200Y916800D03*
X1597221Y969572D03*
X1583180Y969461D03*
X1574576Y976700D03*
X1615494Y973179D03*
X1587829Y969191D03*
X1602187Y969970D03*
X1615807Y961355D03*
X1610807D03*
X1596000Y990000D03*
X1580381Y1007066D03*
X1602400Y1019366D03*
X1620059Y1032932D03*
X1611500Y1078000D03*
X1593000Y1043500D03*
X1574925Y1080673D03*
X1603425Y1105040D03*
Y1100040D03*
X1598425Y1102440D03*
Y1107440D03*
X1620059Y1128071D03*
X1615909Y1150262D03*
X1593500Y1185500D03*
X1581500Y1240000D03*
X1613400Y1236500D03*
X1600000Y1320000D03*
X1640000Y20000D03*
X1660000D03*
X1640000Y60000D03*
X1660000D03*
Y40000D03*
X1640000D03*
Y100000D03*
X1660000D03*
X1640000Y80000D03*
X1660000D03*
Y120000D03*
X1640000D03*
X1661744Y141870D03*
X1650244Y207992D03*
Y198543D03*
X1654744Y195492D03*
Y180492D03*
Y165492D03*
Y245492D03*
X1650244Y217441D03*
X1654744Y235492D03*
X1652387Y277343D03*
X1653789Y267766D03*
X1622738Y264938D03*
X1639000Y320000D03*
X1640000Y340000D03*
X1660000D03*
X1661744Y314114D03*
X1660000Y400000D03*
X1640000Y360000D03*
X1660000Y440000D03*
Y480000D03*
X1640000D03*
Y460000D03*
X1660000D03*
X1640000Y500000D03*
X1660000D03*
Y520000D03*
X1640000D03*
X1660000Y540000D03*
X1640000D03*
Y560000D03*
X1660000D03*
X1661744Y594626D03*
X1654744Y648248D03*
Y633248D03*
Y618248D03*
X1623888Y689917D03*
X1652962Y670204D03*
X1654744Y688248D03*
X1650244Y660748D03*
Y651299D03*
X1637000Y729000D03*
X1638000Y740000D03*
X1654744Y728248D03*
Y718248D03*
Y698248D03*
X1621138Y719238D03*
X1630000Y780000D03*
Y760000D03*
X1661744Y766870D03*
X1625000Y800000D03*
X1643344Y887455D03*
X1646013Y884255D03*
X1639644Y889755D03*
X1651500Y913500D03*
X1633600Y936300D03*
X1621787Y917108D03*
X1636400Y925800D03*
X1650000Y950000D03*
Y980000D03*
X1629094Y975179D03*
X1653500Y1016500D03*
X1650000Y1000000D03*
X1632000Y1049500D03*
X1654744Y1071004D03*
X1661744Y1047382D03*
X1650244Y1122953D03*
Y1113504D03*
Y1104055D03*
X1654744Y1101004D03*
Y1086004D03*
X1627563Y1132075D03*
X1627802Y1118949D03*
X1627769Y1110037D03*
X1624198Y1111309D03*
X1635688Y1141158D03*
X1650841Y1168660D03*
X1654744Y1151004D03*
Y1141004D03*
X1627197Y1143044D03*
X1633138Y1165673D03*
X1635688Y1153773D03*
X1661744Y1219626D03*
X1668378Y1181004D03*
X1640000Y1260000D03*
X1660000D03*
X1640000Y1320000D03*
Y1300000D03*
X1660000Y1320000D03*
Y1300000D03*
Y1280000D03*
X1640000D03*
X1624500Y1349100D03*
X1700000Y20000D03*
X1680000D03*
X1700000Y60000D03*
Y40000D03*
X1680000Y60000D03*
Y40000D03*
Y100000D03*
Y80000D03*
X1700000Y100000D03*
Y80000D03*
Y140000D03*
Y120000D03*
X1680000D03*
X1679500Y144000D03*
X1680138Y162661D03*
X1684638D03*
X1676438Y183661D03*
X1683838Y172661D03*
X1688138Y195261D03*
X1684388Y187911D03*
X1699138Y175061D03*
X1703584Y166019D03*
X1707138Y210661D03*
Y205661D03*
Y200661D03*
X1690638Y227661D03*
X1695638D03*
X1700638D03*
X1707138Y215661D03*
X1675475Y267424D03*
X1671138Y299661D03*
X1677638D03*
X1685638D03*
X1686638Y264661D03*
X1678500Y320000D03*
X1700000Y400000D03*
X1680000Y380000D03*
X1700000Y360000D03*
X1680000Y440000D03*
Y420000D03*
X1700000Y440000D03*
Y420000D03*
Y460000D03*
X1680000Y480000D03*
Y460000D03*
Y500000D03*
Y520000D03*
X1700000Y540000D03*
X1680000D03*
X1707495Y517152D03*
X1711061Y518470D03*
X1700000Y560000D03*
X1680000D03*
X1676438Y636417D03*
X1683838Y625417D03*
X1680138Y615417D03*
X1688138Y648017D03*
X1684388Y638324D03*
X1699138Y627917D03*
X1705000Y618667D03*
X1684638Y615417D03*
X1699638Y675417D03*
X1689638D03*
X1694638D03*
X1707100Y652500D03*
X1707138Y658417D03*
Y663417D03*
Y668417D03*
X1675138Y718917D03*
X1686638Y717417D03*
X1710000Y770000D03*
Y785000D03*
X1685000Y770000D03*
X1671138Y752417D03*
X1677638D03*
X1685638D03*
X1709000Y915000D03*
X1687000Y905500D03*
X1692100Y923600D03*
X1704010Y898000D03*
X1716500Y943500D03*
X1674814Y961977D03*
X1677056Y954636D03*
X1680012Y952402D03*
X1706000Y1022000D03*
X1717681Y1006054D03*
X1712181Y1001554D03*
X1685047Y1014966D03*
X1680087Y1023983D03*
X1671422Y1009266D03*
X1690279Y1011526D03*
X1691771Y1035163D03*
X1683838Y1078173D03*
X1680138Y1068173D03*
X1699138Y1080573D03*
X1685100Y1054000D03*
X1679300Y1043169D03*
X1694638Y1063600D03*
X1684638Y1068173D03*
X1688138Y1100773D03*
X1676438Y1089173D03*
X1700638Y1131673D03*
X1695638D03*
X1690638D03*
X1684388Y1091723D03*
X1707138Y1111173D03*
Y1116173D03*
Y1121173D03*
X1707200Y1105200D03*
X1686638Y1170173D03*
X1675138Y1171673D03*
X1685638Y1205173D03*
X1677638D03*
X1671138D03*
X1702838Y1215300D03*
X1680000Y1240000D03*
X1700000Y1260000D03*
X1680000D03*
X1710617Y1231429D03*
X1715049Y1234000D03*
X1700000Y1320000D03*
Y1300000D03*
Y1280000D03*
X1680000Y1320000D03*
Y1300000D03*
Y1280000D03*
X1760000Y20000D03*
X1740000D03*
X1720000D03*
X1760000Y60000D03*
Y40000D03*
X1740000D03*
Y60000D03*
X1720000Y40000D03*
Y60000D03*
X1740000Y100000D03*
X1760000D03*
X1740000Y80000D03*
X1760000D03*
X1720000Y100000D03*
Y80000D03*
X1740000Y140000D03*
X1760000Y120000D03*
X1740000D03*
X1720000Y140000D03*
Y120000D03*
X1728500Y249500D03*
X1746600Y240561D03*
X1760486Y217441D03*
X1746400Y244561D03*
X1763500Y288000D03*
X1720000Y300000D03*
Y280000D03*
X1747550Y265000D03*
X1720000Y340000D03*
X1760000D03*
X1740000Y320000D03*
X1760000Y440000D03*
Y420000D03*
Y500000D03*
Y480000D03*
Y460000D03*
X1740000Y540000D03*
X1760000D03*
Y520000D03*
X1721710Y516409D03*
X1725100Y519300D03*
X1740019Y508600D03*
X1735019D03*
X1745000Y670000D03*
Y690000D03*
Y660000D03*
X1730000Y690000D03*
Y670000D03*
Y730000D03*
Y710000D03*
X1735000Y785000D03*
X1730000Y775000D03*
Y750000D03*
X1725000Y800000D03*
X1718000Y876000D03*
X1752000Y929200D03*
X1759884Y969161D03*
X1757600Y987200D03*
X1761600D03*
Y983200D03*
X1757600D03*
X1742001Y965464D03*
X1755010Y966285D03*
X1740019Y961355D03*
X1735019D03*
X1738863Y985225D03*
X1761600Y991200D03*
Y999200D03*
Y995200D03*
X1757600Y991200D03*
X1753600Y995200D03*
Y999200D03*
X1757600D03*
Y995200D03*
X1726681Y1001554D03*
X1719681D03*
X1722181Y1009054D03*
X1763714Y1015491D03*
X1755900Y1014600D03*
X1740499Y1008223D03*
X1749863Y1003925D03*
X1756100Y1004362D03*
X1746030Y1004209D03*
X1740363Y989225D03*
X1755000Y1045000D03*
X1725000D03*
X1745000Y1100000D03*
X1759055Y1113504D03*
X1736725Y1123446D03*
X1733245Y1115503D03*
X1748100Y1142673D03*
X1736871Y1158178D03*
X1736941Y1141871D03*
X1751400Y1173900D03*
X1732768Y1141697D03*
X1748100Y1153673D03*
X1718117Y1152553D03*
X1723117D03*
X1728000Y1204500D03*
X1755900Y1212704D03*
X1720000Y1320000D03*
X1760000D03*
X1753000Y1302000D03*
X1740000Y1346900D03*
X1780000Y60000D03*
Y40000D03*
X1800000Y100000D03*
Y80000D03*
X1780000Y100000D03*
Y80000D03*
X1800000Y120000D03*
X1780000D03*
X1785956Y141870D03*
X1804350Y162661D03*
X1808850D03*
X1801988Y183904D03*
X1808050Y172661D03*
X1812350Y195261D03*
X1774456Y207992D03*
Y198543D03*
X1778956Y195492D03*
Y180492D03*
X1775140Y165728D03*
X1808600Y187911D03*
X1778956Y245492D03*
Y235492D03*
X1799350Y266161D03*
X1795350Y299661D03*
X1801850D03*
X1809850D03*
X1810850Y264661D03*
X1778956Y275492D03*
Y265492D03*
X1785956Y314114D03*
X1800000Y440000D03*
X1780000D03*
X1800000Y500000D03*
X1780000D03*
X1800000Y480000D03*
Y460000D03*
X1780000Y480000D03*
Y460000D03*
X1800000Y540000D03*
X1780000D03*
X1800000Y520000D03*
X1780000D03*
X1800000Y560000D03*
X1785956Y594626D03*
X1800650Y636417D03*
X1808050Y625417D03*
X1804350Y615417D03*
X1812350Y648017D03*
X1778956Y648248D03*
Y633248D03*
Y618248D03*
X1808600Y640667D03*
X1808850Y615417D03*
X1774456Y670197D03*
X1778956Y688248D03*
X1774456Y660748D03*
Y651299D03*
X1799326Y717506D03*
X1811474Y717423D03*
X1778956Y728248D03*
Y718248D03*
Y698248D03*
X1766721Y716500D03*
Y720500D03*
X1795468Y752594D03*
X1801968D03*
X1809968D03*
X1785956Y766870D03*
X1773500Y879500D03*
X1813851Y927406D03*
X1771000Y944500D03*
X1799000Y945500D03*
X1788361Y964676D03*
X1799051Y963346D03*
X1768692Y966073D03*
X1797463Y968652D03*
X1806077Y961860D03*
X1782666Y961344D03*
X1777666D03*
X1783778Y970371D03*
X1774863Y1024725D03*
X1788726Y1034726D03*
X1778863Y1005725D03*
X1772863Y1005304D03*
X1772263Y995925D03*
X1785956Y1047382D03*
X1808050Y1078173D03*
X1800750Y1067973D03*
X1778956Y1071004D03*
X1812050Y1071223D03*
X1805250Y1067973D03*
X1800650Y1089173D03*
X1811968Y1100773D03*
X1774456Y1122953D03*
Y1104055D03*
X1778956Y1101004D03*
Y1086004D03*
X1799350Y1171673D03*
X1810850Y1170173D03*
X1778956Y1171004D03*
Y1151004D03*
Y1141004D03*
X1795350Y1205173D03*
X1801850D03*
X1809850D03*
X1785956Y1219626D03*
X1778956Y1181004D03*
X1772111Y1232695D03*
X1860000Y60000D03*
Y80000D03*
Y100000D03*
X1840000D03*
X1820000D03*
X1860000Y140000D03*
Y120000D03*
X1840000D03*
X1820000Y140000D03*
Y120000D03*
X1859017Y161725D03*
X1841021Y152968D03*
X1845517Y158475D03*
X1859117Y167375D03*
X1851717Y179075D03*
X1856219Y212661D03*
Y201661D03*
X1823350Y175161D03*
X1827796Y166019D03*
X1831350Y210661D03*
Y205661D03*
Y200661D03*
X1841169Y254661D03*
X1850669Y219661D03*
X1846169D03*
X1841669D03*
X1824850Y227661D03*
X1819850D03*
X1814850D03*
X1831350Y215661D03*
X1840000Y340000D03*
Y320000D03*
X1860000D03*
X1820000D03*
Y440000D03*
Y480000D03*
Y460000D03*
X1840000Y540000D03*
X1820000D03*
X1845545Y516536D03*
X1831330Y517279D03*
X1834896Y518597D03*
X1849045Y517435D03*
X1859232Y508600D03*
X1840000Y580000D03*
X1820000D03*
X1840000Y560000D03*
X1820000D03*
X1858917Y614481D03*
X1859117Y620131D03*
X1851717Y635331D03*
X1823350Y627917D03*
X1827667Y618703D03*
X1840855Y606200D03*
X1845417Y611231D03*
X1862200Y686700D03*
X1856219Y665417D03*
X1841669Y672417D03*
X1846169D03*
X1850669D03*
X1814850Y680417D03*
X1819850D03*
X1824850D03*
X1856219Y654417D03*
X1831350Y658417D03*
Y663417D03*
Y668417D03*
X1831300Y652600D03*
X1850000Y745000D03*
X1837576Y707417D03*
X1820000Y780000D03*
X1848491Y819787D03*
Y823787D03*
Y815787D03*
Y807787D03*
X1850151Y835119D03*
X1850177Y838746D03*
X1838239Y831626D03*
X1845579Y831731D03*
X1838311Y827911D03*
X1845651Y828016D03*
X1848491Y811787D03*
X1855676Y800787D03*
X1824170Y886349D03*
X1860276Y916059D03*
Y912059D03*
X1843731Y936066D03*
X1819541Y921500D03*
X1823937Y890883D03*
X1821152Y907899D03*
X1843811Y940067D03*
X1840419Y945557D03*
Y951057D03*
X1825945Y945449D03*
Y950949D03*
X1830665Y941751D03*
X1836165D03*
X1825971Y1015512D03*
Y1010012D03*
X1840445Y1015620D03*
Y1010120D03*
X1835895Y1020064D03*
X1830395D03*
X1857363Y1002625D03*
X1845363D03*
X1849363D03*
X1861363D03*
X1853363D03*
X1823350Y1080673D03*
X1856437Y1106400D03*
X1858046Y1092779D03*
X1836953Y1103391D03*
X1850363Y1115037D03*
X1847506Y1118794D03*
X1851565Y1118784D03*
X1850280Y1111373D03*
X1816046Y1098532D03*
X1836200Y1130000D03*
X1828850Y1106173D03*
Y1111173D03*
Y1116173D03*
Y1121173D03*
X1850532Y1153286D03*
X1836231Y1140669D03*
X1824850Y1133173D03*
X1814850D03*
X1819850D03*
X1840585Y1151653D03*
X1836400Y1151900D03*
X1860000Y1320000D03*
X1842000Y1344700D03*
X1880000Y60000D03*
X1900000D03*
X1880000Y80000D03*
X1900000D03*
Y100000D03*
X1880000D03*
X1900000Y120000D03*
X1880000Y140000D03*
Y120000D03*
X1910169Y141870D03*
X1898669Y207992D03*
Y198543D03*
X1903169Y195492D03*
Y180492D03*
Y165492D03*
X1885204Y184345D03*
X1869500Y179134D03*
X1876938Y181062D03*
X1865669Y201661D03*
X1870669D03*
X1875669D03*
X1880669D03*
X1873500Y219000D03*
X1865169Y247161D03*
Y234661D03*
X1903169Y245492D03*
X1898669Y217441D03*
X1903169Y235492D03*
X1881088Y296184D03*
X1903169Y275492D03*
Y265492D03*
X1880969Y276861D03*
X1880000Y340000D03*
Y320000D03*
X1910169Y314114D03*
X1890000Y400000D03*
Y380000D03*
Y360000D03*
Y440000D03*
Y420000D03*
X1864232Y508600D03*
X1910169Y594626D03*
X1903169Y648248D03*
Y633248D03*
Y618248D03*
X1885300Y636800D03*
X1869500Y633500D03*
X1878900Y637000D03*
X1898669Y670197D03*
X1903169Y688248D03*
X1898669Y660748D03*
Y651299D03*
X1879669Y652917D03*
X1874669D03*
X1869669D03*
X1864669D03*
X1903169Y728248D03*
Y718248D03*
Y698248D03*
X1880969Y729617D03*
X1865169Y699917D03*
X1880000Y780000D03*
X1910169Y766870D03*
X1887169Y752917D03*
X1908107Y831894D03*
X1902607D03*
X1907999Y846368D03*
X1902499D03*
X1884800Y890750D03*
X1902441Y888500D03*
X1892443Y894350D03*
X1872276Y916059D03*
X1876276D03*
Y920059D03*
X1872276D03*
X1868276Y916059D03*
X1864276Y912059D03*
X1868276D03*
X1864276Y916059D03*
X1876276Y912059D03*
X1872276D03*
X1884200Y895000D03*
X1896943Y894350D03*
X1891676Y917759D03*
X1884500Y912500D03*
X1904000Y933500D03*
Y929000D03*
Y925000D03*
X1906500Y893400D03*
X1909358Y897500D03*
X1904000Y938000D03*
X1873001Y901396D03*
X1904000Y921000D03*
X1872190Y936766D03*
X1875801Y946796D03*
X1875769Y951122D03*
X1880122Y954062D03*
X1880383Y950341D03*
X1865363Y1002625D03*
X1867963Y996425D03*
X1868100Y1055410D03*
X1871000Y1073300D03*
X1903169Y1071004D03*
X1910169Y1047382D03*
X1884835Y1067400D03*
X1887402Y1050193D03*
X1872162Y1055426D03*
X1864617Y1040934D03*
X1888085Y1059938D03*
X1876662Y1055426D03*
X1863700Y1085000D03*
X1898669Y1122953D03*
Y1113504D03*
Y1104055D03*
X1903169Y1101004D03*
Y1086004D03*
X1864833Y1091419D03*
X1870779Y1091763D03*
X1875779D03*
X1880779D03*
X1863131Y1133108D03*
X1903169Y1171004D03*
X1903100Y1149700D03*
X1903169Y1141004D03*
X1864352Y1153308D03*
X1871174Y1138730D03*
X1887169Y1205673D03*
X1910169Y1219626D03*
X1903169Y1181004D03*
X1880969Y1182373D03*
X1900000Y1260000D03*
Y1280000D03*
Y1320000D03*
Y1300000D03*
X1873500Y1329000D03*
X1920000Y60000D03*
Y80000D03*
Y100000D03*
Y120000D03*
X1912551Y836444D03*
Y841944D03*
X1911676Y893469D03*
X1920000Y1260000D03*
Y1280000D03*
Y1320000D03*
Y1300000D03*
G54D115*
G01X839414Y1520763D02*
X841508Y1522857D01*
Y1528131D01*
G01X848551Y1542440D02*
X843340D01*
X842450Y1541550D01*
Y1538800D01*
G01X885300Y1371050D02*
X886512D01*
X890499Y1367063D01*
X895676D01*
G01X887412Y1365050D02*
X889151D01*
X889698Y1364503D01*
X895676D01*
G01X848551Y1542440D02*
Y1540451D01*
X847854Y1539754D01*
Y1538590D01*
G01X848008Y1533251D02*
X847854Y1533405D01*
Y1538590D01*
G01X895869Y932822D02*
X896420Y933373D01*
Y944100D01*
G01X898920Y1013600D02*
Y1020000D01*
G01X981580Y921900D02*
Y932678D01*
G01X976580Y992400D02*
Y986180D01*
G01X1038460Y921400D02*
X1044680D01*
G01X1025774Y992740D02*
Y1001538D01*
G01X1054080Y1083900D02*
Y1077680D01*
G01X1101580Y1084900D02*
Y1091120D01*
G01X1144580Y1084900D02*
Y1078680D01*
G01X1871000Y1073300D02*
Y1074770D01*
X1871030Y1074800D01*
Y1076940D01*
G01X1863630Y1082060D02*
Y1084930D01*
X1863700Y1085000D01*
G54D22*
X72837Y177961D03*
Y630717D03*
Y1083473D03*
X140372Y736524D03*
X133063Y1006025D03*
X197049Y177961D03*
X199763Y594025D03*
X197449Y1083473D03*
X264739Y736268D03*
X337721Y121955D03*
X321362Y177961D03*
X321262Y630717D03*
Y1083473D03*
X365162Y92470D03*
X388796Y736196D03*
X389067Y1166330D03*
X445474Y177961D03*
Y630717D03*
X457173Y1072026D03*
X445573Y1104126D03*
X525579Y541581D03*
X512892Y736449D03*
X569687Y177961D03*
X575779Y516631D03*
X557279D03*
X594267Y530670D03*
X569687Y630717D03*
Y1083473D03*
X611910Y551674D03*
X637326Y736366D03*
X666142Y106519D03*
X693900Y177961D03*
Y1083473D03*
X752500Y1148300D03*
X877673Y861703D03*
X882400Y861668D03*
X876748Y1355107D03*
X876740Y1347014D03*
X882445Y1407597D03*
X877445D03*
X886792Y1407714D03*
X868500Y1435800D03*
X886500D03*
X877500D03*
X888600Y1482550D03*
X923600Y909000D03*
X928100D03*
X919100D03*
X932361Y959507D03*
X920607Y959382D03*
X936861Y959507D03*
X926100Y978500D03*
X930600D03*
X917100D03*
X929105Y1028560D03*
X920879Y1028703D03*
X932559Y1363584D03*
X936994Y1373148D03*
X932564Y1349912D03*
X926500Y1503000D03*
X942000D03*
X896365Y1516592D03*
X896335Y1525008D03*
X961500Y908300D03*
X966000D03*
X963900Y953700D03*
X950500Y979300D03*
X959500D03*
X946000D03*
X960400Y1024100D03*
X947125Y1372957D03*
X951872Y1361902D03*
X946300Y1503000D03*
X963488Y1517039D03*
X972413Y1545966D03*
X1039100Y905000D03*
X1020480Y904800D03*
X1015728D03*
X1023100Y956050D03*
X997694Y978140D03*
X1011194D03*
X993194D03*
X1017194Y1027240D03*
X1032500Y1070300D03*
X1037000D03*
X1023500D03*
X1035900Y1118100D03*
X1013400Y1140800D03*
X1004300D03*
X999700D03*
X1074400Y-77068D03*
X1043112Y-42008D03*
X1066225Y-47400D03*
X1046803Y872727D03*
X1042101Y877241D03*
X1043900Y905000D03*
X1053200D03*
X1073500Y1070300D03*
X1069000D03*
X1082500D03*
X1110500Y1070400D03*
X1119700D03*
X1124500D03*
X1128800Y1118500D03*
X1092200Y1119200D03*
X1176300Y292700D03*
X1180953Y292785D03*
X1176100Y274200D03*
X1176500Y1116800D03*
X1215547Y253315D03*
X1185588Y292750D03*
X1190200Y292700D03*
X1199000Y292300D03*
X1323521Y82755D03*
X1318821D03*
X1304563Y87558D03*
X1307500Y165961D03*
Y618717D03*
X1305100Y1071473D03*
X1354437Y81538D03*
X1337634Y130388D03*
X1421969Y517057D03*
X1413400Y567900D03*
X1431713Y165961D03*
X1470700Y525400D03*
X1435200Y518400D03*
X1448261Y518334D03*
X1456439Y518366D03*
X1447700Y572400D03*
X1474700D03*
X1431713Y618717D03*
Y1071473D03*
X1478700Y572400D03*
X1555925Y165961D03*
Y618717D03*
Y1071473D03*
X1585757Y126304D03*
X1602200Y1111200D03*
X1680138Y165961D03*
Y618717D03*
Y1071473D03*
X1804350Y165961D03*
Y618717D03*
X1774863Y1018025D03*
X1800750Y1071273D03*
X1855517Y161775D03*
X1843917Y193975D03*
X1855417Y614531D03*
X1843917Y646731D03*
X1840433Y1099941D03*
X1836431Y1144459D03*
X1868100Y1058800D03*
G54D40*
X103642Y36220D03*
X173228Y1062992D03*
X421653Y1141732D03*
X654822Y36220D03*
X670079Y1062992D03*
X1274311Y36220D03*
X1343701Y1062992D03*
X1592126Y1141732D03*
X1825492Y36220D03*
X1840551Y1062992D03*
G54D31*
X68937Y254661D03*
X73437Y240161D03*
Y692917D03*
X68937Y707417D03*
Y1160173D03*
X73437Y1145673D03*
X79937Y254661D03*
X84437Y240161D03*
Y692917D03*
X79937Y707417D03*
Y1160173D03*
X84437Y1145673D03*
X204149Y254661D03*
X193149D03*
X197649Y240161D03*
X208649D03*
X197649Y692917D03*
X208649D03*
X193149Y707417D03*
X204149D03*
X193149Y1160173D03*
X204149D03*
X197649Y1145673D03*
X208649D03*
X328362Y254661D03*
X317362D03*
X321862Y240161D03*
X332862D03*
X321862Y692917D03*
X332862D03*
X317362Y707417D03*
X328362D03*
X317362Y1160173D03*
X328362D03*
X321862Y1145673D03*
X332862D03*
X452574Y254661D03*
X441574D03*
X446074Y240161D03*
X457074D03*
X446074Y692917D03*
X457074D03*
X441574Y707417D03*
X452574D03*
X456200Y1160200D03*
X467200D03*
X534874Y1145973D03*
X523874D03*
X576787Y254661D03*
X565787D03*
X570287Y240161D03*
X581287D03*
X570287Y692917D03*
X581287D03*
X565787Y707417D03*
X576787D03*
X565787Y1160173D03*
X576787D03*
X570287Y1145673D03*
X581287D03*
X701000Y254661D03*
X690000D03*
X694500Y240161D03*
Y692917D03*
X690000Y707417D03*
X701000D03*
X690000Y1160173D03*
X701000D03*
X694500Y1145673D03*
X705500Y240161D03*
Y692917D03*
Y1145673D03*
X1310500Y240661D03*
X1299500D03*
X1318775Y273366D03*
X1307775D03*
X1310500Y693417D03*
X1299500D03*
X1318834Y726182D03*
X1307834D03*
X1310500Y1146173D03*
X1299500D03*
X1318775Y1178761D03*
X1307775D03*
X1423713Y240661D03*
Y693417D03*
Y1146173D03*
X1434713Y240661D03*
X1443047Y273425D03*
X1432047D03*
X1434713Y693417D03*
X1443165Y726005D03*
X1432165D03*
X1442871Y1178820D03*
X1431871D03*
X1434713Y1146173D03*
X1558925Y240661D03*
X1547925D03*
X1567201Y273307D03*
X1556201D03*
X1558925Y693417D03*
X1547925D03*
X1567201Y726182D03*
X1556201D03*
X1558925Y1146173D03*
X1547925D03*
X1567259Y1179291D03*
X1556259D03*
X1683138Y240661D03*
X1672138D03*
X1691296Y273366D03*
X1680296D03*
X1683138Y693417D03*
X1672138D03*
X1691413Y726063D03*
X1680413D03*
X1683138Y1146173D03*
X1672138D03*
X1691590Y1178879D03*
X1680590D03*
X1807350Y240661D03*
X1796350D03*
X1804566Y273190D03*
X1807350Y693417D03*
X1796350D03*
X1806923Y725768D03*
X1807350Y1146173D03*
X1796350D03*
X1804743Y1178878D03*
X1860669Y254661D03*
X1815566Y273190D03*
X1817923Y725768D03*
X1857200Y707200D03*
X1815743Y1178878D03*
X1871669Y254661D03*
X1865169Y240161D03*
X1876169D03*
X1865169Y692917D03*
X1876169D03*
X1868200Y707200D03*
X1865548Y1126458D03*
X1876548D03*
X1875284Y1160157D03*
X1886284D03*
G54D106*
X1265178Y171892D03*
X1267378D03*
X1265178Y174092D03*
X1267378D03*
Y624648D03*
X1265178D03*
X1267378Y626848D03*
X1265178D03*
X1267378Y1077404D03*
X1265178D03*
X1267378Y1079604D03*
X1265178D03*
X1391591Y171892D03*
X1389391D03*
X1391591Y174092D03*
X1389391D03*
X1391591Y624648D03*
X1389391D03*
X1391591Y626848D03*
X1389391D03*
X1391591Y1077404D03*
X1389391D03*
X1391591Y1079604D03*
X1389391D03*
X1515803Y171892D03*
X1513603D03*
X1515803Y174092D03*
X1513603D03*
X1515803Y624648D03*
X1513603D03*
X1515803Y626848D03*
X1513603D03*
X1515803Y1077404D03*
X1513603D03*
X1515803Y1079604D03*
X1513603D03*
X1640016Y171892D03*
X1637816D03*
X1640016Y174092D03*
X1637816D03*
X1640016Y624648D03*
X1637816D03*
X1640016Y626848D03*
X1637816D03*
X1640016Y1077404D03*
X1637816D03*
X1640016Y1079604D03*
X1637816D03*
X1764228Y171892D03*
X1762028D03*
X1764228Y174092D03*
X1762028D03*
X1739228Y624648D03*
X1737028D03*
X1739228Y626848D03*
X1737028D03*
X1764228Y1077404D03*
X1762028D03*
X1764228Y1079604D03*
X1762028D03*
X1888441Y171892D03*
X1886241D03*
X1888441Y174092D03*
X1886241D03*
X1888441Y624648D03*
X1886241D03*
X1888441Y626848D03*
X1886241D03*
X1888441Y1077404D03*
X1886241D03*
X1888441Y1079604D03*
X1886241D03*
G54D13*
X22947Y674933D03*
X23314Y700284D03*
X22920Y1127900D03*
X22894Y1153251D03*
X26822Y682433D03*
X30697Y674933D03*
X27189Y707784D03*
X31064Y700284D03*
X30670Y1127900D03*
X26795Y1135400D03*
X26769Y1160751D03*
X30644Y1153251D03*
X149826Y732591D03*
X145951Y725091D03*
X153701D03*
X145955Y740011D03*
X153705D03*
X149830Y747511D03*
X149841Y1177842D03*
X145966Y1170342D03*
X153716D03*
X150001Y1200224D03*
X146126Y1192724D03*
X153876D03*
X274093Y732335D03*
X270218Y724835D03*
X277968D03*
X270222Y739755D03*
X277972D03*
X274097Y747255D03*
X274055Y1177842D03*
X270180Y1170342D03*
X277930D03*
X274215Y1200224D03*
X270340Y1192724D03*
X278090D03*
X398250Y732263D03*
X394375Y724763D03*
X402125D03*
X394379Y739683D03*
X402129D03*
X398254Y747183D03*
X398281Y1179045D03*
X394406Y1171545D03*
X402156D03*
X398386Y1200224D03*
X394511Y1192724D03*
X402261D03*
X522346Y732516D03*
X518471Y725016D03*
X526221D03*
X518475Y739936D03*
X526225D03*
X522350Y747436D03*
X522648Y1180116D03*
X518773Y1172616D03*
X526523D03*
X522513Y1200182D03*
X518638Y1192682D03*
X526388D03*
X646780Y732433D03*
X642905Y724933D03*
X650655D03*
X642909Y739853D03*
X650659D03*
X646784Y747353D03*
X646864Y1179909D03*
X642989Y1172409D03*
X650739D03*
X646769Y1200140D03*
X642894Y1192640D03*
X650644D03*
X934960Y949195D03*
X931085Y941695D03*
X938835D03*
X1225845Y1160891D03*
X1221970Y1153391D03*
X1229720D03*
X1239945Y1160864D03*
X1236070Y1153364D03*
X1243820D03*
X1357711Y1131655D03*
X1365461D03*
X1361586Y1139155D03*
X1360794Y1160724D03*
X1356919Y1153224D03*
X1364669D03*
X1481346Y1126841D03*
X1489096D03*
X1485221Y1134341D03*
X1485468Y1160808D03*
X1481593Y1153308D03*
X1489343D03*
X1620052Y1114449D03*
X1619446Y1138567D03*
X1623927Y1121949D03*
X1627802Y1114449D03*
X1623321Y1146067D03*
X1627196Y1138567D03*
X1728978Y1127935D03*
X1736728D03*
X1732853Y1135435D03*
X1732996Y1160608D03*
X1729121Y1153108D03*
X1736871D03*
X1860667Y1153308D03*
X1850477Y1160786D03*
X1846602Y1153286D03*
X1854352D03*
X1864542Y1160808D03*
X1868417Y1153308D03*
G54D116*
G01X140572Y997250D02*
Y999422D01*
X142100Y1000950D01*
X148550D01*
X151600Y1004000D01*
Y1019300D01*
X155750Y1023450D01*
X208700D01*
G01X207272Y585250D02*
Y580428D01*
X217975Y569725D01*
X232400D01*
G01X225563Y981725D02*
X230129D01*
X236900Y988496D01*
Y1011800D01*
X225250Y1023450D01*
X208700D01*
G01X269763Y569725D02*
X232400D01*
G01X543371Y547216D02*
Y553186D01*
X543338Y553219D01*
G01X666142Y106469D02*
X670171D01*
X671352Y107650D01*
X675952D01*
G01X682452Y112770D02*
X690535D01*
X690567Y112738D01*
G01X675952Y112770D02*
X682452D01*
G01X885600Y824400D02*
X883763Y826237D01*
Y829253D01*
G01X896365Y1516542D02*
X901042D01*
X904440Y1519940D01*
X907950D01*
G01X911296Y1530405D02*
Y1529404D01*
X914450Y1526250D01*
Y1525060D01*
G01X977400Y1157900D02*
X978158Y1158658D01*
Y1165653D01*
X978115D01*
G01X999300Y-64400D02*
X1001540Y-62160D01*
Y-59968D01*
G01X1035820Y-61355D02*
Y-65980D01*
X1035000Y-66800D01*
G01X1023300Y-44200D02*
X1021660Y-45840D01*
Y-49332D01*
G01X1009100Y-48600D02*
X1006150Y-51550D01*
Y-52568D01*
X1006660D01*
G01X1032080Y-45980D02*
Y-52355D01*
G01X1030174Y-67274D02*
X1032080Y-65368D01*
Y-61355D01*
G01X1084200Y-82300D02*
X1086740Y-79760D01*
Y-77432D01*
G01X1070500Y-67900D02*
X1071840Y-66560D01*
Y-63832D01*
G01X1079600Y-50700D02*
X1076960Y-53340D01*
Y-56432D01*
G01X1058333Y-66597D02*
Y-72770D01*
G01X1053087Y-72916D02*
X1054593Y-71410D01*
Y-66597D01*
G01X1045163Y845653D02*
Y840400D01*
G01X1093900Y-64500D02*
X1091860Y-66540D01*
Y-70032D01*
G01X1107700Y-76800D02*
X1107362Y-76462D01*
Y-72521D01*
G01Y-61262D02*
Y-65121D01*
G01X1223275Y230742D02*
X1233900D01*
G01X1247159Y236459D02*
X1246560Y235860D01*
X1240400D01*
G01X1233900Y230740D02*
X1240400D01*
G01X1233900Y230742D02*
Y230740D01*
G01X1325735Y71629D02*
X1320105D01*
X1320055Y71679D01*
G01X1332500Y56500D02*
X1332600D01*
Y59200D01*
X1330855Y60945D01*
Y65129D01*
G01X1484608Y545215D02*
Y542045D01*
X1487541Y539112D01*
G01X1782372Y1009250D02*
Y1003628D01*
X1802875Y983125D01*
X1814600D01*
G01X1844863D02*
X1814600D01*
G54D23*
X72837Y181361D03*
Y634117D03*
Y1086873D03*
X140372Y739924D03*
X133063Y1009425D03*
X197049Y181361D03*
X199763Y597425D03*
X197449Y1086873D03*
X264739Y739668D03*
X337721Y125355D03*
X321362Y181361D03*
X321262Y634117D03*
Y1086873D03*
X365162Y95870D03*
X388796Y739596D03*
X389067Y1169730D03*
X445474Y181361D03*
Y634117D03*
X457173Y1075426D03*
X445573Y1107526D03*
X525579Y544981D03*
X512892Y739849D03*
X569687Y181361D03*
X575779Y520031D03*
X557279D03*
X594267Y534070D03*
X569687Y634117D03*
Y1086873D03*
X611910Y555074D03*
X637326Y739766D03*
X666142Y109919D03*
X693900Y181361D03*
Y1086873D03*
X752500Y1151700D03*
X877673Y865103D03*
X882400Y865068D03*
X876748Y1358507D03*
X876740Y1350414D03*
X882445Y1410997D03*
X877445D03*
X886792Y1411114D03*
X868500Y1439200D03*
X886500D03*
X877500D03*
X888600Y1485950D03*
X923600Y912400D03*
X928100D03*
X919100D03*
X932361Y962907D03*
X920607Y962782D03*
X936861Y962907D03*
X926100Y981900D03*
X930600D03*
X917100D03*
X929105Y1031960D03*
X920879Y1032103D03*
X932559Y1366984D03*
X932564Y1353312D03*
X936994Y1376548D03*
X926500Y1506400D03*
X942000D03*
X896335Y1528408D03*
X896365Y1519992D03*
X961500Y911700D03*
X966000D03*
X963900Y957100D03*
X950500Y982700D03*
X959500D03*
X946000D03*
X960400Y1027500D03*
X951872Y1365302D03*
X947125Y1376357D03*
X946300Y1506400D03*
X972413Y1549366D03*
X963488Y1520439D03*
X1039100Y908400D03*
X1020480Y908200D03*
X1015728D03*
X1023100Y959450D03*
X997694Y981540D03*
X1011194D03*
X993194D03*
X1017194Y1030640D03*
X1032500Y1073700D03*
X1037000D03*
X1023500D03*
X1035900Y1121500D03*
X1013400Y1144200D03*
X1004300D03*
X999700D03*
X1043112Y-38608D03*
X1066225Y-44000D03*
X1074400Y-73668D03*
X1046803Y876127D03*
X1042101Y880641D03*
X1043900Y908400D03*
X1053200D03*
X1073500Y1073700D03*
X1069000D03*
X1082500D03*
X1110500Y1073800D03*
X1119700D03*
X1124500D03*
X1128800Y1121900D03*
X1092200Y1122600D03*
X1176300Y296100D03*
X1180953Y296185D03*
X1176100Y277600D03*
X1176500Y1120200D03*
X1215547Y256715D03*
X1185588Y296150D03*
X1190200Y296100D03*
X1199000Y295700D03*
X1323521Y86155D03*
X1318821D03*
X1304563Y90958D03*
X1307500Y169361D03*
Y622117D03*
X1305100Y1074873D03*
X1354437Y84938D03*
X1337634Y133788D03*
X1421969Y520457D03*
X1413400Y571300D03*
X1431713Y169361D03*
X1470700Y528800D03*
X1435200Y521800D03*
X1448261Y521734D03*
X1456439Y521766D03*
X1447700Y575800D03*
X1474700D03*
X1431713Y622117D03*
Y1074873D03*
X1478700Y575800D03*
X1555925Y169361D03*
Y622117D03*
Y1074873D03*
X1585757Y129704D03*
X1602200Y1114600D03*
X1680138Y169361D03*
Y622117D03*
Y1074873D03*
X1804350Y169361D03*
Y622117D03*
X1774863Y1021425D03*
X1800750Y1074673D03*
X1855517Y165175D03*
X1843917Y197375D03*
X1855417Y617931D03*
X1843917Y650131D03*
X1840433Y1103341D03*
X1836431Y1147859D03*
X1868100Y1062200D03*
G54D32*
X61737Y254661D03*
X54137D03*
X61737Y707417D03*
X54137D03*
X61737Y1160173D03*
X54137D03*
X117994Y966075D03*
X103200Y975500D03*
X110800D03*
X103200Y967900D03*
X110800D03*
X169900Y563500D03*
Y555900D03*
X125594Y966075D03*
X185949Y254661D03*
X178349D03*
X184694Y554075D03*
X192294D03*
X177500Y563500D03*
Y555900D03*
X185949Y707417D03*
X178349D03*
X185949Y1160173D03*
X178349D03*
X310162Y254661D03*
X302562D03*
X310162Y707417D03*
X302562D03*
X310162Y1160173D03*
X302562D03*
X434374Y254661D03*
X426774D03*
X434374Y707417D03*
X426774D03*
X449338Y1160696D03*
X441738D03*
X550987Y254661D03*
Y707417D03*
Y1160173D03*
X558587Y254661D03*
X581036Y506682D03*
X588636D03*
X558587Y707417D03*
Y1160173D03*
X648465Y577467D03*
X682800Y254661D03*
X675200D03*
X656065Y577467D03*
X682800Y707417D03*
X675200D03*
X682800Y1160173D03*
X675200D03*
X826362Y43947D03*
X833962D03*
X861930Y43376D03*
X869530D03*
X861536Y75972D03*
X869136D03*
X1180068Y716700D03*
X1197068Y58168D03*
X1189468D03*
X1187668Y716700D03*
X1448662Y588301D03*
X1441062D03*
X1759794Y978075D03*
X1745000Y987500D03*
X1752600D03*
X1745000Y979900D03*
X1752600D03*
X1767394Y978075D03*
X1853469Y254661D03*
X1845869D03*
X1849876Y707417D03*
X1842276D03*
G54D41*
X111024Y141870D03*
Y314114D03*
Y594626D03*
Y766870D03*
Y1047382D03*
Y1219626D03*
X235236Y141870D03*
Y314114D03*
Y594626D03*
Y766870D03*
Y1047382D03*
Y1219626D03*
X359449Y141870D03*
Y314114D03*
Y594626D03*
Y766870D03*
Y1047382D03*
Y1219626D03*
X483661Y141870D03*
Y314114D03*
Y594626D03*
Y766870D03*
Y1047382D03*
Y1219626D03*
X607874Y141870D03*
Y314114D03*
Y594626D03*
Y766870D03*
Y1047382D03*
Y1219626D03*
X732087Y141870D03*
Y314114D03*
Y594626D03*
Y766870D03*
Y1047382D03*
Y1219626D03*
X938091Y-115157D03*
X1110335D03*
X1281693Y141870D03*
Y314114D03*
Y594626D03*
Y766870D03*
Y1047382D03*
Y1219626D03*
X1405906Y141870D03*
Y314114D03*
Y594626D03*
Y766870D03*
Y1047382D03*
Y1219626D03*
X1530118Y141870D03*
Y314114D03*
Y594626D03*
Y766870D03*
Y1047382D03*
Y1219626D03*
X1654331Y141870D03*
Y314114D03*
Y594626D03*
Y766870D03*
Y1047382D03*
Y1219626D03*
X1778543Y141870D03*
Y314114D03*
Y594626D03*
Y766870D03*
Y1047382D03*
Y1219626D03*
X1902756Y141870D03*
Y314114D03*
Y594626D03*
Y766870D03*
Y1047382D03*
Y1219626D03*
G54D107*
X1328500Y210661D03*
Y205661D03*
Y200661D03*
X1308500D03*
Y205661D03*
Y210661D03*
X1328500Y215661D03*
X1308500D03*
X1328500Y668417D03*
Y663417D03*
Y658417D03*
Y653417D03*
X1308500D03*
Y658417D03*
Y663417D03*
Y668417D03*
X1328500Y1121173D03*
Y1116173D03*
Y1111173D03*
Y1106173D03*
X1308500D03*
Y1111173D03*
Y1116173D03*
Y1121173D03*
X1452713Y210661D03*
Y205661D03*
Y200661D03*
X1432713D03*
Y205661D03*
Y210661D03*
X1452713Y215661D03*
X1432713D03*
X1452713Y668417D03*
Y663417D03*
Y658417D03*
Y653417D03*
X1432713D03*
Y658417D03*
Y663417D03*
Y668417D03*
X1452713Y1121173D03*
Y1116173D03*
Y1111173D03*
Y1106173D03*
X1432713D03*
Y1111173D03*
Y1116173D03*
Y1121173D03*
X1556925Y200661D03*
Y205661D03*
Y210661D03*
Y215661D03*
X1571925Y670417D03*
Y665417D03*
Y660417D03*
Y655417D03*
X1551925D03*
Y660417D03*
Y665417D03*
Y670417D03*
X1572100Y1099700D03*
Y1104700D03*
Y1109700D03*
Y1114700D03*
X1576925Y210661D03*
Y205661D03*
Y200661D03*
Y215661D03*
X1592100Y1114700D03*
Y1109700D03*
Y1104700D03*
Y1099700D03*
X1701138Y210661D03*
Y205661D03*
Y200661D03*
X1681138D03*
Y205661D03*
Y210661D03*
X1701138Y215661D03*
X1681138D03*
X1701138Y668417D03*
Y663417D03*
Y658417D03*
Y653417D03*
X1681138D03*
Y658417D03*
Y663417D03*
Y668417D03*
X1701138Y1121173D03*
Y1116173D03*
Y1111173D03*
Y1106173D03*
X1681138D03*
Y1111173D03*
Y1116173D03*
Y1121173D03*
X1805350Y200661D03*
Y205661D03*
Y210661D03*
Y215661D03*
Y653417D03*
Y658417D03*
Y663417D03*
Y668417D03*
X1803350Y1106173D03*
Y1111173D03*
Y1116173D03*
Y1121173D03*
X1825350Y210661D03*
Y205661D03*
Y200661D03*
Y215661D03*
Y668417D03*
Y663417D03*
Y658417D03*
Y653417D03*
X1823350Y1121173D03*
Y1116173D03*
Y1111173D03*
Y1106173D03*
G54D14*
X21999Y667471D03*
X22600Y693100D03*
X21626Y1120900D03*
X22100Y1146200D03*
X25000Y1209100D03*
X60187Y194161D03*
X67987Y199261D03*
X68937Y262161D03*
X72049Y424200D03*
X68109Y453300D03*
X43100Y464100D03*
X57963Y457439D03*
X47607Y520462D03*
X61834Y520466D03*
X60187Y646917D03*
X67987Y651900D03*
X68937Y714917D03*
X33900Y764200D03*
X28400Y763600D03*
X72049Y923100D03*
X68109Y932900D03*
X60187Y1099673D03*
X68100Y1104973D03*
X68937Y1167673D03*
X30000Y1206100D03*
X52600Y1201300D03*
X48219Y1196721D03*
X77237Y181411D03*
X81437Y177911D03*
X88300Y186300D03*
X82437Y260661D03*
X79200Y233800D03*
X77237Y634167D03*
X81437Y630667D03*
X87819Y638950D03*
X85146Y625491D03*
X79000Y686500D03*
X82437Y713417D03*
X108647Y980933D03*
X101403Y981195D03*
X96563Y969225D03*
X110363Y1003825D03*
X117063Y1006725D03*
X108063Y988125D03*
X102113Y998225D03*
X81437Y1083423D03*
X77237Y1086923D03*
X88787Y1091673D03*
X82437Y1166173D03*
X78700Y1139500D03*
X139187Y250161D03*
X145437Y261100D03*
X167992Y400500D03*
X168813Y586225D03*
X168103Y569195D03*
X163263Y557225D03*
X139187Y702917D03*
X150253Y718842D03*
X140364Y745281D03*
X145437Y713700D03*
X159600Y758942D03*
X149830Y762815D03*
X137163Y987125D03*
X132175Y979825D03*
X133663Y973825D03*
X131563Y966735D03*
X145363Y997741D03*
X128063Y1006725D03*
X150869Y1163222D03*
X139187Y1155673D03*
X140166Y1214922D03*
X147538Y1213917D03*
X144264Y1186512D03*
X165490Y1217508D03*
X154473Y1213919D03*
X201449Y181411D03*
X184399Y194161D03*
X192199Y199061D03*
X205649Y177911D03*
X212999Y186161D03*
X206649Y260661D03*
X203400Y234000D03*
X193149Y262161D03*
X196261Y397500D03*
X192321Y406000D03*
X182217Y399500D03*
X171861Y520420D03*
X186088Y520424D03*
X210263Y550725D03*
X177063Y591825D03*
X212063Y585741D03*
X194763Y594725D03*
X183763D03*
X174763Y576125D03*
X203863Y575125D03*
X198263Y554735D03*
X198004Y567809D03*
X200363Y561825D03*
X202174Y625523D03*
X196360Y638400D03*
X207409Y625539D03*
X212999Y628417D03*
X203600Y686800D03*
X198000Y650000D03*
X206649Y713417D03*
X193149Y714917D03*
X202534Y917700D03*
X206200Y925200D03*
X208700Y1023450D03*
X205649Y1083423D03*
X201449Y1086923D03*
X183793Y1104177D03*
X194100Y1101800D03*
X212999Y1091673D03*
X206649Y1166173D03*
X193149Y1167673D03*
X203100Y1139500D03*
X263399Y250161D03*
X232400Y569725D03*
X263399Y702917D03*
X264731Y745025D03*
X263399Y1155673D03*
X311000Y76700D03*
X308612Y194161D03*
X269649Y260800D03*
X292153Y491834D03*
X306388Y491797D03*
X296032Y520420D03*
X310259Y520424D03*
X308612Y646917D03*
X268071Y713929D03*
X274520Y718586D03*
X283516Y768434D03*
X274097Y762119D03*
X308612Y1099673D03*
X275087Y1163231D03*
X268478Y1186512D03*
X284954Y1257055D03*
X280888Y1249308D03*
X303376Y1248708D03*
X306015Y1256575D03*
X353894Y66695D03*
X335766Y74334D03*
X322965Y77565D03*
X329529Y77300D03*
X329961Y115700D03*
X333741Y117531D03*
X319329Y117277D03*
X340201Y118481D03*
X325662Y181411D03*
X316412Y199161D03*
X329862Y177911D03*
X337212Y186161D03*
X330862Y260661D03*
X327600Y234000D03*
X317362Y262161D03*
X320925Y491367D03*
X315925Y491578D03*
X325662Y634167D03*
X329862Y630667D03*
X336409Y639049D03*
X333682Y625711D03*
X328000Y686700D03*
X316412Y651917D03*
X330862Y713417D03*
X317362Y714917D03*
X320925Y943284D03*
X315925Y943495D03*
X329862Y1083423D03*
X325662Y1086923D03*
X317811Y1102937D03*
X337312Y1091773D03*
X330862Y1166173D03*
X317362Y1167673D03*
X327600Y1139400D03*
X371619Y84720D03*
X370390Y95920D03*
X387612Y251061D03*
X391986Y262414D03*
X387612Y702917D03*
X393862Y714500D03*
X398677Y718514D03*
X388788Y744953D03*
X407714Y756056D03*
X398254Y757066D03*
X387612Y1155673D03*
X393698Y1166123D03*
X393193Y1220531D03*
X391827Y1214891D03*
X392977Y1185945D03*
X403487Y1213549D03*
X450984Y124507D03*
X436811D03*
X449874Y181411D03*
X432824Y194161D03*
X440624Y199100D03*
X454074Y177911D03*
X455074Y260661D03*
X451800Y234000D03*
X441574Y262161D03*
X445138Y492299D03*
X440138Y492173D03*
X416303Y491797D03*
X430538Y491760D03*
X420182Y520383D03*
X434409Y520387D03*
X449874Y634167D03*
X432824Y646917D03*
X454074Y630667D03*
X457853Y625956D03*
X452000Y686600D03*
X441600Y650800D03*
X455074Y713417D03*
X441574Y714917D03*
X445138Y943284D03*
X440138Y943495D03*
X443923Y1082726D03*
X452173Y1075476D03*
X447423Y1086926D03*
X453423Y1108600D03*
X456174Y1167573D03*
X415430Y1216989D03*
X479830Y124507D03*
X465157D03*
X461424Y186161D03*
X460521Y638901D03*
X550197Y124507D03*
X536023D03*
X521850D03*
X511824Y250161D03*
X518074Y260500D03*
X539350Y491729D03*
X534350Y491940D03*
X510621Y491834D03*
X524856Y491797D03*
X550161Y544768D03*
X549279Y524831D03*
X554889Y550331D03*
X521191Y545078D03*
X514500Y520420D03*
X528727Y520424D03*
X553279Y530931D03*
Y537910D03*
X536900Y528500D03*
X536891Y532831D03*
X554055Y576466D03*
X552379Y566531D03*
X536979Y553219D03*
X513729Y557675D03*
X511824Y702917D03*
X515025Y715075D03*
X522773Y718767D03*
X512884Y745206D03*
X531810Y755383D03*
X522350Y756393D03*
X509300Y1121500D03*
X514000Y1139900D03*
X514274Y1161673D03*
X518975Y1167110D03*
X517342Y1185651D03*
X544486Y1266486D03*
X534733Y1252634D03*
X547100Y1232500D03*
X554772Y1250785D03*
X564370Y124507D03*
X574087Y181411D03*
X557037Y194161D03*
X566160Y197579D03*
X578287Y177911D03*
X585637Y186161D03*
X579287Y260661D03*
X576700Y234000D03*
X565787Y262161D03*
X575607Y499947D03*
X588026Y526957D03*
X594795Y504965D03*
X569347Y524499D03*
X587279Y547831D03*
X575779Y524831D03*
X588978Y534615D03*
X564388Y526640D03*
X599247Y525694D03*
X596414Y538329D03*
Y543329D03*
X560500Y558600D03*
X601979Y559456D03*
X593779Y556274D03*
X576029Y561181D03*
X568029Y560831D03*
X586279Y560331D03*
X562279Y565331D03*
X580053Y559080D03*
X574087Y634167D03*
X557037Y646917D03*
X578287Y630667D03*
X585637Y638917D03*
X576300Y686800D03*
X564937Y651917D03*
X579287Y713417D03*
X565787Y714917D03*
X569350Y945784D03*
X564350Y945995D03*
X578287Y1083423D03*
X574087Y1086923D03*
X557037Y1099673D03*
X564837Y1104800D03*
X585637Y1091673D03*
X579000Y1166500D03*
X565787Y1167673D03*
X576000Y1139700D03*
X616903Y107633D03*
X636037Y250161D03*
X642287Y262200D03*
X627863Y517621D03*
X642344Y516870D03*
X606884Y525791D03*
X642152Y578952D03*
X636037Y702917D03*
X642287Y714800D03*
X647207Y718684D03*
X637318Y745123D03*
X646784Y756310D03*
X636037Y1155673D03*
X647716Y1165672D03*
X638776Y1214234D03*
X641383Y1186238D03*
X661638Y109969D03*
X685711Y101931D03*
X698300Y181411D03*
X681250Y194161D03*
X690166Y198044D03*
X699900Y233700D03*
X690000Y262161D03*
X693112Y382100D03*
X689172Y380276D03*
X693112Y361401D03*
X689172Y362876D03*
X699025Y636023D03*
X679213Y612355D03*
X690213Y603973D03*
X701000Y686700D03*
X689758Y649790D03*
X689050Y669146D03*
X690000Y714917D03*
X656244Y755300D03*
X689172Y928400D03*
X693112Y940100D03*
X698300Y1086923D03*
X680400Y1105800D03*
X691400Y1101900D03*
X690000Y1167673D03*
X700100Y1139500D03*
X658241Y1228338D03*
X658303Y1216330D03*
X679907Y1232607D03*
X702500Y177911D03*
X709850Y186161D03*
X703500Y260661D03*
X704260Y635957D03*
X709850Y638917D03*
X703500Y713417D03*
X737984Y861689D03*
X747383Y924689D03*
X702500Y1083423D03*
X709850Y1091673D03*
X703500Y1166173D03*
X758000Y223500D03*
X753893Y912630D03*
X760250Y1154000D03*
X779535Y1180469D03*
X792263Y1178661D03*
Y1174461D03*
Y1170261D03*
X784544Y1210178D03*
Y1205978D03*
X779535Y1193469D03*
Y1189269D03*
Y1184669D03*
X797177Y1189537D03*
X797225Y1185337D03*
X792263Y1182861D03*
X882900Y359100D03*
X883200Y378495D03*
X882400Y445462D03*
X882500Y450200D03*
Y454900D03*
X870179D03*
X870389Y445462D03*
X870221Y450200D03*
X882600Y459562D03*
X882700Y464505D03*
X870263Y459562D03*
X883900Y542405D03*
X884182Y820251D03*
X879519Y821655D03*
X874623Y822631D03*
X881203Y852900D03*
X876900D03*
X885873Y852800D03*
X888643Y1356566D03*
X889223Y1350339D03*
X885754Y1375500D03*
X885608Y1379698D03*
X877500Y1443500D03*
X881901Y1443300D03*
X871325Y1443125D03*
X888000Y1478800D03*
X883647Y1478447D03*
X879341Y1478200D03*
X882572Y1492349D03*
X879321Y1489661D03*
X855535Y1498705D03*
X855523Y1504750D03*
X888390Y1534018D03*
X855899Y1529934D03*
X867500Y1519500D03*
X915654Y916254D03*
X921100Y916100D03*
X928100Y916200D03*
X923600Y905000D03*
X928100Y905300D03*
X901540Y916200D03*
X904100Y912860D03*
X933524Y916449D03*
X923985Y954185D03*
X918577Y955523D03*
X929960Y954810D03*
X918220Y985720D03*
X923100Y985700D03*
X927460Y985574D03*
X927917Y974344D03*
X934343Y978450D03*
X912994Y967848D03*
X910594Y955106D03*
X906600Y985800D03*
X908094Y965295D03*
X905506Y958415D03*
X902866Y964401D03*
X900400Y960942D03*
X901480Y985800D03*
X926513Y1023713D03*
X920500Y1024400D03*
X932316Y1023966D03*
X942893Y1001345D03*
X918430Y1040930D03*
X919778Y1047278D03*
X919400Y1056000D03*
X914100Y1056200D03*
X910387Y1051177D03*
X904875Y1046590D03*
X924200Y1371800D03*
X924436Y1367064D03*
X924400Y1362000D03*
X925313Y1356403D03*
X924300Y1376100D03*
X938000Y1511000D03*
X918500Y1510200D03*
X898378Y1478800D03*
X924000Y1518200D03*
X929000Y1544700D03*
X921500Y1544200D03*
X924300Y1530184D03*
X937250Y1547200D03*
X924110Y1536700D03*
X931500Y1548200D03*
X923400Y1524279D03*
X900248Y1521048D03*
X904900Y1534500D03*
X958200Y915800D03*
X963066Y915830D03*
X953320Y915800D03*
X961100Y949800D03*
X956800Y949900D03*
X950400Y949800D03*
X951700Y986600D03*
X956300D03*
X947400Y986458D03*
X981580Y953300D03*
X979020Y949700D03*
X976460Y953300D03*
X973900Y949800D03*
X971340Y953300D03*
X968780Y949800D03*
X944617Y975530D03*
X945790Y945819D03*
X956100Y1020300D03*
X951800D03*
X946800Y1020200D03*
X981500Y1179000D03*
X968800Y1158500D03*
X957346Y1516124D03*
X964419Y1509261D03*
X946300Y1511200D03*
X967998Y1512551D03*
X988573Y1513673D03*
X971069Y1495465D03*
X972158Y1542266D03*
X961008Y1546961D03*
X959987Y1541339D03*
X945250Y1547450D03*
X956597Y1533926D03*
X955236Y1546187D03*
X958199Y1520984D03*
X948750Y1545050D03*
X998045Y-90000D03*
X1006660Y-81200D03*
X1010800Y-77400D03*
X1004100Y-47369D03*
X1029900Y-75400D03*
X1004100Y-65700D03*
X1039560Y-45900D03*
X1038808Y-67700D03*
X1019100Y-43996D03*
Y-62000D03*
X1010380Y-20480D03*
X1011125Y-15559D03*
X1005981Y58902D03*
X1004000Y54400D03*
X1005400Y63780D03*
X1006815Y545207D03*
X1006400Y554532D03*
X1035958Y838664D03*
X1037400Y868600D03*
X1033600Y912400D03*
X1019221Y913481D03*
X1025400Y912800D03*
X1012750Y926499D03*
X1000174Y986100D03*
X1006694D03*
X1023100Y951000D03*
X994900Y986000D03*
X1009200Y1020500D03*
X1003000Y1023000D03*
X998439Y1023100D03*
X1029339Y1077911D03*
X1034069Y1077881D03*
X1024500Y1077800D03*
X1031400Y1112664D03*
X1026900Y1114107D03*
X1022400Y1114181D03*
X1026900Y1125640D03*
X1022400Y1125311D03*
X998208Y1148628D03*
X1004500Y1148300D03*
X1011497Y1148303D03*
X1009500Y1180377D03*
X1014500Y1180413D03*
X1004500Y1180370D03*
X1038000Y1324216D03*
X1038200Y1337616D03*
X1038400Y1342668D03*
X1038200Y1330916D03*
X1018483Y1474093D03*
X1075100Y-86200D03*
X1049500Y-73200D03*
X1062073Y-51100D03*
X1062400Y-72800D03*
X1074400Y-50694D03*
Y-69174D03*
X1073400Y22405D03*
X1073598Y79465D03*
X1053774Y429753D03*
X1053721Y434409D03*
X1047853Y446600D03*
X1053700Y557053D03*
X1049301Y835703D03*
X1046937Y829163D03*
X1042123Y868400D03*
X1083633Y864110D03*
X1046803Y868900D03*
X1042155Y912845D03*
X1051573Y912477D03*
X1083633Y902332D03*
X1074292Y1077704D03*
X1078534Y1077715D03*
X1069870Y1077770D03*
X1086842Y1114342D03*
X1079000Y1115489D03*
X1074500Y1115393D03*
X1041975Y1349992D03*
X1042039Y1354526D03*
X1074283Y1474093D03*
X1046283D03*
X1070400Y1521000D03*
X1105400Y-91100D03*
X1112600Y-94000D03*
X1089300Y-82962D03*
X1094300Y-84700D03*
X1089300Y-64555D03*
X1111778Y-60293D03*
X1107362Y-59500D03*
X1096500Y-53500D03*
X1137446Y1024025D03*
Y1009852D03*
Y995679D03*
Y1038198D03*
X1120179Y1078250D03*
X1125362Y1078488D03*
X1115520Y1078475D03*
X1127100Y1113738D03*
X1122500Y1113770D03*
X1118000D03*
X1136007Y1114387D03*
X1137446Y1167343D03*
Y1224036D03*
Y1209863D03*
Y1195690D03*
Y1181516D03*
Y1266556D03*
Y1252383D03*
Y1238209D03*
Y1309076D03*
Y1323249D03*
Y1294902D03*
Y1280729D03*
Y1365769D03*
Y1351595D03*
Y1337422D03*
Y1394115D03*
Y1408288D03*
Y1379942D03*
X1172375Y101360D03*
X1171552Y96794D03*
X1185100Y245100D03*
X1185588Y301468D03*
X1180953Y303520D03*
X1176272Y301668D03*
X1180953Y288600D03*
X1185588Y288981D03*
X1182411Y317764D03*
X1178081Y329765D03*
X1148997Y1097672D03*
X1148830Y1091117D03*
X1145936Y1113107D03*
X1142020Y1114701D03*
X1138679Y1117874D03*
X1176500Y1127000D03*
X1223600Y241100D03*
X1190882Y255782D03*
X1190200Y301168D03*
X1220200Y268800D03*
X1190200Y288892D03*
X1192600Y277700D03*
X1188900Y281300D03*
X1192600Y273400D03*
X1189924Y314076D03*
X1188400Y1029031D03*
X1189900Y1033731D03*
X1211205Y1174705D03*
X1220723Y1146560D03*
X1216205Y1182451D03*
X1256500Y250161D03*
X1249000Y227700D03*
X1250500Y262600D03*
X1261500Y451500D03*
X1256500Y465200D03*
X1239758Y489880D03*
X1250660Y478500D03*
X1244910Y513555D03*
X1259426Y513463D03*
X1254500Y702917D03*
X1250660Y714960D03*
X1268742Y922198D03*
X1263742Y938298D03*
X1240222Y911913D03*
X1254331Y935742D03*
X1245251Y965973D03*
X1259600Y965700D03*
X1254750Y1155423D03*
X1251053Y1168353D03*
X1234995Y1146053D03*
X1242718Y1190900D03*
X1238778Y1222200D03*
X1304563Y96258D03*
X1323181Y89965D03*
X1328161Y90500D03*
X1299569Y96258D03*
X1317900Y90500D03*
X1327307Y124489D03*
X1319807Y125683D03*
X1317445Y120920D03*
X1317000Y178161D03*
X1308250Y186200D03*
X1324500Y194661D03*
X1317000Y169411D03*
X1326300Y165911D03*
X1310500Y247161D03*
X1310501Y279736D03*
X1317000Y630917D03*
X1302500Y642417D03*
X1324500Y647417D03*
X1317000Y622167D03*
X1326423Y618667D03*
X1310882Y732348D03*
X1310500Y699917D03*
X1317000Y1083673D03*
X1313400Y1074923D03*
X1302500Y1095173D03*
X1324500Y1100173D03*
X1310500Y1152673D03*
X1310494Y1184880D03*
X1336516Y87410D03*
X1337176Y78470D03*
X1340961Y82656D03*
X1343521Y89403D03*
X1348641Y87218D03*
X1331759Y80400D03*
X1333281Y90526D03*
X1349931Y134433D03*
X1331365Y125601D03*
X1351008Y124582D03*
X1343170Y125197D03*
X1336500Y194661D03*
X1334534Y274847D03*
X1374713Y263900D03*
X1366931Y402900D03*
X1362991Y429900D03*
X1347982Y482100D03*
X1356542Y458900D03*
X1341262Y513426D03*
X1355778Y513334D03*
X1368165Y542402D03*
X1361500Y567500D03*
X1369300Y578700D03*
X1336500Y647417D03*
X1378713Y702917D03*
X1334385Y726575D03*
X1374839Y715539D03*
X1362991Y888400D03*
X1366931Y921200D03*
X1345800Y924700D03*
X1354301Y935405D03*
X1343677Y965649D03*
X1358581Y966602D03*
X1336500Y1100173D03*
X1356639Y1123408D03*
X1378963Y1155600D03*
X1375887Y1169387D03*
X1355100Y1147400D03*
X1334232Y1181463D03*
X1346321Y1182700D03*
X1351321Y1211900D03*
X1366931Y1198700D03*
X1362991Y1254400D03*
X1380713Y251400D03*
X1402872Y535918D03*
X1426713Y642417D03*
Y1095173D03*
X1447834Y124507D03*
X1441213Y178161D03*
X1460713Y194661D03*
X1432463Y186623D03*
X1448713Y194661D03*
X1441213Y169411D03*
X1450700Y165937D03*
X1434713Y247161D03*
X1434890Y279853D03*
X1458098Y274316D03*
X1472194Y448500D03*
X1463085Y494974D03*
X1462848Y512169D03*
X1467000Y533700D03*
X1475600Y525900D03*
X1440400Y537300D03*
X1432800Y535300D03*
X1452584Y530090D03*
X1459950Y531600D03*
X1440700Y544600D03*
X1441700Y532100D03*
X1473090Y542100D03*
X1465700Y527100D03*
X1449614Y533651D03*
X1430431Y549130D03*
X1444000Y567000D03*
X1434414Y580369D03*
X1459200Y568200D03*
X1452200Y567600D03*
X1439000Y558000D03*
X1463521Y567421D03*
X1474700Y561500D03*
Y554521D03*
X1433200Y571600D03*
X1428200Y562850D03*
X1430431Y554130D03*
X1451686Y594814D03*
X1441213Y630917D03*
X1460713Y647417D03*
X1448713D03*
X1441213Y622167D03*
X1451016Y618667D03*
X1435496Y732268D03*
X1458283Y728459D03*
X1434713Y699917D03*
X1466036Y937510D03*
X1467889Y965707D03*
X1441213Y1083673D03*
Y1074923D03*
X1446213Y1066700D03*
X1460713Y1100173D03*
X1448713D03*
X1458334Y1180299D03*
X1434713Y1152673D03*
X1434536Y1185247D03*
X1504527Y124507D03*
X1490354D03*
X1518701D03*
X1503025Y250061D03*
X1497025Y273400D03*
X1491143Y420100D03*
X1487203Y448300D03*
X1481938Y493921D03*
X1477766Y479986D03*
X1477818Y547663D03*
X1492700Y539112D03*
X1512940Y533903D03*
X1478700Y567600D03*
X1502925Y702917D03*
X1498349Y715749D03*
X1491143Y863600D03*
X1487203Y887900D03*
X1484054Y911900D03*
X1482793Y966760D03*
X1479828Y1118016D03*
X1504700Y1156926D03*
X1500838Y1167938D03*
X1480600Y1144400D03*
X1491143Y1211600D03*
X1476175Y1265600D03*
X1481175Y1251700D03*
X1487203Y1234300D03*
X1532874Y124507D03*
X1565425Y178161D03*
X1556675Y186000D03*
X1565425Y169411D03*
X1558925Y247161D03*
X1559257Y279526D03*
X1565425Y630917D03*
X1551675Y640424D03*
X1565425Y622167D03*
X1567925Y649417D03*
X1559129Y732414D03*
X1558925Y699917D03*
X1565425Y1083673D03*
Y1074923D03*
X1570425Y1067600D03*
X1549425Y1092973D03*
X1558925Y1152673D03*
X1558141Y1185570D03*
X1565173Y1185730D03*
X1589100Y146241D03*
X1585757Y121382D03*
X1584925Y194661D03*
X1572925D03*
X1575479Y165911D03*
X1582965Y274048D03*
X1615356Y487800D03*
X1611416Y465200D03*
X1596407Y472700D03*
X1601101Y464367D03*
X1592144Y513510D03*
X1606660Y513418D03*
X1575057Y618667D03*
X1578976Y670497D03*
X1582690Y727290D03*
X1615356Y885149D03*
X1611416Y877400D03*
X1592128Y938753D03*
X1604967Y905900D03*
X1592102Y965633D03*
X1606800Y965889D03*
X1594025Y1093873D03*
X1582025D03*
X1619308Y1107701D03*
X1605083Y1217917D03*
X1615900Y1200200D03*
X1619940Y1225400D03*
X1615356Y1256600D03*
X1628738Y250061D03*
X1622738Y260500D03*
X1627138Y702917D03*
X1621138Y714900D03*
X1623034Y1132351D03*
X1689638Y178161D03*
X1709138Y194661D03*
X1680888Y186300D03*
X1697138Y194661D03*
X1689638Y169411D03*
X1699692Y165911D03*
X1683138Y247161D03*
X1682961Y280030D03*
X1706641Y275966D03*
X1716609Y513257D03*
X1689638Y630917D03*
X1709138Y647417D03*
X1675138Y642417D03*
X1697138Y647417D03*
X1689638Y622167D03*
X1699788Y618667D03*
X1683708Y732526D03*
X1706680Y727755D03*
X1683138Y699917D03*
X1689638Y1083673D03*
Y1074923D03*
X1694638Y1067600D03*
X1709138Y1100173D03*
X1675138Y1095173D03*
X1697138Y1100173D03*
X1683138Y1152673D03*
X1682961Y1185542D03*
X1706935Y1180888D03*
X1753550Y250061D03*
X1747550Y261100D03*
X1729179Y393700D03*
X1739568Y453500D03*
X1723619Y436700D03*
X1735628Y476630D03*
X1731125Y513165D03*
X1755459Y711160D03*
X1739568Y852900D03*
X1735628Y883800D03*
X1752000Y901047D03*
X1749145Y918827D03*
X1749242Y970095D03*
X1764356Y970161D03*
X1749573Y939015D03*
X1738363Y981225D03*
X1752163Y1015825D03*
X1758863Y1018725D03*
X1749863Y1000125D03*
X1743913Y1010225D03*
X1737241Y997843D03*
X1727481Y1120480D03*
X1751600Y1155523D03*
X1746700Y1169200D03*
X1727463Y1145781D03*
X1739568Y1209300D03*
X1735628Y1226800D03*
X1718117Y1274820D03*
X1723117Y1266400D03*
X1813850Y178161D03*
X1804897Y187050D03*
X1813850Y169411D03*
X1807350Y247161D03*
X1807880Y279499D03*
X1813850Y630917D03*
X1799350Y642417D03*
X1813850Y622167D03*
X1808526Y731698D03*
X1807350Y699917D03*
X1777666Y932748D03*
X1782666Y939436D03*
X1794767Y964624D03*
X1811581Y965390D03*
X1783778Y974371D03*
X1775863Y978735D03*
X1775963Y985825D03*
X1792236Y942480D03*
X1806452Y942675D03*
X1787163Y1009741D03*
X1769863Y1018725D03*
X1778963Y999125D03*
X1774000Y991825D03*
X1813850Y1083673D03*
X1810250Y1074723D03*
X1799350Y1095173D03*
X1807350Y1152673D03*
X1807527Y1185306D03*
X1841021Y156822D03*
X1845667Y176775D03*
X1833350Y194661D03*
X1851919Y199644D03*
X1859117Y193744D03*
X1821350Y194661D03*
X1842167Y172575D03*
X1850517Y165225D03*
X1823904Y165911D03*
X1831323Y274905D03*
X1860669Y262161D03*
X1859841Y452000D03*
X1844832Y446400D03*
X1853392Y476500D03*
X1840000Y513000D03*
X1854800Y513100D03*
X1845667Y629531D03*
X1833350Y647417D03*
X1859117Y646500D03*
X1821350Y647417D03*
X1842167Y625331D03*
X1850417Y617981D03*
X1823543Y618667D03*
X1840891Y610086D03*
X1851667Y652500D03*
X1847500Y659100D03*
X1821900Y676400D03*
X1830850Y730417D03*
X1854028Y713674D03*
X1814600Y983125D03*
X1857100Y1086300D03*
X1833350Y1100173D03*
X1851981Y1103613D03*
X1859974Y1109049D03*
X1821350Y1100173D03*
X1844432Y1099891D03*
X1831089Y1181419D03*
X1844138Y1240750D03*
X1845845Y1234445D03*
X1860457Y1229857D03*
X1856642Y1233142D03*
X1874400Y190744D03*
X1864775Y182057D03*
X1871200Y234100D03*
Y262000D03*
X1863781Y429200D03*
X1874500Y643500D03*
X1864000Y638000D03*
X1871000Y686600D03*
X1870198Y713498D03*
X1867652Y865421D03*
X1876555Y1070799D03*
X1872967Y1067014D03*
X1877045Y1138812D03*
X1871802Y1182620D03*
G54D50*
G01X64487Y209361D02*
Y212761D01*
G01X56687Y210561D02*
Y214661D01*
G01X64487Y205261D02*
Y201761D01*
G01X56587Y179561D02*
X53087D01*
G01X54137Y254661D02*
X49437D01*
G01X54088Y506897D02*
Y512336D01*
G01X39853Y506934D02*
Y512373D01*
G01X44107Y513016D02*
Y516506D01*
X44111Y516510D01*
G01X58334Y513020D02*
Y516461D01*
X58346Y516473D01*
G01X72500Y504000D02*
Y508600D01*
G01X67500Y504000D02*
Y508600D01*
G01X56587Y632317D02*
X53087D01*
G01X30697Y674933D02*
Y679553D01*
G01X31043Y692869D02*
Y689115D01*
G01X30676Y667518D02*
Y663764D01*
G01X64487Y662017D02*
Y665417D01*
G01X56687Y663317D02*
Y667417D01*
G01X64487Y657917D02*
Y654417D01*
G01X54137Y707417D02*
X49437D01*
G01X31064Y700284D02*
Y704904D01*
G01X67500Y961355D02*
Y956755D01*
G01X72500Y961355D02*
Y956755D01*
G01X30256Y1120485D02*
Y1116731D01*
G01X30670Y1127900D02*
Y1132472D01*
G01X64487Y1114773D02*
Y1118173D01*
G01X56687Y1116073D02*
Y1120173D01*
G01X64487Y1110673D02*
Y1107173D01*
G01X56487Y1085073D02*
X53027D01*
G01X30644Y1153251D02*
Y1157871D01*
G01X54137Y1160173D02*
X49437D01*
G01X30623Y1145836D02*
Y1142082D01*
G01X30000Y1195000D02*
Y1190400D01*
G01X25000Y1195000D02*
Y1190400D01*
G01X111024Y141870D02*
X118437D01*
G01X118209Y180492D02*
X111437D01*
G01X118209Y165492D02*
X111437D01*
G01X118209Y195492D02*
X111437D01*
G01X99823Y207992D02*
X106937D01*
G01X99823Y198543D02*
X106937D01*
G01X92287Y191161D02*
Y194661D01*
G01X92187Y181161D02*
X95437D01*
G01X118209Y235492D02*
X111437D01*
G01X118209Y245492D02*
X111437D01*
G01X99823Y217441D02*
X106937D01*
G01X77437Y247161D02*
X73437D01*
G01Y234661D02*
Y240161D01*
G01X118209Y275492D02*
X111437D01*
G01X118209Y265492D02*
X111437D01*
G01X94237Y276861D02*
X89237D01*
G01X95437Y296161D02*
Y300161D01*
G01X111024Y314114D02*
X118437D01*
G01X111024Y594626D02*
X118753D01*
G01X118209Y648248D02*
X111437D01*
G01X118209Y633248D02*
X111437D01*
G01X118209Y618248D02*
X111437D01*
G01X92287Y643917D02*
Y647417D01*
G01X92187Y633917D02*
X95437D01*
G01X99823Y670197D02*
X106937D01*
G01X118209Y688248D02*
X111437D01*
G01X99823Y660748D02*
X106937D01*
G01X99823Y651299D02*
X106937D01*
G01X73437Y687417D02*
Y692917D01*
G01X118209Y728248D02*
X111437D01*
G01X118209Y718248D02*
X111437D01*
G01X118209Y698248D02*
X111437D01*
G01X94237Y729617D02*
X89237D01*
G01X77437Y699917D02*
X73437D01*
G01X111024Y766870D02*
X118437D01*
G01X95437Y748917D02*
Y752917D01*
G01X119163Y959625D02*
Y964906D01*
G01D02*
X117994Y966075D01*
G01X118209Y1071004D02*
X111437D01*
G01X111024Y1047382D02*
X118437D01*
G01X99823Y1122953D02*
X106937D01*
G01X99823Y1113504D02*
X106937D01*
G01X99823Y1104055D02*
X106937D01*
G01X118209Y1101004D02*
X111437D01*
G01X118209Y1086004D02*
X111437D01*
G01X92287Y1096673D02*
Y1100173D01*
G01Y1086673D02*
X95537D01*
G01X118209Y1171004D02*
X111437D01*
G01X118209Y1151004D02*
X111437D01*
G01X118209Y1141004D02*
X111437D01*
G01X73437Y1140173D02*
Y1145673D01*
G01X77437Y1152673D02*
X73437D01*
G01X111024Y1219626D02*
X118437D01*
G01X118209Y1181004D02*
X111437D01*
G01X94237Y1182373D02*
X89237D01*
G01X95437Y1201673D02*
Y1205673D01*
G01X142687Y240661D02*
Y237161D01*
G01Y244761D02*
Y248100D01*
G01X164107Y506892D02*
Y512331D01*
G01X168361Y512874D02*
Y516364D01*
X168365Y516368D01*
G01X142687Y693417D02*
Y689917D01*
G01X153705Y740011D02*
Y744831D01*
G01X140372Y736474D02*
Y732370D01*
G01X153701Y725091D02*
Y720791D01*
X153714D01*
Y720741D01*
G01X153753Y714355D02*
Y710653D01*
X153757D01*
G01X142687Y697517D02*
Y700767D01*
G01X126063Y979825D02*
X132175D01*
G01X130463Y983925D02*
X132175Y982213D01*
Y979825D01*
G01X126063Y973825D02*
X133663D01*
G01X138506Y971762D02*
X136443Y973825D01*
X133663D01*
G01X125594Y966075D02*
X126254Y966735D01*
X131563D01*
G01D02*
X138478D01*
G01X125063Y997225D02*
X125313Y997475D01*
Y1001725D01*
G01X124405Y992723D02*
Y996567D01*
X125063Y997225D01*
G01X125313Y1001725D02*
X123547Y1003491D01*
X121914D01*
G01X133063Y1009475D02*
Y1012725D01*
G01X142687Y1146173D02*
Y1142673D01*
G01X153716Y1170342D02*
Y1174793D01*
G01X154362Y1158233D02*
Y1161725D01*
X154363D01*
G01X142687Y1150273D02*
Y1153523D01*
G01X153932Y1186220D02*
Y1182940D01*
G01X153876Y1192724D02*
Y1197248D01*
X153824D01*
G01X135422Y1195537D02*
Y1190937D01*
G01X140422Y1195537D02*
Y1190937D01*
G01X216499Y191161D02*
Y194700D01*
X216600D01*
Y194756D01*
X216500D01*
G01X188699Y209061D02*
Y212561D01*
G01X180899Y210561D02*
Y214661D01*
G01X188699Y204961D02*
Y200561D01*
G01X180699Y179661D02*
X177399D01*
G01X216499Y181361D02*
X219749D01*
G01X197649Y234661D02*
Y240161D01*
G01X178349Y254661D02*
X173649D01*
G01X201649Y247161D02*
X197649D01*
G01X218449Y276861D02*
X213449D01*
G01X178342Y506855D02*
Y512294D01*
G01X182588Y512878D02*
Y516319D01*
X182600Y516331D01*
G01X196712Y504000D02*
Y508600D01*
G01X191712Y504000D02*
Y508600D01*
G01X208678Y554735D02*
X210263Y553150D01*
Y550725D01*
G01Y546725D02*
Y550725D01*
G01X191763Y585225D02*
X192013Y585475D01*
Y589725D01*
G01X191105Y580723D02*
Y584567D01*
X191763Y585225D01*
G01X192013Y589725D02*
X190247Y591491D01*
X188614D01*
G01X199763Y597475D02*
Y600725D01*
G01X198263Y554735D02*
X205178D01*
G01X192294Y554075D02*
X192954Y554735D01*
X198263D01*
G01X192763Y567825D02*
X197988D01*
X198004Y567809D01*
G01X197163Y571925D02*
X198004Y571084D01*
Y567809D01*
G01X192763Y561825D02*
X200363D01*
G01X205206Y559762D02*
X203143Y561825D01*
X200363D01*
G01X206250Y644000D02*
X210000D01*
G01X216499Y633417D02*
Y636917D01*
G01X185149Y621417D02*
Y617949D01*
G01X216499Y623417D02*
X219749D01*
G01X197649Y687417D02*
Y692917D01*
G01X206250Y650000D02*
X210000D01*
G01X218449Y729617D02*
X213449D01*
G01X178349Y707417D02*
X173649D01*
G01X201649Y699917D02*
X197649D01*
G01X216712Y956555D02*
Y961155D01*
G01X188399Y1110473D02*
Y1113873D01*
G01X216499Y1096673D02*
Y1100173D01*
G01X188399Y1106373D02*
Y1102873D01*
G01X180977Y1094839D02*
X177105D01*
G01X216499Y1086873D02*
X219749D01*
G01X178349Y1160173D02*
X173649D01*
G01X201649Y1152673D02*
X197649D01*
G01X193423Y1140945D02*
X197649Y1145171D01*
Y1145673D01*
G01X218449Y1182373D02*
X213449D01*
G01X235236Y141870D02*
X242649D01*
G01X242421Y180492D02*
X235649D01*
G01X242421Y165492D02*
X235649D01*
G01X224035Y207992D02*
X231149D01*
G01X242421Y195492D02*
X235649D01*
G01X224035Y198543D02*
X231991D01*
G01X224035Y217441D02*
X231149D01*
G01X242421Y235492D02*
X235649D01*
G01X242421Y245492D02*
X235649D01*
G01X242421Y275492D02*
X235649D01*
G01X242421Y265492D02*
X235649D01*
G01X219649Y296161D02*
Y300161D01*
G01X235236Y314114D02*
X242649D01*
G01X235236Y594626D02*
X243051D01*
G01X242421Y648248D02*
X235649D01*
G01X242421Y633248D02*
X235649D01*
G01X242421Y618248D02*
X235649D01*
G01X224035Y670197D02*
X231149D01*
G01X242421Y688248D02*
X235649D01*
G01X224035Y660748D02*
X231149D01*
G01X224035Y651299D02*
X231149D01*
G01X242421Y728248D02*
X235649D01*
G01X242421Y718248D02*
X235649D01*
G01X242421Y698248D02*
X235649D01*
G01X264739Y736218D02*
Y732114D01*
G01X235236Y766870D02*
X242649D01*
G01X219649Y748917D02*
Y752917D01*
G01X221712Y956555D02*
Y961155D01*
G01X242421Y1071004D02*
X235649D01*
G01X235236Y1047382D02*
X242649D01*
G01X224035Y1122953D02*
X231149D01*
G01X224035Y1113504D02*
X231149D01*
G01X224035Y1104055D02*
X231149D01*
G01X242421Y1101004D02*
X235649D01*
G01X242421Y1086004D02*
X235649D01*
G01X242421Y1171004D02*
X235649D01*
G01X242421Y1151004D02*
X235649D01*
G01X235300Y1142700D02*
X236996Y1141004D01*
X242421D01*
G01X235236Y1219626D02*
X242649D01*
G01X242421Y1181004D02*
X235649D01*
G01X219649Y1201673D02*
Y1205673D01*
G01X264594Y1195368D02*
Y1190768D01*
G01X259594Y1195368D02*
Y1190768D01*
G01X313312Y103031D02*
Y98705D01*
G01X315671Y72855D02*
X312355D01*
G01X306955Y68429D02*
X303029D01*
G01X315705Y68379D02*
X312079D01*
G01X314370Y121891D02*
Y118452D01*
G01X312912Y209161D02*
Y211003D01*
X314329Y212420D01*
G01X305112Y210561D02*
Y214661D01*
G01X312912Y205061D02*
Y201661D01*
G01X304912Y179661D02*
X301612D01*
G01X302562Y254661D02*
X297862D01*
G01X266899Y240661D02*
Y237161D01*
G01Y244761D02*
Y248011D01*
G01X302513Y506855D02*
Y512294D01*
G01X288278Y506892D02*
Y512331D01*
G01X292532Y512874D02*
Y516364D01*
X292536Y516368D01*
G01X306759Y512878D02*
Y516319D01*
X306771Y516331D01*
G01X305012Y632417D02*
X301612D01*
G01X266899Y693417D02*
Y689917D01*
G01X312912Y661917D02*
Y665417D01*
G01X305112Y663317D02*
Y667417D01*
G01X312912Y657717D02*
Y654417D01*
G01X277972Y739755D02*
Y744575D01*
G01X302562Y707417D02*
X297862D01*
G01X277968Y724835D02*
Y720535D01*
X277981D01*
Y720485D01*
G01X278020Y714099D02*
Y710397D01*
X278024D01*
G01X266899Y697517D02*
Y700767D01*
G01X312912Y1114773D02*
Y1118273D01*
G01X305112Y1116073D02*
Y1120173D01*
G01X312912Y1110573D02*
Y1106819D01*
X313232Y1106499D01*
G01X304912Y1085173D02*
X301327D01*
G01X266899Y1146173D02*
Y1141173D01*
G01X277930Y1170342D02*
Y1175001D01*
G01X302452Y1165162D02*
Y1160173D01*
X302562D01*
G01X278576Y1158233D02*
Y1161725D01*
X278577D01*
G01X266899Y1150273D02*
X268064D01*
X271165Y1147172D01*
G01X278146Y1186220D02*
Y1182940D01*
G01X278090Y1192724D02*
Y1197271D01*
X278076D01*
Y1197355D01*
G01X363248Y-425196D02*
Y-505196D01*
G01D02*
X1639148D01*
G01X359248Y-409196D02*
G02I-12000J0D01*
G01X354098D02*
G02I-6850J0D01*
G01X347248Y-425196D02*
Y-393196D01*
G01X363248Y-425196D02*
X1639148D01*
G01X363248Y-460696D02*
X1639148D01*
G01X363248Y-409196D02*
X331248D01*
G01X342479Y58745D02*
X346245D01*
G01X338979D02*
X334845D01*
G01X317812Y103781D02*
Y98905D01*
G01X326029Y72845D02*
X322545D01*
G01X326029Y68345D02*
X322500D01*
G01X359449Y141870D02*
X366862D01*
G01X333021Y125405D02*
Y129679D01*
G01X337721Y125405D02*
Y129821D01*
G01X323813Y121872D02*
Y118512D01*
G01X366634Y180492D02*
X359862D01*
G01X366634Y165492D02*
X359862D01*
G01X348248Y207992D02*
X355362D01*
G01X348248Y198543D02*
X355362D01*
G01X366634Y195492D02*
X359862D01*
G01X340712Y191161D02*
Y194661D01*
G01Y181161D02*
X343962D01*
G01X366634Y245492D02*
X359862D01*
G01X348248Y217441D02*
X355362D01*
G01X366634Y235492D02*
X359862D01*
G01X321862Y234661D02*
Y240161D01*
G01X325862Y247161D02*
X321862D01*
G01X366634Y275492D02*
X359862D01*
G01X366634Y265492D02*
X359862D01*
G01X342662Y276861D02*
X337662D01*
G01X343862Y296161D02*
Y300161D01*
G01X359449Y314114D02*
X366862D01*
G01X320925Y504000D02*
Y508600D01*
G01X315925Y504000D02*
Y508600D01*
G01X359449Y594626D02*
X366862D01*
G01X366634Y648248D02*
X359862D01*
G01X366634Y633248D02*
X359862D01*
G01X366634Y618248D02*
X359862D01*
G01X340712Y644017D02*
Y647517D01*
G01Y634017D02*
X343762D01*
X343862Y633917D01*
G01X348248Y670197D02*
X355362D01*
G01X366634Y688248D02*
X359862D01*
G01X348248Y660748D02*
X355362D01*
G01X348248Y651299D02*
X355362D01*
G01X321862Y687417D02*
Y692917D01*
G01X366634Y728248D02*
X359862D01*
G01X366634Y718248D02*
X359862D01*
G01X366634Y698248D02*
X359862D01*
G01X342662Y729617D02*
X337662D01*
G01X325862Y699917D02*
X321862D01*
G01X359449Y766870D02*
X366862D01*
G01X343862Y748917D02*
Y752917D01*
G01X320925Y956755D02*
Y961355D01*
G01X315925Y956755D02*
Y961355D01*
G01X366634Y1071004D02*
X359862D01*
G01X359449Y1047382D02*
X366862D01*
G01X348248Y1122953D02*
X355362D01*
G01X348248Y1113504D02*
X355362D01*
G01X348248Y1104055D02*
X355362D01*
G01X366634Y1101004D02*
X359862D01*
G01X366634Y1086004D02*
X359862D01*
G01X340812Y1096773D02*
Y1100273D01*
G01Y1086773D02*
X344062D01*
G01X366634Y1151004D02*
X359862D01*
G01X366634Y1141004D02*
X359862D01*
G01X321862Y1140173D02*
Y1145673D01*
G01X325862Y1152673D02*
X321862D01*
G01X358518Y1171114D02*
X358628Y1171004D01*
X366634D01*
G01X359449Y1219626D02*
X366862D01*
G01X366634Y1181004D02*
X359862D01*
G01X342662Y1182373D02*
X337662D01*
G01X343862Y1201673D02*
Y1205673D01*
G01X365162Y92420D02*
Y88731D01*
G01Y81220D02*
Y77731D01*
G01X391112Y240661D02*
Y237961D01*
X390312Y237161D01*
G01X391112Y244761D02*
Y247311D01*
X390412Y248011D01*
G01X391112Y693417D02*
Y689917D01*
G01X402129Y739683D02*
Y744503D01*
G01X388796Y736146D02*
Y732042D01*
G01X402125Y724763D02*
Y720463D01*
X402138D01*
Y720413D01*
G01X402177Y714027D02*
Y710325D01*
X402181D01*
G01X391112Y697517D02*
Y700767D01*
G01Y1146173D02*
Y1142673D01*
G01X402156Y1171545D02*
X399474Y1168863D01*
Y1166787D01*
G01X389067Y1166280D02*
X385277D01*
X385210Y1166347D01*
G01X391112Y1150273D02*
Y1153500D01*
G01X402403Y1185011D02*
Y1188312D01*
G01X402261Y1192724D02*
Y1192706D01*
X406037D01*
G01X383849Y1195242D02*
Y1190833D01*
G01X388849Y1195242D02*
Y1191148D01*
G01X437124Y209161D02*
Y212661D01*
G01Y205061D02*
Y201661D01*
G01X429324Y210561D02*
Y214661D01*
G01X429224Y179661D02*
Y176300D01*
G01X450074Y247161D02*
X446074D01*
G01X426774Y254661D02*
X422300D01*
G01X446074Y234661D02*
Y240161D01*
G01X426663Y506818D02*
Y512257D01*
G01X412428Y506855D02*
Y512294D01*
G01X416682Y512837D02*
Y516327D01*
X416686Y516331D01*
G01X430909Y512841D02*
Y516282D01*
X430921Y516294D01*
G01X440138Y504000D02*
Y508600D01*
G01X445138Y504000D02*
Y508600D01*
G01X429224Y632317D02*
X425824D01*
G01X446074Y687417D02*
Y692917D01*
G01X437224Y661917D02*
Y665417D01*
G01Y657817D02*
Y654417D01*
G01X429324Y663317D02*
Y667417D01*
G01X426774Y707417D02*
X422074D01*
G01X450074Y699917D02*
X446074D01*
G01X440138Y956755D02*
Y961355D01*
G01X445138Y956755D02*
Y961355D01*
G01X457173Y1071976D02*
X460673D01*
G01X447173D02*
Y1068726D01*
G01X445573Y1107576D02*
X441976D01*
G01X449924Y1112973D02*
X446627D01*
G01X449924D02*
Y1117073D01*
G01X441738Y1160696D02*
X437104D01*
G01X476319Y144481D02*
X478930Y141870D01*
X483661D01*
G01X500184Y200328D02*
X495348Y195492D01*
X490846D01*
G01X506750Y165324D02*
Y165492D01*
X490846D01*
G01X497785Y178034D02*
X495327Y180492D01*
X490846D01*
G01X478306Y195593D02*
Y197394D01*
X477157Y198543D01*
X472460D01*
G01X480159Y201245D02*
Y206219D01*
X478386Y207992D01*
X472460D01*
G01X461122Y194861D02*
X463005D01*
X464924Y192942D01*
Y191161D01*
G01Y181161D02*
X467192D01*
X468472Y182441D01*
G01X478651Y220734D02*
X475358Y217441D01*
X472460D01*
G01X490846Y235492D02*
X484074D01*
G01X490846Y245492D02*
X484074D01*
G01X490846Y265492D02*
X481174D01*
G01X490846Y275492D02*
X484074D01*
G01X466874Y276861D02*
X461874D01*
G01X468074Y296161D02*
Y300161D01*
G01X483661Y314114D02*
X491074D01*
G01X506746Y506892D02*
Y512331D01*
G01X483661Y594626D02*
X491074D01*
G01X490846Y648248D02*
X484074D01*
G01X490846Y633248D02*
X484074D01*
G01X490846Y618248D02*
X484074D01*
G01X464924Y643917D02*
Y647417D01*
G01Y633917D02*
X468174D01*
G01X472460Y670197D02*
X479574D01*
G01X490846Y688248D02*
X484074D01*
G01X472460Y660748D02*
X479574D01*
G01X472460Y651299D02*
X479574D01*
G01X490846Y728248D02*
X484074D01*
G01X490846Y718248D02*
X484074D01*
G01X490846Y698248D02*
X484074D01*
G01X466874Y729617D02*
X461874D01*
G01X483661Y766870D02*
X491074D01*
G01X468074Y748917D02*
Y752917D01*
G01X490846Y1071004D02*
X484074D01*
G01X483661Y1047382D02*
X491074D01*
G01X472460Y1122953D02*
X465346D01*
G01X472460Y1113504D02*
X479574D01*
G01X472460Y1104055D02*
X479574D01*
G01X490846Y1101004D02*
X484074D01*
G01X490846Y1086004D02*
X484074D01*
G01X504724Y1114573D02*
Y1118073D01*
G01Y1110573D02*
Y1107073D01*
G01X490846Y1171004D02*
X484074D01*
G01X490846Y1151004D02*
X484074D01*
G01X490846Y1141004D02*
X484074D01*
G01X503324Y1141973D02*
X506700D01*
G01X503324Y1145973D02*
X506700D01*
G01X490846Y1181004D02*
X484074D01*
G01X466874Y1182373D02*
X461874D01*
G01X468074Y1201673D02*
Y1205673D01*
G01X476373Y1219498D02*
Y1219626D01*
X483661D01*
G01X508103Y1195157D02*
Y1190557D01*
G01X553537Y214661D02*
Y210661D01*
G01X553337Y179561D02*
Y180493D01*
X546009Y187821D01*
G01X515324Y240661D02*
X518195D01*
X519868Y242334D01*
G01X550987Y254661D02*
Y262810D01*
G01X515324Y244661D02*
Y252511D01*
G01X520981Y506855D02*
Y512294D01*
G01X549279Y513331D02*
Y516581D01*
G01X525579Y538331D02*
Y541531D01*
G01X511000Y512874D02*
Y516364D01*
X511004Y516368D01*
G01X525227Y512878D02*
Y516319D01*
X525239Y516331D01*
G01X553279Y513331D02*
Y516581D01*
G01X534350Y504000D02*
Y508600D01*
G01X539350Y504000D02*
Y508600D01*
G01X533879Y566031D02*
Y561531D01*
G01X524297Y553231D02*
X520579D01*
G01X513517Y576931D02*
X517499D01*
G01X543338Y556719D02*
X548667D01*
X548767Y556819D01*
G01X527145Y564270D02*
Y568697D01*
X527179Y568731D01*
G01X520479Y564713D02*
X522645D01*
X523088Y564270D01*
X527145D01*
G01X543338Y553219D02*
X536979D01*
G01X530297Y553231D02*
X530309Y553219D01*
X536979D01*
G01X529145Y558670D02*
Y554383D01*
X530297Y553231D01*
G01X513517Y567931D02*
Y557887D01*
X513729Y557675D01*
G01X520479Y558713D02*
X519441Y557675D01*
X513729D01*
G01X525145Y558670D02*
X525102Y558713D01*
X520479D01*
G01X553437Y632317D02*
X549937D01*
G01X515324Y693417D02*
Y689917D01*
G01X553537Y667417D02*
Y663417D01*
G01X526225Y739936D02*
Y744756D01*
G01X550987Y707417D02*
X546287D01*
G01X512892Y736399D02*
Y732295D01*
G01X526221Y725016D02*
Y720716D01*
X526234D01*
Y720666D01*
G01X526273Y714280D02*
Y710578D01*
X526277D01*
G01X515324Y697417D02*
Y700667D01*
G01X553537Y1120173D02*
Y1116173D01*
G01X553437Y1085173D02*
X549773D01*
G01X550987Y1160173D02*
X546287D01*
G01X534874Y1145973D02*
Y1139774D01*
G01X526523Y1172616D02*
Y1177122D01*
G01X526501Y1163084D02*
Y1166546D01*
G01X531674Y1152773D02*
X535320D01*
Y1152771D01*
G01X526388Y1192682D02*
Y1197747D01*
G01X526367Y1186666D02*
Y1183111D01*
G01X513103Y1195157D02*
Y1190557D01*
G01X615059Y195492D02*
X605288D01*
X604517Y196263D01*
G01X596673Y207992D02*
X603787D01*
G01X603697Y182091D02*
X605296Y180492D01*
X615059D01*
G01X589137Y191161D02*
Y194470D01*
X586719Y196888D01*
G01X604517Y196263D02*
X602237Y198543D01*
X596673D01*
G01X561437Y209161D02*
Y213416D01*
X563000Y214979D01*
Y217600D01*
G01X561437Y204861D02*
Y197249D01*
G01X589137Y181361D02*
X591252Y183476D01*
X596741D01*
X598236Y181981D01*
G01X588188Y216520D02*
X589109Y217441D01*
X596673D01*
G01X570287Y234661D02*
Y240161D01*
G01X574287Y247161D02*
X569735D01*
X569009Y247887D01*
G01X592287Y296161D02*
Y300161D01*
G01X591087Y276861D02*
X582758D01*
G01X569529Y506627D02*
Y502127D01*
G01X563279Y511531D02*
Y506731D01*
G01X557279Y516581D02*
Y513331D01*
G01X568779Y516581D02*
Y512831D01*
G01X575779Y516581D02*
Y512831D01*
G01X580279D02*
Y516581D01*
G01X557279Y567081D02*
Y570331D01*
G01X602779Y552331D02*
X599029D01*
G01X589137Y643917D02*
Y647417D01*
G01Y634017D02*
X592387D01*
G01X596673Y670197D02*
X603787D01*
G01X596673Y660748D02*
X603787D01*
G01X596673Y651299D02*
X603787D01*
G01X570287Y687417D02*
Y692917D01*
G01X561437Y661917D02*
Y665417D01*
G01Y657717D02*
Y654417D01*
G01X591087Y729617D02*
X586087D01*
G01X574287Y699917D02*
X570287D01*
G01X592287Y748917D02*
Y752917D01*
G01X569350Y956755D02*
Y961355D01*
G01X564350Y956755D02*
Y961355D01*
G01X596673Y1122953D02*
X603787D01*
G01X596673Y1113504D02*
X603787D01*
G01X596673Y1104055D02*
X603787D01*
G01X589137Y1096673D02*
Y1100173D01*
G01X561337Y1114673D02*
Y1120873D01*
G01Y1110473D02*
Y1107173D01*
G01X589137Y1086873D02*
X592387D01*
G01X570287Y1140173D02*
Y1145673D01*
G01X574287Y1152673D02*
X570287D01*
G01X591087Y1182373D02*
X586087D01*
G01X592287Y1201673D02*
Y1205673D01*
G01X625147Y107633D02*
X629024D01*
G01X615151Y112329D02*
X619171D01*
G01X614967Y134777D02*
X613816D01*
X607874Y140719D01*
Y141870D01*
G01X606718Y168580D02*
X609806Y165492D01*
X615059D01*
G01Y235492D02*
X608287D01*
G01X615059Y245492D02*
X608287D01*
G01X639537Y240661D02*
Y237161D01*
G01Y244761D02*
Y248011D01*
G01X607961Y263934D02*
X609519Y265492D01*
X615059D01*
G01Y275492D02*
X608287D01*
G01X607874Y314114D02*
X615287D01*
G01X620153Y506555D02*
Y511994D01*
G01X634388Y506518D02*
Y511957D01*
G01X615100Y516850D02*
Y513287D01*
G01X624407Y512537D02*
Y516027D01*
X624411Y516031D01*
G01X638634Y512541D02*
Y515982D01*
X638646Y515994D01*
G01X607460Y550274D02*
X608810Y551624D01*
X611910D01*
G01D02*
X615119D01*
Y551586D01*
G01X619560Y547201D02*
Y555174D01*
G01X652663Y512000D02*
Y516600D01*
G01X647663Y512000D02*
Y516600D01*
G01X607874Y594626D02*
X615287D01*
G01X607460Y566774D02*
X608210Y566024D01*
X611910D01*
G01D02*
X615147D01*
Y565956D01*
G01X619560Y562574D02*
X623236D01*
G01X615059Y648248D02*
X608287D01*
G01X615059Y633248D02*
X608287D01*
G01X615059Y618248D02*
X608287D01*
G01X615059Y688248D02*
X608287D01*
G01X639537Y693417D02*
Y689917D01*
G01X650659Y739853D02*
Y744673D01*
G01X615059Y728248D02*
X608287D01*
G01X615059Y718248D02*
X608287D01*
G01X615059Y698248D02*
X608287D01*
G01X637326Y736316D02*
Y732212D01*
G01X650655Y724933D02*
Y720633D01*
X650668D01*
Y720583D01*
G01X650707Y714197D02*
Y710495D01*
X650711D01*
G01X639537Y697517D02*
Y700767D01*
G01X607874Y766870D02*
X615287D01*
G01X615059Y1071004D02*
X608287D01*
G01X607874Y1047382D02*
X615287D01*
G01X615059Y1101004D02*
X608287D01*
G01X615059Y1086004D02*
X608287D01*
G01X615059Y1171004D02*
X608287D01*
G01X615059Y1151004D02*
X608287D01*
G01X615059Y1141004D02*
X608287D01*
G01X639537Y1146173D02*
X643000D01*
G01X651216Y1160810D02*
Y1164051D01*
G01D02*
Y1169132D01*
X650739Y1169609D01*
Y1172409D01*
G01X639537Y1150273D02*
Y1153523D01*
G01X615059Y1181004D02*
X608287D01*
G01X650644Y1192640D02*
Y1197038D01*
G01X650626Y1186007D02*
Y1182447D01*
G01X615238Y1218951D02*
X614563Y1219626D01*
X607874D01*
G01X632316Y1195074D02*
Y1190474D01*
G01X637316Y1195074D02*
Y1190474D01*
G01X694307Y107247D02*
X697457D01*
G01X694067Y112738D02*
X696245D01*
X697483Y111500D01*
G01X661965Y106177D02*
X662257Y106469D01*
X666142D01*
G01X690567Y112738D02*
Y112569D01*
X687566Y109568D01*
G01X685550Y209261D02*
Y212686D01*
X685545D01*
Y212806D01*
G01X677750Y210561D02*
Y214661D01*
G01X677550Y179561D02*
Y185569D01*
X677450Y185669D01*
G01X685550Y205161D02*
Y199793D01*
X685250Y199493D01*
G01X689426Y236628D02*
X692959Y240161D01*
X694500D01*
G01X698500Y247161D02*
X694500D01*
G01X675200Y254661D02*
X670500D01*
G01X696787Y584645D02*
Y580633D01*
G01X682000Y631917D02*
Y628449D01*
G01X694500Y687417D02*
Y692917D01*
G01X685550Y662017D02*
Y665417D01*
G01Y657917D02*
Y654417D01*
G01X675200Y707417D02*
X670500D01*
G01X698500Y699917D02*
X694500D01*
G01X688563Y956755D02*
Y961355D01*
G01X693563Y956755D02*
Y961355D01*
G01X685250Y1110373D02*
Y1113673D01*
G01Y1106273D02*
Y1102873D01*
G01X677150Y1093100D02*
Y1096050D01*
X674700Y1098500D01*
G01X694500Y1140173D02*
Y1145673D01*
G01X675200Y1160173D02*
X667700D01*
G01X698500Y1152673D02*
X692745D01*
X692671Y1152747D01*
G01X720748Y-425196D02*
Y-505196D01*
G01X724645Y138941D02*
X727574Y141870D01*
X732087D01*
G01X732100Y198373D02*
X734981Y195492D01*
X739272D01*
G01Y165492D02*
X732500D01*
G01X739272Y180492D02*
X732500D01*
G01X720886Y198543D02*
X728000D01*
G01X720886Y207992D02*
X728000D01*
G01X713350Y191161D02*
Y194661D01*
G01Y181161D02*
X716600D01*
G01X731048Y238563D02*
X734119Y235492D01*
X739272D01*
G01Y245492D02*
X732500D01*
G01X720886Y217441D02*
X728000D01*
G01X739272Y265492D02*
X732500D01*
G01X739272Y275492D02*
X732500D01*
G01X738361Y306612D02*
X732087Y312886D01*
Y314114D01*
G01X715300Y276861D02*
X710300D01*
G01X716500Y296161D02*
Y300161D01*
G01X732087Y594626D02*
X739500D01*
G01X739272Y648248D02*
X732500D01*
G01X739272Y633248D02*
X732500D01*
G01X739272Y618248D02*
X732500D01*
G01X713350Y643917D02*
Y647417D01*
G01Y633917D02*
X716600D01*
G01X720886Y670197D02*
X728000D01*
G01X739272Y688248D02*
X732500D01*
G01X720886Y660748D02*
X728000D01*
G01X720886Y651299D02*
X728000D01*
G01X739272Y728248D02*
X732500D01*
G01X739272Y718248D02*
X732500D01*
G01X739272Y698248D02*
X732500D01*
G01X715300Y729617D02*
X710300D01*
G01X732087Y766870D02*
X739500D01*
G01X716500Y748917D02*
Y752917D01*
G01X739272Y1071004D02*
X732500D01*
G01X732087Y1047382D02*
X739500D01*
G01X720886Y1122953D02*
X728000D01*
G01X720886Y1113504D02*
X728000D01*
G01X720886Y1104055D02*
X728000D01*
G01X739272Y1101004D02*
X732500D01*
G01X739272Y1086004D02*
X732500D01*
G01X713350Y1096673D02*
Y1100173D01*
G01Y1086673D02*
X716600D01*
G01X739272Y1171004D02*
X732500D01*
G01X739272Y1151004D02*
X732500D01*
G01X739272Y1141004D02*
X732500D01*
G01X732087Y1219626D02*
X739500D01*
G01X739272Y1181004D02*
X732500D01*
G01X715300Y1182373D02*
X710300D01*
G01X716500Y1201673D02*
Y1205673D01*
G01X794488Y11615D02*
X789045D01*
G01X752950Y209600D02*
Y213450D01*
G01Y205500D02*
X762541D01*
X767405Y210364D01*
G01X751750Y681800D02*
Y685300D01*
G01Y677700D02*
X755000D01*
G01X752500Y1140250D02*
X756250D01*
G01X752500Y1151750D02*
X756250D01*
G01X854625Y1518750D02*
X841427D01*
X839414Y1520763D01*
G01X858248Y-425196D02*
Y-505196D01*
G01X885040Y11615D02*
Y20378D01*
X885046Y20384D01*
G01X881750Y41500D02*
Y37397D01*
G01X874800Y359100D02*
Y355798D01*
G01X874807Y378495D02*
Y375193D01*
G01X874693Y464505D02*
X872403D01*
X871487Y463589D01*
G01X878500Y476000D02*
X874750Y472250D01*
Y471100D01*
G01X875893Y542405D02*
X860092D01*
G01X870163Y840303D02*
Y836153D01*
G01X865663Y838553D02*
Y834403D01*
G01X871013Y818831D02*
X867663D01*
G01X877673Y865153D02*
Y868873D01*
G01X881448Y1358557D02*
X885301D01*
G01X881420Y1350438D02*
X884746D01*
G01X876956Y1369300D02*
X874408D01*
X873495Y1370213D01*
G01X881256Y1370950D02*
X885200D01*
X885300Y1371050D01*
G01X876740Y1350464D02*
X872164D01*
G01X873259Y1365805D02*
Y1365800D01*
X876956D01*
G01D02*
X880406D01*
X881256Y1364950D01*
G01D02*
X881356Y1365050D01*
X887412D01*
G01X872122Y1358528D02*
Y1354823D01*
X872181Y1354764D01*
G01X876748Y1358557D02*
X876719Y1358528D01*
X872122D01*
G01X882445Y1411047D02*
X882562Y1411164D01*
X886792D01*
G01X877445Y1411047D02*
X882445D01*
G01X873918Y1411149D02*
X874020Y1411047D01*
X877445D01*
G01X886500Y1435750D02*
Y1432500D01*
G01X877500Y1435750D02*
Y1432600D01*
X877300Y1432400D01*
G01X882000Y1435750D02*
Y1432600D01*
G01X868500Y1435750D02*
Y1434900D01*
X870921Y1432479D01*
Y1432300D01*
G01D02*
X873000Y1434379D01*
Y1435750D01*
G01X893050Y1486050D02*
Y1489500D01*
G01X893158Y1516542D02*
X896365D01*
G01X869913Y1487165D02*
X868600Y1485852D01*
Y1482760D01*
G01D02*
Y1478973D01*
X868791Y1478782D01*
G01X876514Y1514948D02*
Y1519164D01*
X871958Y1523720D01*
G01X863851Y1501681D02*
X861602D01*
X861171Y1501250D01*
X860000D01*
G01X888600Y1486000D02*
Y1489236D01*
X889002Y1489638D01*
G01X851354Y1538590D02*
X852323D01*
X855092Y1535821D01*
G01X882500Y1522868D02*
X884650Y1520718D01*
X892682D01*
G01X864583Y1537187D02*
Y1542168D01*
X866621Y1544206D01*
G01X896335Y1528458D02*
X892558D01*
G01X892700Y1539918D02*
Y1543900D01*
G01X899288Y1539560D02*
X893058D01*
X892700Y1539918D01*
G01X882500Y1531868D02*
X884100D01*
X886250Y1534018D01*
X888390D01*
G01X892700Y1533918D02*
X892600Y1534018D01*
X888390D01*
G01X897288Y1533960D02*
X892742D01*
X892700Y1533918D01*
G01X928600Y-115200D02*
X938048D01*
X938091Y-115157D01*
G01X919100Y908950D02*
Y905253D01*
X914876Y901029D01*
G01X926185Y928342D02*
X926290D01*
X929232Y925400D01*
G01X924974Y933041D02*
X928383D01*
X933524Y927900D01*
G01X937031Y912047D02*
Y914734D01*
X937621Y915324D01*
G01X917100Y978450D02*
Y973527D01*
X919759Y970868D01*
G01X927861Y962957D02*
X927766Y963052D01*
X924670D01*
X924563Y962945D01*
G01X919759Y970868D02*
X916500Y967609D01*
Y962850D01*
G01X945790Y953912D02*
X943679D01*
X941868Y952101D01*
G01X935328Y995820D02*
X941640D01*
G01X938009Y991763D02*
Y987330D01*
G01X943500Y1008950D02*
Y1008172D01*
X945373Y1006299D01*
X946138D01*
G01X916769Y1032189D02*
Y1032324D01*
X916446Y1032647D01*
Y1035438D01*
G01X925053Y1032135D02*
Y1033753D01*
X927272Y1035972D01*
X929257D01*
Y1035883D01*
G01X943500Y1008950D02*
X940750D01*
X939000Y1007200D01*
G01X928384Y1349832D02*
Y1346435D01*
G01X928439Y1363564D02*
Y1360167D01*
G01X932559Y1363534D02*
Y1360137D01*
G01X932564Y1349862D02*
Y1346100D01*
G01X942879Y1365307D02*
Y1368964D01*
X942925Y1369010D01*
G01D02*
Y1372907D01*
G01X936959Y1363540D02*
Y1360143D01*
G01X936964Y1349862D02*
X938945D01*
X947306Y1358223D01*
X955723D01*
X1028937Y1431437D01*
X1117137D01*
X1122900Y1437200D01*
X1147200D01*
X1151569Y1432831D01*
Y1362799D01*
X1188052Y1326316D01*
Y1097227D01*
X1170140Y1079315D01*
Y1043939D01*
G01X928194Y1376598D02*
Y1379995D01*
G01X932294Y1376598D02*
Y1379995D01*
G01X936994Y1376598D02*
Y1379895D01*
G01X918500Y1499700D02*
Y1502950D01*
G01X932500Y1497900D02*
Y1493200D01*
G01X926500Y1502950D02*
Y1499700D01*
G01X938000Y1502950D02*
Y1499200D01*
G01X942000Y1502950D02*
Y1499500D01*
G01X922500Y1499700D02*
Y1502950D01*
G01X915082Y1534500D02*
X918800D01*
G01X914796Y1530405D02*
X918505D01*
G01X905900Y1539500D02*
Y1543600D01*
X906000Y1543700D01*
G01X941000Y1560450D02*
Y1564200D01*
G01X937000Y1560450D02*
Y1564200D01*
G01X926500Y1553450D02*
Y1556700D01*
G01X931500Y1560450D02*
Y1564200D01*
G01X911900Y1539500D02*
Y1542850D01*
X913250Y1544200D01*
G01X916250Y1539200D02*
X912200D01*
X911900Y1539500D01*
G01X913250Y1544200D02*
Y1547700D01*
G01X901288Y1533960D02*
X901828Y1534500D01*
X904900D01*
G01D02*
X909082D01*
G01D02*
X911296Y1532286D01*
Y1530405D01*
G01X973248Y-425196D02*
Y-505196D01*
G01X971713Y-122342D02*
Y-115570D01*
G01X986713Y-122342D02*
Y-115570D01*
G01X966000Y908250D02*
X961500D01*
G01D02*
Y906400D01*
X962900Y905000D01*
G01X944776Y935000D02*
X948845D01*
G01D02*
X952602D01*
X953967Y933635D01*
G01X959400Y957150D02*
Y960300D01*
G01X959500Y979250D02*
Y977825D01*
X961134Y976191D01*
G01X950500Y979250D02*
Y976213D01*
X948942Y974655D01*
G01X955700Y1027550D02*
Y1030700D01*
G01X987970Y1008007D02*
Y1004157D01*
G01X972140Y1153500D02*
Y1148070D01*
X982722Y1137488D01*
X994923D01*
G01X973055Y1183003D02*
X976797D01*
X977500Y1182300D01*
G01X947125Y1372907D02*
Y1369010D01*
G01D02*
X947159Y1368976D01*
Y1365337D01*
G01X951525Y1372907D02*
Y1369107D01*
G01X951872Y1365352D02*
Y1365372D01*
X955500Y1369000D01*
G01X951813Y1495424D02*
X951815D01*
Y1491459D01*
G01X988573Y1506462D02*
Y1502974D01*
X988624Y1502923D01*
G01X946300Y1502950D02*
Y1499300D01*
G01X950300Y1502950D02*
Y1499500D01*
G01X975813Y1556916D02*
X972413D01*
G01D02*
X969563Y1559766D01*
X967813D01*
G01X953500Y1559200D02*
Y1563200D01*
G01X962000Y1560450D02*
Y1564200D01*
G01X958000Y1560450D02*
Y1564200D01*
G01X949000Y1560450D02*
Y1564200D01*
G01X945000Y1560450D02*
Y1564200D01*
G01X968001Y1533926D02*
X972001D01*
G01X967813Y1543166D02*
X968708Y1542271D01*
X972158D01*
G01D02*
Y1542266D01*
G01X975813Y1545916D02*
X972413D01*
G01D02*
Y1542526D01*
X972158Y1542271D01*
G01X962001Y1533926D02*
X956597D01*
G01X964782Y1538282D02*
X962001Y1535501D01*
Y1533926D01*
G01X979963Y1545689D02*
Y1542687D01*
X975202Y1537926D01*
X968638D01*
X968282Y1538282D01*
G01X979963Y1549366D02*
Y1545689D01*
G01Y1553466D02*
Y1549366D01*
G01X1004213Y-103956D02*
Y-95837D01*
G01X1036713Y-122342D02*
Y-115500D01*
G01X1015582Y-66200D02*
Y-69800D01*
G01X1035000Y-66800D02*
X1034462Y-67338D01*
Y-70708D01*
G01X1022618Y-40100D02*
Y-36900D01*
G01X1032053Y-38525D02*
Y-34953D01*
G01X1038712Y-38508D02*
Y-34812D01*
G01X1007582Y-43500D02*
Y-39418D01*
G01X1004100Y-73482D02*
X1001018D01*
X1000300Y-74200D01*
G01X1032053Y-42025D02*
Y-45953D01*
X1032080Y-45980D01*
G01X1014150Y63600D02*
X1017600D01*
G01X1014150Y58900D02*
X1017600D01*
G01X1014150Y54200D02*
X1017600D01*
G01X1094200Y-38400D02*
X1050209Y5591D01*
Y256250D01*
X1024406Y282053D01*
Y783606D01*
X1083633Y842833D01*
Y864110D01*
G01X1014922Y545207D02*
X1018322D01*
G01X1014900Y550000D02*
X1018300D01*
G01X1035973Y823995D02*
Y808773D01*
X1014856Y787656D01*
Y554532D01*
G01X1032480Y834829D02*
X1028472D01*
G01X1031563Y856603D02*
Y852453D01*
G01X1027063Y854853D02*
Y850703D01*
G01X1039100Y904950D02*
X1043900D01*
G01X1009950Y939000D02*
Y936250D01*
X1008700Y935000D01*
G01D02*
Y931550D01*
X1009750Y930500D01*
G01X997694Y978090D02*
Y974940D01*
G01X1011194Y978090D02*
Y977170D01*
X1013713Y974651D01*
G01X1014891Y943357D02*
X1013322D01*
X1009950Y939985D01*
Y939000D01*
G01X992994Y1009590D02*
Y1005740D01*
G01X1012494Y1030690D02*
Y1033840D01*
G01X1017194Y1030690D02*
Y1033840D01*
G01X1007849Y1027093D02*
Y1024309D01*
X1007372Y1023832D01*
G01X1037000Y1070250D02*
Y1067100D01*
G01X1032500Y1070250D02*
Y1067100D01*
G01X1031400Y1121550D02*
Y1124700D01*
G01X1017000Y1099000D02*
Y1093950D01*
G01X1021200Y1100850D02*
Y1094300D01*
G01X1035900Y1121550D02*
Y1124700D01*
G01X1013400Y1140750D02*
Y1137500D01*
G01X999700Y1140750D02*
X1004300D01*
G01X1021991Y1141526D02*
X1022000Y1141535D01*
Y1145500D01*
X1014500Y1153000D01*
Y1154500D01*
G01X1004300Y1140750D02*
Y1137994D01*
X1004294Y1137988D01*
Y1137600D01*
G01X995000Y1140750D02*
Y1137565D01*
X994923Y1137488D01*
G01X999500Y1184250D02*
Y1174500D01*
G01X1008700Y1140750D02*
Y1137500D01*
G01X1017800Y1140750D02*
Y1137500D01*
G01X999500Y1187750D02*
Y1190500D01*
X997500Y1192500D01*
G01X1004500Y1187750D02*
Y1188900D01*
X1006800Y1191200D01*
G01X995948Y1184250D02*
X999500D01*
G01X1029479Y1324216D02*
X1025335D01*
G01X1034624Y1354526D02*
X1031474D01*
G01X1034603Y1349992D02*
X1031508D01*
X1031000Y1350500D01*
G01X1029479Y1337616D02*
X1025335D01*
G01X1029479Y1330916D02*
X1025335D01*
G01X1029579Y1342668D02*
X1026736D01*
X1025284Y1341216D01*
G01X1076713Y-122342D02*
Y-115570D01*
G01X1046713Y-122342D02*
Y-115570D01*
G01X1074400Y-77118D02*
Y-81000D01*
G01X1065621Y-80978D02*
Y-85082D01*
G01X1065571Y-76578D02*
X1066600Y-75549D01*
Y-72800D01*
G01X1085818Y-87500D02*
Y-90182D01*
X1085300Y-90700D01*
G01X1074400Y-42282D02*
Y-39100D01*
G01X1087700Y-42200D02*
Y-37886D01*
G01X1042308Y-75936D02*
X1045800D01*
G01X1058333Y-72770D02*
Y-73867D01*
X1057783Y-74417D01*
Y-76247D01*
G01X1061325Y-43950D02*
Y-40378D01*
G01X1054625Y-43700D02*
Y-40278D01*
G01X1042308Y-71536D02*
Y-68292D01*
X1043000Y-67600D01*
G01X1043112Y-38558D02*
Y-34912D01*
G01X1066225Y-43950D02*
Y-40278D01*
G01X1054625Y-47200D02*
Y-51090D01*
X1054593Y-51122D01*
G01X1085800Y-60300D02*
Y-57100D01*
G01X1087700Y-51200D02*
X1090300Y-48600D01*
X1094200D01*
G01X1066168Y22405D02*
X1054800D01*
G01X1062854Y79465D02*
Y83434D01*
G01X1046251Y434409D02*
X1042833D01*
G01X1046250Y442000D02*
X1042800D01*
G01X1046465Y557053D02*
Y559890D01*
X1045106Y561249D01*
G01X1083633Y864110D02*
Y902332D01*
G01X1053200Y904950D02*
Y901703D01*
G01X1043900Y904950D02*
Y901568D01*
X1043882D01*
G01X1083633Y932172D02*
Y902332D01*
G01X1082500Y1070250D02*
Y1067100D01*
G01X1073500Y1070250D02*
Y1067100D01*
G01X1069000Y1070250D02*
Y1067100D01*
G01X1064500Y1100000D02*
Y1096150D01*
G01X1087700Y1122650D02*
Y1125800D01*
G01X1068700Y1101850D02*
Y1096600D01*
G01Y1105350D02*
Y1108700D01*
G01X1083355Y1119253D02*
Y1116103D01*
G01X1070155Y1119253D02*
Y1116103D01*
G01X1086457Y1561743D02*
X1090064D01*
G01X1117535Y-115157D02*
X1110335D01*
G01X1113371Y-80838D02*
X1115000Y-79209D01*
Y-77500D01*
G01X1097600Y-82462D02*
X1100829D01*
G01X1113371Y-85538D02*
X1116600D01*
G01X1100929Y-86862D02*
Y-90371D01*
G01X1114400Y-55662D02*
X1110838D01*
G01X1113300Y-48400D02*
Y-44100D01*
G01X1100800Y-42800D02*
X1100600Y-42600D01*
X1094200D01*
G01D02*
Y-38400D01*
G01X1107338Y-55662D02*
X1107362Y-55686D01*
Y-59500D01*
G01X1107300Y-48400D02*
X1107338Y-48438D01*
Y-55662D01*
G01X1102800Y-48400D02*
X1107300D01*
G01X1107362Y-59500D02*
Y-61262D01*
G01X1098800Y-48400D02*
Y-52800D01*
X1098000Y-53600D01*
X1096500D01*
G01D02*
X1095000D01*
X1094200Y-52800D01*
Y-48600D01*
G01X1096500Y-53600D02*
Y-53500D01*
G01X1119700Y1070350D02*
Y1067200D01*
G01X1124500Y1070350D02*
Y1067200D01*
G01X1128900Y1070350D02*
Y1067200D01*
G01X1107100Y1099900D02*
Y1096050D01*
G01X1111600Y1101650D02*
Y1097800D01*
G01X1124100Y1121950D02*
Y1125100D01*
G01X1128800Y1121950D02*
Y1125100D01*
G01X1092200Y1122650D02*
Y1125800D01*
G01X1180299Y101360D02*
X1184088D01*
G01X1180452Y96794D02*
X1184141D01*
G01X1182590Y257688D02*
Y254388D01*
G01X1174037Y281343D02*
X1178015D01*
G01X1185000D02*
X1181515D01*
G01X1176100Y266250D02*
Y270603D01*
G01Y274150D02*
Y270603D01*
G01X1176300Y292650D02*
Y288600D01*
G01X1176835Y614682D02*
Y618934D01*
G01X1176500Y1116750D02*
X1174187D01*
X1172564Y1118373D01*
G01X1228942Y225125D02*
X1224875D01*
X1224800Y225200D01*
G01X1221460Y236291D02*
Y238103D01*
X1219917Y239646D01*
G01X1186600Y253200D02*
Y257178D01*
X1186090Y257688D01*
G01X1215547Y253265D02*
Y246355D01*
G01D02*
Y235553D01*
X1220358Y230742D01*
X1223275D01*
G01X1194600Y284750D02*
Y288237D01*
G01Y292650D02*
Y288237D01*
G01X1236347Y959442D02*
Y954047D01*
X1232700Y950400D01*
G01X1197879Y1033731D02*
Y1035321D01*
X1195300Y1037900D01*
X1194000D01*
G01X1197879Y1029031D02*
Y1033731D01*
G01X1229697Y1145325D02*
Y1148580D01*
X1229691D01*
G01D02*
X1229720Y1148609D01*
Y1153391D01*
G01X1216205Y1156194D02*
X1211205D01*
G01D02*
X1202914D01*
X1198130Y1151410D01*
G01X1271648Y-425196D02*
Y-505196D01*
G01X1289000Y145400D02*
X1285470Y141870D01*
X1281693D01*
G01X1280800Y167200D02*
X1282508Y165492D01*
X1288878D01*
G01X1281603Y203340D02*
X1276806Y198543D01*
X1270492D01*
G01X1278421Y205974D02*
X1276403Y207992D01*
X1270492D01*
G01X1282287Y243489D02*
X1284290Y245492D01*
X1288878D01*
G01X1277606Y217441D02*
X1270492D01*
G01X1253250Y240661D02*
X1250150D01*
X1248193Y242618D01*
G01X1250410Y236459D02*
X1247159D01*
G01X1255600Y237300D02*
X1254759Y236459D01*
X1250410D01*
G01X1253250Y244861D02*
X1252172D01*
X1250016Y247017D01*
G01X1288878Y265492D02*
X1274992D01*
X1273200Y263700D01*
G01X1288878Y275492D02*
X1278108D01*
X1276200Y277400D01*
G01X1289000Y309500D02*
X1284386Y314114D01*
X1281693D01*
G01X1250011Y516707D02*
Y513463D01*
G01X1235883Y506901D02*
X1235874Y506910D01*
Y513432D01*
G01D02*
Y517372D01*
X1235796Y517450D01*
G01X1250011Y513463D02*
X1249992Y513444D01*
Y506900D01*
G01X1269878Y504421D02*
X1264878D01*
G01D02*
Y508068D01*
G01X1281693Y594626D02*
X1289106D01*
G01X1270492Y670197D02*
X1277606D01*
G01X1270492Y660748D02*
X1277606D01*
G01X1270492Y651299D02*
X1277606D01*
G01X1251250Y693417D02*
Y692150D01*
X1253800Y689600D01*
G01X1258250Y697850D02*
X1264158D01*
X1265891Y699583D01*
G01X1281693Y766870D02*
X1289106D01*
G01X1250475Y969248D02*
Y966004D01*
G01D02*
X1250456Y965985D01*
Y959441D01*
G01X1236326Y965973D02*
Y959463D01*
X1236347Y959442D01*
G01X1284695Y956586D02*
X1268742D01*
G01D02*
X1263742D01*
G01X1279081Y1071085D02*
X1279162Y1071004D01*
X1288878D01*
G01X1289114Y1048624D02*
X1287872Y1047382D01*
X1281693D01*
G01X1270492Y1122953D02*
X1277606D01*
G01X1270492Y1113504D02*
X1277606D01*
G01X1270492Y1104055D02*
X1277606D01*
G01X1251250Y1146173D02*
Y1141700D01*
G01X1243820Y1153364D02*
X1247164D01*
X1249600Y1155800D01*
G01X1243814Y1145413D02*
Y1146825D01*
X1245144Y1148155D01*
X1246557D01*
G01X1258250Y1150173D02*
X1268948D01*
G01X1281693Y1219626D02*
X1289106D01*
G01X1320055Y71679D02*
Y68000D01*
G01X1323521Y82705D02*
Y79179D01*
G01X1312999Y111125D02*
Y107280D01*
G01X1304563Y87508D02*
Y84309D01*
G01X1299569Y87441D02*
Y84272D01*
G01X1317655Y112801D02*
Y107896D01*
X1317661D01*
G01X1318821Y82705D02*
Y79079D01*
X1319100Y78800D01*
G01D02*
Y76134D01*
X1320055Y75179D01*
G01X1327921Y82705D02*
Y78900D01*
G01X1310571Y86155D02*
Y90855D01*
G01D02*
Y91056D01*
X1308228Y93399D01*
G01X1312000Y165911D02*
X1314794Y163117D01*
Y162944D01*
G01X1324207Y130353D02*
Y127040D01*
X1324134Y126967D01*
G01X1315115Y130350D02*
Y126970D01*
X1315118Y126967D01*
G01X1288878Y180492D02*
X1282106D01*
G01X1288878Y195492D02*
X1297507D01*
G01X1307500Y165911D02*
Y165909D01*
X1304293D01*
G01X1311750Y195261D02*
X1313655D01*
X1315838Y193078D01*
Y188804D01*
G01X1326400Y178311D02*
X1327645D01*
X1330807Y181473D01*
G01X1311750Y191161D02*
Y187911D01*
G01X1288878Y235492D02*
X1282106D01*
G01X1298500Y295661D02*
Y302900D01*
G01X1313000Y294961D02*
Y302900D01*
G01X1305000Y299400D02*
Y294961D01*
G01X1313915Y263541D02*
X1312795Y264661D01*
X1308500D01*
G01X1298500Y266161D02*
Y271100D01*
X1298700Y271300D01*
Y272800D01*
G01X1288878Y648248D02*
X1282106D01*
G01X1288878Y633248D02*
X1282106D01*
G01X1311750Y648017D02*
X1315400D01*
G01X1307500Y618667D02*
Y615417D01*
G01X1288878Y618248D02*
X1282106D01*
G01X1326500Y631067D02*
Y627917D01*
G01X1311750Y643917D02*
Y640667D01*
G01X1312000Y618667D02*
Y615417D01*
G01X1288878Y688248D02*
X1282106D01*
G01X1302500Y718917D02*
X1298500D01*
G01X1308500Y717417D02*
X1314000D01*
G01X1288878Y728248D02*
X1282106D01*
G01X1288878Y718248D02*
X1282106D01*
G01X1288878Y698248D02*
X1282106D01*
G01X1313000Y747717D02*
Y752417D01*
G01X1305000Y747717D02*
Y752417D01*
G01X1298500Y748417D02*
Y752417D01*
G01X1305100Y1071423D02*
Y1068173D01*
G01X1326500Y1083823D02*
Y1080673D01*
G01X1309600Y1071423D02*
Y1068173D01*
G01X1288878Y1101004D02*
X1282106D01*
G01X1288878Y1086004D02*
X1282106D01*
G01X1311750Y1100773D02*
X1315300D01*
G01X1311750Y1096673D02*
Y1093423D01*
G01X1302500Y1171673D02*
X1298500D01*
G01X1288878Y1171004D02*
X1282106D01*
G01X1288878Y1151004D02*
X1282106D01*
G01X1288878Y1141004D02*
X1282106D01*
G01X1313950Y1165990D02*
X1309767Y1170173D01*
X1308500D01*
G01X1305000Y1200473D02*
Y1205173D01*
G01X1313000Y1200473D02*
Y1205173D01*
G01X1288878Y1181004D02*
X1282106D01*
G01X1298500Y1201173D02*
Y1204443D01*
X1300065Y1206008D01*
G01X1354437Y84988D02*
Y86863D01*
X1351201Y90099D01*
G01X1332934Y133838D02*
Y137712D01*
G01X1342253Y133842D02*
X1342249Y133838D01*
X1337634D01*
G01D02*
Y136403D01*
X1337662D01*
Y137188D01*
G01X1377463Y240661D02*
Y237100D01*
G01X1346363Y516578D02*
Y513334D01*
G01D02*
X1346344Y513315D01*
Y506771D01*
G01X1332235Y513294D02*
Y517234D01*
X1332148Y517321D01*
G01X1332235Y513294D02*
X1332226Y513303D01*
G01X1332235Y506772D02*
Y513294D01*
G01X1359882Y504000D02*
Y508014D01*
G01X1364882Y504000D02*
Y508014D01*
G01X1376243Y574769D02*
X1373481D01*
X1372272Y573560D01*
G01X1375463Y693417D02*
Y689917D01*
G01Y697517D02*
Y699084D01*
X1373553Y700994D01*
G01X1348796Y969488D02*
Y965705D01*
G01D02*
Y959826D01*
X1348928Y959694D01*
G01X1334755Y965825D02*
X1331335D01*
X1331070Y966090D01*
G01X1334736Y959653D02*
Y965806D01*
X1334755Y965825D01*
G01X1367382Y956755D02*
Y961355D01*
G01X1362382Y956755D02*
Y961355D01*
G01X1365461Y1131655D02*
Y1136100D01*
G01X1365404Y1123365D02*
X1368935D01*
G01X1375463Y1146173D02*
Y1142673D01*
G01X1364713Y1143791D02*
Y1147073D01*
G01D02*
Y1153224D01*
X1364669D01*
G01X1375463Y1150273D02*
X1372952D01*
X1370716Y1148037D01*
G01X1346321Y1156153D02*
X1351321D01*
G01D02*
Y1152553D01*
G01X1413268Y146062D02*
X1409076Y141870D01*
X1405906D01*
G01X1394705Y207992D02*
X1401819D01*
G01X1413091Y180492D02*
X1406319D01*
G01X1394705Y198543D02*
Y195413D01*
G01X1402713Y194242D02*
X1403963Y195492D01*
X1413091D01*
G01X1405100Y166000D02*
X1405608Y165492D01*
X1413091D01*
G01Y245492D02*
X1403963D01*
G01X1406000Y236700D02*
X1407208Y235492D01*
X1413091D01*
G01X1385051Y218684D02*
X1386294Y217441D01*
X1394705D01*
G01X1384459Y244829D02*
Y255823D01*
X1384475Y255839D01*
G01X1426713Y266161D02*
X1422713D01*
G01X1413091Y275492D02*
X1406319D01*
G01X1413091Y265492D02*
X1406319D01*
G01X1422713Y295661D02*
Y303713D01*
X1426400Y307400D01*
G01X1405906Y314114D02*
X1398493D01*
G01X1421969Y531407D02*
X1425069D01*
X1426419Y532757D01*
G01X1418493Y531407D02*
X1421969D01*
G01Y517007D02*
X1425669D01*
X1426419Y516257D01*
G01X1418507Y517007D02*
X1421969D01*
G01X1425200Y540100D02*
X1428950D01*
G01X1414319Y523900D02*
Y527857D01*
G01Y520457D02*
Y523900D01*
G01X1405906Y594626D02*
X1413319D01*
G01X1413400Y571350D02*
Y575000D01*
G01X1413091Y648248D02*
X1406319D01*
G01X1413091Y633248D02*
X1406319D01*
G01X1413091Y618248D02*
X1406319D01*
G01X1394705Y670197D02*
X1401819D01*
G01X1413091Y688248D02*
X1406319D01*
G01X1394705Y660748D02*
X1401819D01*
G01X1394705Y651299D02*
X1401819D01*
G01X1426713Y718917D02*
X1422713D01*
G01X1413091Y728248D02*
X1406319D01*
G01X1413091Y718248D02*
X1406319D01*
G01X1413091Y698248D02*
X1406319D01*
G01X1422713Y748417D02*
Y752417D01*
G01X1405906Y766870D02*
X1398245D01*
G01X1413091Y1071004D02*
X1406319D01*
G01X1405906Y1047382D02*
X1413319D01*
G01X1394705Y1122953D02*
X1401819D01*
G01X1394705Y1104055D02*
X1401819D01*
G01X1413091Y1101004D02*
X1406319D01*
G01X1413091Y1086004D02*
X1406319D01*
G01X1394705Y1113504D02*
X1385494D01*
G01X1426713Y1171673D02*
X1422713D01*
G01X1413091Y1171004D02*
X1406319D01*
G01X1413091Y1151004D02*
X1406319D01*
G01X1413091Y1141004D02*
X1406319D01*
G01X1422713Y1201173D02*
Y1205173D01*
G01X1405906Y1219626D02*
X1413319D01*
G01X1413091Y1181004D02*
X1406319D01*
G01X1441648Y-425196D02*
Y-505196D01*
G01X1431713Y165911D02*
Y162661D01*
G01X1436213Y165911D02*
X1436204D01*
Y159247D01*
G01X1435963Y195261D02*
X1437245D01*
X1440300Y192206D01*
Y188000D01*
G01X1435963Y191161D02*
Y183833D01*
G01X1450713Y178311D02*
Y173049D01*
G01X1438186Y261287D02*
X1434812Y264661D01*
X1432713D01*
G01X1429800Y302500D02*
X1429213Y301913D01*
Y294961D01*
G01X1439300Y301500D02*
X1437213Y299413D01*
Y294961D01*
G01X1449576Y506621D02*
Y495482D01*
G01X1468605Y506518D02*
Y493549D01*
G01X1463085Y506635D02*
X1468488D01*
X1468605Y506518D01*
G01X1470700Y525350D02*
Y522100D01*
G01X1435200Y518350D02*
Y515000D01*
G01X1464700Y580900D02*
Y585600D01*
G01X1460261Y588256D02*
Y592498D01*
X1460274D01*
G01X1470000Y580000D02*
X1470700Y579300D01*
Y575850D01*
G01X1447700Y579600D02*
Y575850D01*
G01X1474700Y579100D02*
Y575850D01*
G01X1431713Y618667D02*
Y615417D01*
G01X1435963Y648017D02*
X1439613D01*
X1439713Y647917D01*
G01X1450713Y631067D02*
Y627817D01*
G01X1435963Y643917D02*
Y640667D01*
G01X1436213Y618667D02*
Y615417D01*
G01X1438087Y713756D02*
X1434426Y717417D01*
X1432713D01*
G01X1437213Y747717D02*
Y752417D01*
G01X1429213Y747717D02*
Y752417D01*
G01X1473008Y969646D02*
Y965763D01*
G01D02*
Y959784D01*
X1473140Y959652D01*
G01X1458967Y965883D02*
Y969535D01*
G01X1458948Y959611D02*
Y965864D01*
X1458967Y965883D01*
G01X1431713Y1071423D02*
Y1068173D01*
G01X1450713Y1083823D02*
Y1080673D01*
G01X1436213Y1071423D02*
Y1068173D01*
G01X1435963Y1100773D02*
X1439713D01*
G01X1435963Y1096673D02*
X1439750D01*
G01X1432713Y1170173D02*
X1438213D01*
G01X1470953Y1156027D02*
Y1152427D01*
G01X1437213Y1200473D02*
Y1205173D01*
G01X1429213Y1200473D02*
Y1205173D01*
G01X1518917Y207992D02*
X1526031D01*
G01X1518917Y198543D02*
X1526031D01*
G01X1518917Y217441D02*
X1526031D01*
G01X1499775Y240561D02*
Y236675D01*
X1498900Y235800D01*
G01X1499775Y244661D02*
Y248061D01*
G01X1487541Y535612D02*
X1479212D01*
G01X1494100Y526400D02*
Y530900D01*
G01X1503882Y539100D02*
X1507900D01*
G01X1481938Y506520D02*
Y512568D01*
G01X1502400Y550900D02*
Y554100D01*
G01X1486850Y525900D02*
Y523253D01*
X1485932Y522335D01*
G01X1483850Y530900D02*
X1488100D01*
G01D02*
Y527150D01*
X1486850Y525900D01*
G01X1507037Y527903D02*
X1500806D01*
X1500540Y528169D01*
G01D02*
Y523360D01*
X1500600Y523300D01*
G01X1486594Y504000D02*
Y508098D01*
G01X1491594Y504000D02*
Y508098D01*
G01X1487541Y539112D02*
X1492700D01*
G01X1497882Y539100D02*
X1493524D01*
X1493512Y539112D01*
X1492700D01*
G01X1498540Y533769D02*
X1497882Y534427D01*
Y539100D01*
G01X1514297Y544511D02*
Y535260D01*
X1512940Y533903D01*
G01X1507037D02*
X1512940D01*
G01X1502540Y533769D02*
X1506903D01*
X1507037Y533903D01*
G01X1478700Y579100D02*
Y575850D01*
G01X1514297Y553511D02*
X1509911D01*
G01X1518917Y670197D02*
X1526031D01*
G01X1518917Y660748D02*
X1526031D01*
G01X1518917Y651299D02*
X1526031D01*
G01X1499675Y693417D02*
X1495700D01*
X1494462Y692179D01*
G01X1499675Y697517D02*
Y700363D01*
X1495480Y704558D01*
G01X1491594Y956755D02*
Y961355D01*
G01X1486594Y956755D02*
Y961355D01*
G01X1518917Y1122953D02*
X1526031D01*
G01X1518917Y1113504D02*
X1526031D01*
G01X1518917Y1104055D02*
X1526031D01*
G01X1489096Y1126841D02*
Y1131456D01*
G01X1489108Y1117943D02*
Y1121674D01*
G01X1499675Y1146173D02*
Y1142673D01*
G01X1489333Y1144062D02*
Y1147664D01*
G01D02*
X1489343Y1147674D01*
Y1153308D01*
G01X1499675Y1150373D02*
X1497273D01*
X1495900Y1149000D01*
G01X1475953Y1156027D02*
Y1152427D01*
G01X1555925Y165911D02*
Y162661D01*
G01X1545383Y164116D02*
X1544007Y165492D01*
X1537303D01*
G01X1525336Y149369D02*
X1530118Y144587D01*
Y141870D01*
G01X1560425Y165911D02*
Y162661D01*
G01X1537303Y195492D02*
X1530531D01*
G01X1537303Y180492D02*
X1530531D01*
G01X1560175Y195261D02*
X1563925D01*
G01X1560175Y191161D02*
Y187911D01*
G01X1537303Y245492D02*
X1530531D01*
G01X1530142Y238021D02*
X1532671Y235492D01*
X1537303D01*
G01X1550925Y266161D02*
X1546925D01*
G01Y295661D02*
Y299661D01*
G01X1553425Y294961D02*
Y299661D01*
G01X1561425Y294961D02*
Y299661D01*
G01X1556925Y264661D02*
X1562425D01*
G01X1537303Y275492D02*
X1530531D01*
G01X1537303Y265492D02*
X1530531D01*
G01X1530118Y314114D02*
X1537531D01*
G01X1530118Y594626D02*
X1537531D01*
G01X1555925Y618667D02*
Y615417D01*
G01X1537303Y648248D02*
X1530531D01*
G01X1537303Y633248D02*
X1530531D01*
G01X1537303Y618248D02*
X1530531D01*
G01X1555175Y645917D02*
Y642667D01*
G01X1560425Y618667D02*
Y615417D01*
G01X1537303Y688248D02*
X1530531D01*
G01X1555175Y650017D02*
X1558925D01*
G01X1550925Y718917D02*
X1546925D01*
G01X1556925Y717417D02*
X1562425D01*
G01X1537303Y728248D02*
X1530531D01*
G01X1537303Y718248D02*
X1530531D01*
G01X1537303Y698248D02*
X1530531D01*
G01X1546925Y748417D02*
Y752417D01*
G01X1553425Y747717D02*
Y752417D01*
G01X1561425Y747717D02*
Y752417D01*
G01X1530118Y766870D02*
X1537531D01*
G01X1530118Y1047382D02*
X1537531D01*
G01X1555925Y1071423D02*
Y1068173D01*
G01X1537303Y1071004D02*
X1530531D01*
G01X1560425Y1071423D02*
Y1068173D01*
G01X1537303Y1101004D02*
X1530531D01*
G01X1537303Y1086004D02*
X1530531D01*
G01X1552575Y1132273D02*
X1553584D01*
X1556231Y1134920D01*
G01X1550925Y1171673D02*
X1546925D01*
G01X1556925Y1170173D02*
X1562425D01*
G01X1537303Y1171004D02*
X1530531D01*
G01X1537303Y1151004D02*
X1530531D01*
G01X1552575Y1136373D02*
Y1139700D01*
G01X1528723Y1138918D02*
X1530809Y1141004D01*
X1537303D01*
G01X1561425Y1200473D02*
Y1205173D01*
G01X1537303Y1181004D02*
X1530531D01*
G01X1553425Y1200473D02*
Y1208897D01*
G01X1530118Y1219626D02*
X1537879D01*
G01X1546925Y1201173D02*
Y1204827D01*
X1546898D01*
G01X1585757Y129754D02*
Y134147D01*
G01X1574925Y178311D02*
Y175061D01*
G01X1597245Y516662D02*
Y513418D01*
G01D02*
X1597226Y513399D01*
Y506855D01*
G01X1583108Y513387D02*
Y517327D01*
X1583030Y517405D01*
G01X1583117Y506856D02*
Y513378D01*
X1583108Y513387D01*
G01X1615807Y504000D02*
Y508600D01*
G01X1610807Y504000D02*
Y508600D01*
G01X1574925Y631067D02*
Y627817D01*
G01X1623888Y697517D02*
X1620469D01*
G01X1597353Y959778D02*
X1597321Y959810D01*
Y965889D01*
G01D02*
Y969472D01*
X1597221Y969572D01*
G01X1583180Y965809D02*
Y969461D01*
G01X1583161Y959737D02*
Y965790D01*
X1583180Y965809D01*
G01X1615807Y956755D02*
Y961355D01*
G01X1610807Y956755D02*
Y961355D01*
G01X1574925Y1083923D02*
Y1080673D01*
G01X1620236Y1156206D02*
X1615552D01*
G01D02*
Y1150619D01*
X1615909Y1150262D01*
G01X1639148Y-425196D02*
Y-505196D01*
G01X1667148Y-409196D02*
G02I-12000J0D01*
G01X1661998D02*
G02I-6850J0D01*
G01X1655148Y-425196D02*
Y-393196D01*
G01X1671148Y-409196D02*
X1639148D01*
G01X1654331Y141870D02*
X1661744D01*
G01X1643130Y207992D02*
X1650244D01*
G01X1643130Y198543D02*
X1650244D01*
G01X1661516Y195492D02*
X1654744D01*
G01X1661516Y180492D02*
X1654744D01*
G01X1661516Y165492D02*
X1654744D01*
G01X1661516Y245492D02*
X1654744D01*
G01X1643130Y217441D02*
X1650244D01*
G01X1661516Y235492D02*
X1654744D01*
G01X1625488Y240561D02*
X1621100D01*
G01X1625488Y244661D02*
X1621100D01*
G01X1653789Y267766D02*
X1656063Y265492D01*
X1661516D01*
G01X1652387Y277343D02*
X1654238Y275492D01*
X1661516D01*
G01X1654331Y314114D02*
X1661744D01*
G01X1654331Y594626D02*
X1661744D01*
G01X1661516Y648248D02*
X1654744D01*
G01X1661516Y633248D02*
X1654744D01*
G01X1661516Y618248D02*
X1654744D01*
G01X1623888Y693417D02*
Y689917D01*
G01X1661516Y688248D02*
X1654744D01*
G01X1643130Y660748D02*
X1650244D01*
G01X1643130Y651299D02*
X1650244D01*
G01X1652962Y670204D02*
Y670197D01*
X1643130D01*
G01X1661516Y728248D02*
X1654744D01*
G01X1661516Y718248D02*
X1654744D01*
G01X1661516Y698248D02*
X1654744D01*
G01X1654331Y766870D02*
X1661744D01*
G01X1661516Y1071004D02*
X1654744D01*
G01X1654331Y1047382D02*
X1661744D01*
G01X1643130Y1122953D02*
X1650244D01*
G01X1643130Y1113504D02*
X1650244D01*
G01X1643130Y1104055D02*
X1650244D01*
G01X1661516Y1101004D02*
X1654744D01*
G01X1661516Y1086004D02*
X1654744D01*
G01X1627563Y1128071D02*
Y1132075D01*
G01X1627802Y1118949D02*
Y1114449D01*
G01X1627798Y1106754D02*
Y1110008D01*
X1627769Y1110037D01*
G01X1661516Y1151004D02*
X1654744D01*
G01X1661516Y1141004D02*
X1654744D01*
G01X1635688Y1146173D02*
Y1141158D01*
G01X1650841Y1168660D02*
X1653185Y1171004D01*
X1661516D01*
G01X1627196Y1138567D02*
Y1143044D01*
X1627197D01*
G01X1635688Y1150273D02*
Y1153773D01*
G01X1654331Y1219626D02*
X1661744D01*
G01X1661516Y1181004D02*
X1668378D01*
G01X1680138Y165911D02*
Y162661D01*
G01X1684638Y165911D02*
Y162661D01*
G01X1684388Y195261D02*
X1688138D01*
G01X1684388Y191161D02*
Y187911D01*
G01X1699138Y178311D02*
Y175061D01*
G01X1671138Y295661D02*
Y299661D01*
G01X1677638Y294961D02*
Y299661D01*
G01X1685638Y294961D02*
Y299661D01*
G01X1681138Y264661D02*
X1686638D01*
G01X1671138Y266161D02*
X1674212D01*
X1675475Y267424D01*
G01X1707582Y513125D02*
Y517065D01*
X1707495Y517152D01*
G01X1707573Y513134D02*
X1707582Y513125D01*
G01D02*
Y506603D01*
G01X1684388Y648017D02*
X1688138D01*
G01X1680138Y618667D02*
Y615417D01*
G01X1684388Y643917D02*
Y638324D01*
G01X1699138Y631067D02*
Y627917D01*
G01X1684638Y618667D02*
Y615417D01*
G01X1675138Y718917D02*
X1671138D01*
G01X1681138Y717417D02*
X1686638D01*
G01X1685638Y747717D02*
Y752417D01*
G01X1677638Y747717D02*
Y752417D01*
G01X1671138Y748417D02*
Y752417D01*
G01X1680138Y1071423D02*
Y1068173D01*
G01X1699138Y1083823D02*
Y1080573D01*
G01X1684638Y1071423D02*
Y1068173D01*
G01X1684388Y1100773D02*
X1688138D01*
G01X1684388Y1096673D02*
Y1091723D01*
G01X1681138Y1170173D02*
X1686638D01*
G01X1675138Y1171673D02*
X1671138D01*
G01X1685638Y1200473D02*
Y1205173D01*
G01X1677638Y1200473D02*
Y1205173D01*
G01X1671138Y1201173D02*
Y1205173D01*
G01X1767342Y217441D02*
X1760486D01*
G01X1750300Y240561D02*
X1746600D01*
G01X1750300Y244661D02*
X1746500D01*
X1746400Y244561D01*
G01X1721710Y516409D02*
Y513165D01*
G01D02*
X1721691Y513146D01*
Y506602D01*
G01X1740019Y504000D02*
Y508600D01*
G01X1735019Y504000D02*
Y508600D01*
G01X1763250Y716500D02*
X1766721D01*
G01X1763250Y720500D02*
X1766721D01*
G01X1759884Y969161D02*
Y965756D01*
G01D02*
Y959740D01*
X1759890Y959734D01*
G01X1745686Y965664D02*
X1742201D01*
X1742001Y965464D01*
G01X1745686Y965664D02*
Y959705D01*
X1745698Y959693D01*
G01X1740019Y956755D02*
Y961355D01*
G01X1735019Y956755D02*
Y961355D01*
G01X1767113Y1013725D02*
X1765347Y1015491D01*
X1763714D01*
G01X1767342Y1113504D02*
X1759055D01*
G01X1736745Y1120127D02*
Y1123446D01*
X1736725D01*
G01D02*
X1736728Y1123449D01*
Y1127935D01*
G01X1748100Y1146173D02*
Y1142673D01*
G01X1736871Y1153108D02*
Y1158178D01*
G01X1736941Y1145478D02*
Y1141871D01*
G01X1748100Y1150273D02*
Y1153673D01*
G01X1718117Y1156153D02*
Y1152553D01*
G01X1723117Y1156153D02*
Y1152553D01*
G01X1778543Y141870D02*
X1785956D01*
G01X1804350Y165911D02*
Y162661D01*
G01X1808850Y165911D02*
Y162661D01*
G01X1767342Y207992D02*
X1774456D01*
G01X1767342Y198543D02*
X1774456D01*
G01X1785728Y195492D02*
X1778956D01*
G01X1785728Y180492D02*
X1778956D01*
G01X1808600Y195261D02*
X1812350D01*
G01X1775140Y165728D02*
X1775376Y165492D01*
X1785728D01*
G01X1808600Y191161D02*
Y187911D01*
G01X1785728Y245492D02*
X1778956D01*
G01X1785728Y235492D02*
X1778956D01*
G01X1799350Y266161D02*
X1795350D01*
G01X1805350Y264661D02*
X1810850D01*
G01X1785728Y275492D02*
X1778956D01*
G01X1785728Y265492D02*
X1778956D01*
G01X1809850Y294961D02*
Y299661D01*
G01X1801850Y294961D02*
Y299661D01*
G01X1795350Y295661D02*
Y299661D01*
G01X1778543Y314114D02*
X1785956D01*
G01X1778543Y594626D02*
X1785956D01*
G01X1785728Y648248D02*
X1778956D01*
G01X1785728Y633248D02*
X1778956D01*
G01X1808600Y648017D02*
X1812350D01*
G01X1804350Y618667D02*
Y615417D01*
G01X1785728Y618248D02*
X1778956D01*
G01X1808600Y643917D02*
Y640667D01*
G01X1808850Y618667D02*
Y615417D01*
G01X1767342Y670197D02*
X1774456D01*
G01X1785728Y688248D02*
X1778956D01*
G01X1767342Y660748D02*
X1774456D01*
G01X1767342Y651299D02*
X1774456D01*
G01X1785728Y728248D02*
X1778956D01*
G01X1785728Y718248D02*
X1778956D01*
G01X1785728Y698248D02*
X1778956D01*
G01X1811474Y717423D02*
Y717417D01*
X1805350D01*
G01X1795350Y718917D02*
X1797915D01*
X1799326Y717506D01*
G01X1809968Y747894D02*
Y752594D01*
G01X1801968Y747894D02*
Y752594D01*
G01X1795468Y748594D02*
Y752594D01*
G01X1778543Y766870D02*
X1785956D01*
G01X1802577Y959610D02*
Y965626D01*
G01X1790388Y968689D02*
Y966703D01*
X1788361Y964676D01*
G01D02*
Y959351D01*
G01X1802577Y965626D02*
X1801331D01*
X1799051Y963346D01*
G01X1782666Y956744D02*
Y961344D01*
G01X1777666Y956744D02*
Y961344D01*
G01X1783778Y978735D02*
Y974371D01*
G01D02*
Y970371D01*
G01X1767394Y978075D02*
X1768054Y978735D01*
X1775863D01*
G01D02*
X1780278D01*
G01X1780306Y983762D02*
X1778243Y985825D01*
X1775963D01*
G01D02*
X1767863D01*
G01X1766863Y1009225D02*
X1767113Y1009475D01*
Y1013725D01*
G01X1766205Y1004723D02*
Y1008567D01*
X1766863Y1009225D01*
G01X1774863Y1021475D02*
Y1024725D01*
G01X1774000Y991825D02*
X1767863D01*
G01X1772263Y995925D02*
X1774000Y994188D01*
Y991825D01*
G01X1778543Y1047382D02*
X1785956D01*
G01X1800750Y1071223D02*
Y1067973D01*
G01X1785728Y1071004D02*
X1778956D01*
G01X1805250Y1071223D02*
Y1067973D01*
G01X1767342Y1122953D02*
X1774456D01*
G01X1767342Y1104055D02*
X1774456D01*
G01X1785728Y1101004D02*
X1778956D01*
G01X1785728Y1086004D02*
X1778956D01*
G01X1808600Y1100773D02*
X1811968D01*
G01X1808600Y1096673D02*
X1814187D01*
X1816046Y1098532D01*
G01X1799350Y1171673D02*
X1795350D01*
G01X1805350Y1170173D02*
X1810850D01*
G01X1785728Y1171004D02*
X1778956D01*
G01X1785728Y1151004D02*
X1778956D01*
G01X1785728Y1141004D02*
X1778956D01*
G01X1795350Y1201173D02*
Y1205173D01*
G01X1801850Y1200473D02*
Y1205173D01*
G01X1809850Y1200473D02*
Y1205173D01*
G01X1778543Y1219626D02*
X1785956D01*
G01X1785728Y1181004D02*
X1778956D01*
G01X1855517Y161725D02*
X1859017D01*
G01X1845517D02*
Y158475D01*
G01X1856219Y209161D02*
Y212661D01*
G01X1848419Y210461D02*
Y214661D01*
G01X1843917Y197425D02*
X1843919D01*
Y205961D01*
X1848419Y210461D01*
G01X1856219Y204961D02*
Y201661D01*
G01X1823350Y178311D02*
Y175161D01*
G01X1845869Y254661D02*
X1841169D01*
G01X1845545Y516536D02*
Y513292D01*
G01D02*
X1845526Y513273D01*
Y506729D01*
G01X1831408Y513261D02*
Y517201D01*
X1831330Y517279D01*
G01X1831417Y506730D02*
Y511801D01*
X1831408Y511810D01*
Y513261D01*
G01X1859232Y504000D02*
Y508600D01*
G01X1855417Y614481D02*
X1858917D01*
G01X1823350Y631067D02*
Y627917D01*
G01X1845417Y614481D02*
Y611231D01*
G01X1856219Y661917D02*
Y665417D01*
G01X1862200Y686700D02*
X1865169Y689669D01*
Y692917D01*
G01X1847500Y659100D02*
X1848419Y660019D01*
Y663317D01*
G01X1843917Y650181D02*
Y655517D01*
X1847500Y659100D01*
G01X1848419Y663317D02*
Y667417D01*
G01X1856219Y657817D02*
Y654417D01*
G01X1842276Y707417D02*
X1837576D01*
G01X1821152Y907899D02*
X1824551Y904500D01*
X1869897D01*
X1873001Y901396D01*
G01X1823350Y1083823D02*
Y1080673D01*
G01X1856441Y1102987D02*
Y1106016D01*
X1856437D01*
Y1106400D01*
G01X1856341Y1098787D02*
Y1094484D01*
X1858046Y1092779D01*
G01X1836953Y1103391D02*
X1840433D01*
G01X1854352Y1153286D02*
X1850532D01*
G01X1836200Y1136670D02*
Y1140638D01*
X1836231Y1140669D01*
G01D02*
X1836431Y1140869D01*
Y1144409D01*
G01X1836400Y1151900D02*
Y1155700D01*
G01D02*
X1836421Y1155721D01*
X1841084D01*
G01X1902756Y141870D02*
X1910169D01*
G01X1891555Y207992D02*
X1898669D01*
G01X1891555Y198543D02*
X1898669D01*
G01X1909941Y195492D02*
X1903169D01*
G01X1909941Y180492D02*
X1903169D01*
G01X1909941Y165492D02*
X1903169D01*
G01X1883000Y187494D02*
Y186549D01*
X1885204Y184345D01*
G01X1878900Y187494D02*
X1876938Y185532D01*
Y181062D01*
G01X1869169Y247161D02*
X1865169D01*
G01Y234661D02*
Y240161D01*
G01X1909941Y245492D02*
X1903169D01*
G01X1891555Y217441D02*
X1898669D01*
G01X1909941Y235492D02*
X1903169D01*
G01X1909941Y275492D02*
X1903169D01*
G01X1909941Y265492D02*
X1903169D01*
G01X1885969Y276861D02*
X1880969D01*
G01X1887169Y296161D02*
X1881111D01*
X1881088Y296184D01*
G01X1902756Y314114D02*
X1910169D01*
G01X1864232Y504000D02*
Y508600D01*
G01X1902756Y594626D02*
X1910169D01*
G01X1909941Y648248D02*
X1903169D01*
G01X1909941Y633248D02*
X1903169D01*
G01X1909941Y618248D02*
X1903169D01*
G01X1883000Y640250D02*
Y639100D01*
X1885300Y636800D01*
G01X1878900Y640250D02*
Y637000D01*
G01X1891555Y670197D02*
X1898669D01*
G01X1909941Y688248D02*
X1903169D01*
G01X1891555Y660748D02*
X1898669D01*
G01X1891555Y651299D02*
X1898669D01*
G01X1909941Y728248D02*
X1903169D01*
G01X1909941Y718248D02*
X1903169D01*
G01X1909941Y698248D02*
X1903169D01*
G01X1885969Y729617D02*
X1880969D01*
G01X1869169Y699917D02*
X1865169D01*
G01X1902756Y766870D02*
X1910169D01*
G01X1887169Y748917D02*
Y752917D01*
G01X1884800Y890750D02*
X1881938D01*
X1867652Y876464D01*
Y865421D01*
G01Y846508D02*
Y865421D01*
G01X1909941Y1071004D02*
X1903169D01*
G01X1902756Y1047382D02*
X1910169D01*
G01X1884835Y1064038D02*
Y1067400D01*
G01X1868100Y1058750D02*
Y1055410D01*
G01X1884835Y1059938D02*
X1888085D01*
G01X1876662Y1058676D02*
Y1055426D01*
G01X1891555Y1122953D02*
X1898669D01*
G01X1891555Y1113504D02*
X1898669D01*
G01X1891555Y1104055D02*
X1898669D01*
G01X1909941Y1101004D02*
X1903169D01*
G01X1909941Y1086004D02*
X1903169D01*
G01X1863131Y1133108D02*
X1865548Y1130691D01*
Y1126458D01*
G01X1909941Y1171004D02*
X1903169D01*
G01X1909941Y1141004D02*
X1903169D01*
G01X1868417Y1153308D02*
X1864352D01*
G01X1903100Y1149700D02*
X1904404Y1151004D01*
X1909941D01*
G01X1871174Y1138730D02*
X1865992D01*
G01X1870648Y1133143D02*
Y1138204D01*
X1871174Y1138730D01*
G01X1909941Y1181004D02*
X1903169D01*
G01X1885969Y1182373D02*
X1880969D01*
G01X1902756Y1219626D02*
X1910169D01*
G01X1887169Y1201673D02*
Y1205673D01*
X127988Y190242D03*
Y185742D03*
Y194242D03*
Y181742D03*
Y634498D03*
Y638498D03*
Y642998D03*
Y646998D03*
Y1087254D03*
Y1091254D03*
Y1095754D03*
Y1099754D03*
X252200Y190242D03*
Y185742D03*
Y194242D03*
Y181742D03*
Y634498D03*
Y638498D03*
Y642998D03*
Y646998D03*
Y1087254D03*
Y1091254D03*
Y1095754D03*
Y1099754D03*
X376413Y190242D03*
Y185742D03*
Y194242D03*
Y181742D03*
Y634498D03*
Y638498D03*
Y642998D03*
Y646998D03*
Y1087254D03*
Y1091254D03*
Y1095754D03*
Y1099754D03*
X500625Y190242D03*
Y185742D03*
Y194242D03*
Y181742D03*
Y634498D03*
Y638498D03*
Y642998D03*
Y646998D03*
Y1087254D03*
Y1091254D03*
Y1095754D03*
Y1099754D03*
X624838Y190242D03*
Y185742D03*
Y194242D03*
Y181742D03*
Y634498D03*
Y638498D03*
Y642998D03*
Y646998D03*
Y1087254D03*
Y1091254D03*
Y1095754D03*
Y1099754D03*
X749051Y190242D03*
Y185742D03*
Y194242D03*
Y181742D03*
Y634498D03*
Y638498D03*
Y642998D03*
Y646998D03*
Y1087254D03*
Y1091254D03*
Y1095754D03*
Y1099754D03*
X1066750Y1224035D03*
X1070750D03*
X1075250D03*
X1079250D03*
X1066750Y1209862D03*
X1070750D03*
X1075250D03*
X1079250D03*
X1066750Y1216949D03*
X1070750D03*
X1075250D03*
X1079250D03*
X1066750Y1231122D03*
X1070750D03*
X1075250D03*
X1079250D03*
X1066750Y1238209D03*
X1070750D03*
X1075250D03*
X1079250D03*
X1066750Y1245295D03*
X1070750D03*
X1075250D03*
X1079250D03*
X1066750Y1301988D03*
X1070750D03*
X1075250D03*
X1079250D03*
X1066750Y1309075D03*
X1070750D03*
X1075250D03*
X1079250D03*
X1066750Y1316161D03*
X1070750D03*
X1075250D03*
X1079250D03*
X1066750Y1323248D03*
X1070750D03*
X1075250D03*
X1079250D03*
X1066750Y1294902D03*
X1070750D03*
X1075250D03*
X1079250D03*
X1066750Y1330335D03*
X1070750D03*
X1075250D03*
X1079250D03*
X1066750Y1387028D03*
X1070750D03*
X1075250D03*
X1079250D03*
X1066750Y1394114D03*
X1070750D03*
X1075250D03*
X1079250D03*
X1066750Y1401201D03*
X1070750D03*
X1075250D03*
X1079250D03*
X1066750Y1408287D03*
X1070750D03*
X1075250D03*
X1079250D03*
X1066750Y1415374D03*
X1070750D03*
X1075250D03*
X1079250D03*
X1066750Y1379941D03*
X1070750D03*
X1075250D03*
X1079250D03*
X1278900Y182823D03*
X1274900D03*
X1270400D03*
X1266400D03*
X1261250Y167823D03*
X1256750D03*
X1265250D03*
X1252750D03*
X1278500Y634498D03*
Y638498D03*
Y642998D03*
Y646998D03*
X1259800Y631998D03*
Y627998D03*
Y623498D03*
Y619498D03*
Y1080754D03*
Y1076254D03*
Y1072254D03*
X1278500Y1087254D03*
Y1091254D03*
Y1095754D03*
Y1099754D03*
X1259800Y1084754D03*
X1376963Y167823D03*
X1402713Y181742D03*
Y185742D03*
Y190242D03*
Y194242D03*
X1380963Y167823D03*
X1385463D03*
X1389463D03*
X1402713Y634498D03*
Y638498D03*
Y642998D03*
Y646998D03*
X1384013Y631998D03*
Y627998D03*
Y623498D03*
Y619498D03*
Y1080754D03*
Y1076254D03*
Y1072254D03*
X1402713Y1087254D03*
Y1091254D03*
Y1095754D03*
Y1099754D03*
X1384013Y1084754D03*
X1515450Y181700D03*
X1511450D03*
X1506950D03*
X1502950D03*
X1508225Y631998D03*
Y627998D03*
Y623498D03*
Y619498D03*
Y1080754D03*
Y1076254D03*
Y1072254D03*
Y1084754D03*
X1526925Y181742D03*
Y185742D03*
Y190242D03*
Y194242D03*
Y634498D03*
Y638498D03*
Y642998D03*
Y646998D03*
Y1087254D03*
Y1091254D03*
Y1095754D03*
Y1099754D03*
X1651138Y181742D03*
Y185742D03*
Y190242D03*
Y194242D03*
X1632438Y179242D03*
Y175242D03*
Y170742D03*
Y166742D03*
X1651138Y634498D03*
Y638498D03*
Y642998D03*
Y646998D03*
X1632438Y631998D03*
Y627998D03*
Y623498D03*
Y619498D03*
Y1080754D03*
Y1076254D03*
Y1072254D03*
X1651138Y1087254D03*
Y1091254D03*
Y1095754D03*
Y1099754D03*
X1632438Y1084754D03*
X1756650Y179242D03*
Y175242D03*
Y170742D03*
Y166742D03*
X1725350Y634498D03*
Y638498D03*
Y642998D03*
Y646998D03*
X1731650Y631998D03*
Y627998D03*
Y623498D03*
Y619498D03*
X1756650Y1080754D03*
Y1076254D03*
Y1072254D03*
Y1084754D03*
X1775350Y181742D03*
Y185742D03*
Y190242D03*
Y194242D03*
Y1087254D03*
Y1091254D03*
Y1095754D03*
Y1099754D03*
X1899563Y181742D03*
Y185742D03*
Y190242D03*
Y194242D03*
X1880863Y179242D03*
Y175242D03*
Y170742D03*
Y166742D03*
X1899563Y634498D03*
Y638498D03*
Y642998D03*
Y646998D03*
X1880863Y631998D03*
Y627998D03*
Y623498D03*
Y619498D03*
Y1080754D03*
Y1076254D03*
Y1072254D03*
X1899563Y1087254D03*
Y1091254D03*
Y1095754D03*
Y1099754D03*
X1880863Y1084754D03*
G54D117*
G01X141978Y966735D02*
Y958572D01*
G01X142006Y971762D02*
Y978425D01*
G01X208706Y559762D02*
X209863Y560919D01*
Y566625D01*
G01X1783806Y983762D02*
Y989468D01*
G54D24*
X67937Y205261D03*
X60037Y179561D03*
Y632317D03*
X67937Y657917D03*
X30993Y692869D03*
X30626Y667518D03*
X67937Y1110673D03*
X59937Y1085073D03*
X30206Y1120485D03*
X30573Y1145836D03*
X92237Y191161D03*
X88596Y629631D03*
X92237Y643917D03*
X120395Y999067D03*
X92237Y1096673D03*
X153703Y714355D03*
X154312Y1158233D03*
X153882Y1186220D03*
X184149Y179661D03*
X192149Y204961D03*
X216449Y191161D03*
X187095Y587067D03*
X216449Y633417D03*
X188599Y621417D03*
X204502Y620496D03*
X191849Y1106373D03*
X216449Y1096673D03*
X184427Y1094839D03*
X184439Y1099043D03*
X308362Y179661D03*
X308462Y632417D03*
X277970Y714099D03*
X308362Y1085173D03*
X278526Y1158233D03*
X278096Y1186220D03*
X319155Y68379D03*
X329479Y68345D03*
X316362Y205061D03*
X340662Y191161D03*
X337132Y629429D03*
X340662Y644017D03*
X316362Y657717D03*
Y1110573D03*
X340762Y1096773D03*
X402127Y714027D03*
X402353Y1185011D03*
X432674Y179661D03*
X440574Y205061D03*
X432674Y632317D03*
X440674Y657817D03*
X453373Y1104326D03*
X464874Y191161D03*
X461303Y629682D03*
X464874Y643917D03*
X508174Y1110573D03*
X556787Y179561D03*
X526223Y714280D03*
X526451Y1163084D03*
X526317Y1186666D03*
X589087Y191161D03*
X564887Y204861D03*
X592479Y566331D03*
X589087Y643917D03*
X556887Y632317D03*
X564887Y657717D03*
X564787Y1110473D03*
X589087Y1096673D03*
X556887Y1085173D03*
X616958Y538745D03*
Y542745D03*
X650657Y714197D03*
X651166Y1160810D03*
X650576Y1186007D03*
X694257Y107247D03*
X689000Y205161D03*
X681000Y179561D03*
X685450Y631917D03*
X701353Y630996D03*
X689000Y657917D03*
X688700Y1106273D03*
X680600Y1093100D03*
X713300Y191161D03*
Y643917D03*
Y1096673D03*
X885200Y41500D03*
X878257Y378495D03*
X882973Y816103D03*
X874523Y814580D03*
X881073Y856903D03*
X936981Y912047D03*
X936713Y1028083D03*
X936624Y1032390D03*
X961700Y1552700D03*
X1022568Y-40100D03*
X1014100Y58900D03*
Y63600D03*
Y54200D03*
X1014872Y545207D03*
X1014806Y554532D03*
X1034214Y872741D03*
X1032929Y1324216D03*
X1038053Y1349992D03*
X1032929Y1337616D03*
X1033029Y1342668D03*
X1032929Y1330916D03*
X1065571Y-80978D03*
X1042258Y-75936D03*
X1069618Y22405D03*
X1044173Y835703D03*
X1042073Y872703D03*
X1104300Y-78400D03*
X1113321Y-80838D03*
X1104379Y-86862D03*
X1089268Y-87500D03*
X1089250Y-60300D03*
X1180402Y96794D03*
X1180249Y101360D03*
X1183000Y249800D03*
X1190832D03*
X1229647Y1145325D03*
X1256700Y244861D03*
X1243764Y1145413D03*
X1314021Y90855D03*
Y86155D03*
X1345703Y133842D03*
X1332700Y194661D03*
X1363928Y542311D03*
X1332700Y647417D03*
Y1100173D03*
X1365354Y1123365D03*
X1364663Y1147073D03*
X1417769Y520457D03*
Y527857D03*
X1425400Y549600D03*
Y553600D03*
X1378913Y697517D03*
Y1150273D03*
X1456913Y194661D03*
X1451900Y526100D03*
X1459900D03*
X1432400Y540100D03*
X1456913Y647417D03*
Y1100173D03*
X1503225Y244661D03*
X1486800Y525900D03*
X1483800Y530900D03*
X1485800Y560400D03*
Y556100D03*
X1503125Y697517D03*
X1489058Y1117943D03*
X1503125Y1150373D03*
X1489283Y1144062D03*
X1581125Y194661D03*
X1576125Y649417D03*
X1590225Y1093873D03*
X1628938Y244661D03*
X1627338Y697517D03*
X1627513Y1128071D03*
X1627748Y1106754D03*
X1639138Y1150273D03*
X1705338Y194661D03*
Y647417D03*
Y1100173D03*
X1753750Y244661D03*
X1762195Y1011067D03*
X1736695Y1120127D03*
X1751550Y1150273D03*
X1736891Y1145478D03*
X1829550Y194661D03*
X1859669Y204961D03*
X1851717Y194075D03*
X1829550Y647417D03*
X1851717Y646831D03*
X1859669Y657817D03*
X1829550Y1100173D03*
X1859791Y1098787D03*
X1851696Y1098813D03*
G54D15*
X31496Y882677D03*
X168307Y646457D03*
X660236D03*
X718110Y820866D03*
X1366142Y646457D03*
X1462992Y866929D03*
X1602756Y646457D03*
X1903346Y803937D03*
G54D33*
X50937Y245661D03*
X55937D03*
X60937D03*
X65937D03*
Y225661D03*
X60937D03*
X55937D03*
X50937D03*
Y698417D03*
X55937D03*
X60937D03*
X65937D03*
Y678417D03*
X60937D03*
X55937D03*
X50937D03*
X65937Y1131173D03*
X60937D03*
X55937D03*
X50937D03*
Y1151173D03*
X55937D03*
X60937D03*
X65937D03*
X88937Y207661D03*
X83937D03*
X78937D03*
X73937D03*
Y227661D03*
X78937D03*
X83937D03*
X88937D03*
Y660417D03*
X83937D03*
X78937D03*
X73937D03*
Y680417D03*
X78937D03*
X83937D03*
X88937D03*
Y1113173D03*
X83937D03*
X78937D03*
X73937D03*
Y1133173D03*
X78937D03*
X83937D03*
X88937D03*
X213149Y207661D03*
X208149D03*
X203149D03*
X198149D03*
X175149Y245661D03*
X180149D03*
X185149D03*
X190149D03*
Y225661D03*
X185149D03*
X180149D03*
X175149D03*
X198149Y227661D03*
X203149D03*
X208149D03*
X213149D03*
X175149Y698417D03*
X180149D03*
X185149D03*
X190149D03*
Y678417D03*
X185149D03*
X180149D03*
X175149D03*
X213149Y660417D03*
X208149D03*
X203149D03*
X198149D03*
Y680417D03*
X203149D03*
X208149D03*
X213149D03*
X190149Y1131173D03*
X185149D03*
X180149D03*
X175149D03*
X213149Y1113173D03*
X208149D03*
X203149D03*
X198149D03*
Y1133173D03*
X203149D03*
X208149D03*
X213149D03*
X175149Y1151173D03*
X180149D03*
X185149D03*
X190149D03*
X299362Y245661D03*
X304362D03*
X309362D03*
X314362D03*
Y225661D03*
X309362D03*
X304362D03*
X299362D03*
Y698417D03*
X304362D03*
X309362D03*
X314362D03*
Y678417D03*
X309362D03*
X304362D03*
X299362D03*
X314362Y1131173D03*
X309362D03*
X304362D03*
X299362D03*
Y1151173D03*
X304362D03*
X309362D03*
X314362D03*
X337362Y207661D03*
X332362D03*
X327362D03*
X322362D03*
Y227661D03*
X327362D03*
X332362D03*
X337362D03*
Y660417D03*
X332362D03*
X327362D03*
X322362D03*
Y680417D03*
X327362D03*
X332362D03*
X337362D03*
Y1113173D03*
X332362D03*
X327362D03*
X322362D03*
Y1133173D03*
X327362D03*
X332362D03*
X337362D03*
X456574Y207661D03*
X451574D03*
X446574D03*
Y227661D03*
X451574D03*
X456574D03*
X423574Y245661D03*
X428574D03*
X433574D03*
X438574D03*
Y225661D03*
X433574D03*
X428574D03*
X423574D03*
Y698417D03*
X428574D03*
X433574D03*
X438574D03*
Y678417D03*
X433574D03*
X428574D03*
X423574D03*
X456574Y660417D03*
X451574D03*
X446574D03*
Y680417D03*
X451574D03*
X456574D03*
X457100Y1130200D03*
X452100D03*
X447100D03*
Y1150200D03*
X452100D03*
X457100D03*
X461574Y207661D03*
Y227661D03*
Y660417D03*
Y680417D03*
X462100Y1130200D03*
Y1150200D03*
X547787Y245661D03*
X552787D03*
Y225661D03*
X547787D03*
Y698417D03*
X552787D03*
Y678417D03*
X547787D03*
X552787Y1131173D03*
X547787D03*
X529474Y1113073D03*
X524474D03*
X519474D03*
X514474D03*
Y1133073D03*
X519474D03*
X524474D03*
X529474D03*
X547787Y1151173D03*
X552787D03*
X585787Y207661D03*
X580787D03*
X575787D03*
X570787D03*
Y227661D03*
X575787D03*
X580787D03*
X585787D03*
X557787Y245661D03*
X562787D03*
Y225661D03*
X557787D03*
Y698417D03*
X562787D03*
Y678417D03*
X557787D03*
X585787Y660417D03*
X580787D03*
X575787D03*
X570787D03*
Y680417D03*
X575787D03*
X580787D03*
X585787D03*
X562787Y1131173D03*
X557787D03*
X585787Y1113173D03*
X580787D03*
X575787D03*
X570787D03*
Y1133173D03*
X575787D03*
X580787D03*
X585787D03*
X557787Y1151173D03*
X562787D03*
X700000Y207661D03*
X695000D03*
Y227661D03*
X700000D03*
X672000Y245661D03*
X677000D03*
X682000D03*
X687000D03*
Y225661D03*
X682000D03*
X677000D03*
X672000D03*
Y698417D03*
X677000D03*
X682000D03*
X687000D03*
Y678417D03*
X682000D03*
X677000D03*
X672000D03*
X700000Y660417D03*
X695000D03*
Y680417D03*
X700000D03*
X687000Y1131173D03*
X682000D03*
X677000D03*
X672000D03*
X700000Y1113173D03*
X695000D03*
Y1133173D03*
X700000D03*
X672000Y1151173D03*
X677000D03*
X682000D03*
X687000D03*
X710000Y207661D03*
X705000D03*
Y227661D03*
X710000D03*
Y660417D03*
X705000D03*
Y680417D03*
X710000D03*
Y1113173D03*
X705000D03*
Y1133173D03*
X710000D03*
X999500Y1174500D03*
X1004500D03*
X1009500D03*
X1014500D03*
Y1154500D03*
X1009500D03*
X1004500D03*
X999500D03*
X1318500Y254161D03*
X1323500D03*
X1328500D03*
Y234161D03*
X1323500D03*
X1318500D03*
X1328500Y686917D03*
X1323500D03*
X1318500D03*
Y706917D03*
X1323500D03*
X1328500D03*
X1318500Y1159673D03*
X1323500D03*
X1328500D03*
Y1139673D03*
X1323500D03*
X1318500D03*
X1333500Y254161D03*
Y234161D03*
Y686917D03*
Y706917D03*
Y1159673D03*
Y1139673D03*
X1442713Y254161D03*
X1447713D03*
X1452713D03*
X1457713D03*
Y234161D03*
X1452713D03*
X1447713D03*
X1442713D03*
X1457713Y686917D03*
X1452713D03*
X1447713D03*
X1442713D03*
Y706917D03*
X1447713D03*
X1452713D03*
X1457713D03*
X1442713Y1159673D03*
X1447713D03*
X1452713D03*
X1457713D03*
Y1139673D03*
X1452713D03*
X1447713D03*
X1442713D03*
X1566925Y254161D03*
X1571925D03*
Y234161D03*
X1566925D03*
X1571925Y686917D03*
X1566925D03*
Y706917D03*
X1571925D03*
X1564073Y1105175D03*
X1559073D03*
X1554073D03*
X1549073D03*
Y1125175D03*
X1554073D03*
X1559073D03*
X1564073D03*
X1576925Y254161D03*
X1581925D03*
Y234161D03*
X1576925D03*
X1581925Y686917D03*
X1576925D03*
Y706917D03*
X1581925D03*
X1691138Y254161D03*
X1696138D03*
X1701138D03*
X1706138D03*
Y234161D03*
X1701138D03*
X1696138D03*
X1691138D03*
X1706138Y686917D03*
X1701138D03*
X1696138D03*
X1691138D03*
Y706917D03*
X1696138D03*
X1701138D03*
X1706138D03*
X1691138Y1159673D03*
X1696138D03*
X1701138D03*
X1706138D03*
Y1139673D03*
X1701138D03*
X1696138D03*
X1691138D03*
X1842669Y245661D03*
X1847669D03*
X1852669D03*
X1857669D03*
Y225661D03*
X1852669D03*
X1847669D03*
X1842669D03*
X1815350Y254161D03*
X1820350D03*
X1825350D03*
X1830350D03*
Y234161D03*
X1825350D03*
X1820350D03*
X1815350D03*
X1842669Y698417D03*
X1847669D03*
X1852669D03*
X1857669D03*
Y678417D03*
X1852669D03*
X1847669D03*
X1842669D03*
X1830350Y686917D03*
X1825350D03*
X1820350D03*
X1815350D03*
Y706917D03*
X1820350D03*
X1825350D03*
X1830350D03*
X1858277Y1125264D03*
X1853277D03*
X1848277D03*
X1843277D03*
Y1145264D03*
X1848277D03*
X1853277D03*
X1858277D03*
X1815350Y1159673D03*
X1820350D03*
X1825350D03*
X1830350D03*
Y1139673D03*
X1825350D03*
X1820350D03*
X1815350D03*
X1880669Y207661D03*
X1875669D03*
X1870669D03*
X1865669D03*
Y227661D03*
X1870669D03*
X1875669D03*
X1880669D03*
Y660417D03*
X1875669D03*
X1870669D03*
X1865669D03*
Y680417D03*
X1870669D03*
X1875669D03*
X1880669D03*
X1880779Y1097763D03*
X1875779D03*
X1870779D03*
X1865779D03*
Y1117763D03*
X1870779D03*
X1875779D03*
X1880779D03*
G54D42*
X99823Y211142D03*
Y207992D03*
Y204842D03*
Y201693D03*
Y198543D03*
Y217441D03*
Y214291D03*
Y670197D03*
Y667047D03*
Y663898D03*
Y660748D03*
Y657598D03*
Y654449D03*
Y651299D03*
Y1122953D03*
Y1119803D03*
Y1116654D03*
Y1113504D03*
Y1110354D03*
Y1107205D03*
Y1104055D03*
X224035Y211142D03*
Y207992D03*
Y204842D03*
Y201693D03*
Y198543D03*
Y217441D03*
Y214291D03*
Y670197D03*
Y667047D03*
Y663898D03*
Y660748D03*
Y657598D03*
Y654449D03*
Y651299D03*
Y1122953D03*
Y1119803D03*
Y1116654D03*
Y1113504D03*
Y1110354D03*
Y1107205D03*
Y1104055D03*
X348248Y211142D03*
Y207992D03*
Y204842D03*
Y201693D03*
Y198543D03*
Y217441D03*
Y214291D03*
Y670197D03*
Y667047D03*
Y663898D03*
Y660748D03*
Y657598D03*
Y654449D03*
Y651299D03*
Y1122953D03*
Y1119803D03*
Y1116654D03*
Y1113504D03*
Y1110354D03*
Y1107205D03*
Y1104055D03*
X472460Y211142D03*
Y207992D03*
Y204842D03*
Y201693D03*
Y198543D03*
Y217441D03*
Y214291D03*
Y670197D03*
Y667047D03*
Y663898D03*
Y660748D03*
Y657598D03*
Y654449D03*
Y651299D03*
Y1122953D03*
Y1119803D03*
Y1116654D03*
Y1113504D03*
Y1110354D03*
Y1107205D03*
Y1104055D03*
X596673Y211142D03*
Y207992D03*
Y204842D03*
Y201693D03*
Y198543D03*
Y217441D03*
Y214291D03*
Y670197D03*
Y667047D03*
Y663898D03*
Y660748D03*
Y657598D03*
Y654449D03*
Y651299D03*
Y1122953D03*
Y1119803D03*
Y1116654D03*
Y1113504D03*
Y1110354D03*
Y1107205D03*
Y1104055D03*
X720886Y211142D03*
Y207992D03*
Y204842D03*
Y201693D03*
Y198543D03*
Y217441D03*
Y214291D03*
Y670197D03*
Y667047D03*
Y663898D03*
Y660748D03*
Y657598D03*
Y654449D03*
Y651299D03*
Y1122953D03*
Y1119803D03*
Y1116654D03*
Y1113504D03*
Y1110354D03*
Y1107205D03*
Y1104055D03*
X1270492Y211142D03*
Y207992D03*
Y204842D03*
Y201693D03*
Y198543D03*
Y217441D03*
Y214291D03*
Y670197D03*
Y667047D03*
Y663898D03*
Y660748D03*
Y657598D03*
Y654449D03*
Y651299D03*
Y1122953D03*
Y1119803D03*
Y1116654D03*
Y1113504D03*
Y1110354D03*
Y1107205D03*
Y1104055D03*
X1394705Y211142D03*
Y207992D03*
Y204842D03*
Y201693D03*
Y198543D03*
Y217441D03*
Y214291D03*
Y670197D03*
Y667047D03*
Y663898D03*
Y660748D03*
Y657598D03*
Y654449D03*
Y651299D03*
Y1122953D03*
Y1119803D03*
Y1116654D03*
Y1113504D03*
Y1110354D03*
Y1107205D03*
Y1104055D03*
X1518917Y211142D03*
Y207992D03*
Y204842D03*
Y201693D03*
Y198543D03*
Y217441D03*
Y214291D03*
Y670197D03*
Y667047D03*
Y663898D03*
Y660748D03*
Y657598D03*
Y654449D03*
Y651299D03*
Y1122953D03*
Y1119803D03*
Y1116654D03*
Y1113504D03*
Y1110354D03*
Y1107205D03*
Y1104055D03*
X1643130Y211142D03*
Y207992D03*
Y204842D03*
Y201693D03*
Y198543D03*
Y217441D03*
Y214291D03*
Y670197D03*
Y667047D03*
Y663898D03*
Y660748D03*
Y657598D03*
Y654449D03*
Y651299D03*
Y1122953D03*
Y1119803D03*
Y1116654D03*
Y1113504D03*
Y1110354D03*
Y1107205D03*
Y1104055D03*
X1767342Y211142D03*
Y207992D03*
Y204842D03*
Y201693D03*
Y198543D03*
Y217441D03*
Y214291D03*
Y670197D03*
Y667047D03*
Y663898D03*
Y660748D03*
Y657598D03*
Y654449D03*
Y651299D03*
Y1122953D03*
Y1119803D03*
Y1116654D03*
Y1113504D03*
Y1110354D03*
Y1107205D03*
Y1104055D03*
X1891555Y211142D03*
Y207992D03*
Y204842D03*
Y201693D03*
Y198543D03*
Y217441D03*
Y214291D03*
Y670197D03*
Y667047D03*
Y663898D03*
Y660748D03*
Y657598D03*
Y654449D03*
Y651299D03*
Y1122953D03*
Y1119803D03*
Y1116654D03*
Y1113504D03*
Y1110354D03*
Y1107205D03*
Y1104055D03*
G54D108*
X1392452Y573397D03*
Y579803D03*
G54D51*
X128909Y171892D03*
X126709D03*
X128909Y174092D03*
X126709D03*
Y624648D03*
X128909D03*
X126709Y626848D03*
X128909D03*
X126709Y1077404D03*
X128909D03*
X126709Y1079604D03*
X128909D03*
X253121Y171892D03*
X250921D03*
X253121Y174092D03*
X250921D03*
Y626848D03*
X253121D03*
X250921Y624648D03*
X253121D03*
X250921Y1077404D03*
X253121D03*
X250921Y1079604D03*
X253121D03*
X377334Y171892D03*
X375134D03*
X377334Y174092D03*
X375134D03*
Y624648D03*
X377334D03*
X375134Y626848D03*
X377334D03*
X375134Y1077404D03*
X377334D03*
X375134Y1079604D03*
X377334D03*
X501546Y174092D03*
X499346D03*
X501546Y171892D03*
X499346D03*
Y624648D03*
X501546D03*
X499346Y626848D03*
X501546D03*
X499346Y1079604D03*
X501546D03*
X499346Y1077404D03*
X501546D03*
X625759Y174092D03*
X623559D03*
X625759Y171892D03*
X623559D03*
Y624648D03*
X625759D03*
X623559Y626848D03*
X625759D03*
X623559Y1077404D03*
X625759D03*
X623559Y1079604D03*
X625759D03*
X747772Y174092D03*
Y171892D03*
Y624648D03*
Y626848D03*
Y1077404D03*
Y1079604D03*
X749972Y174092D03*
Y171892D03*
Y624648D03*
Y626848D03*
Y1077404D03*
Y1079604D03*
G54D60*
X429724Y63977D03*
X443898D03*
X458071D03*
X436811Y67914D03*
X450984D03*
X429724Y116339D03*
Y92323D03*
Y96654D03*
Y102166D03*
Y106496D03*
Y110827D03*
Y78150D03*
X443898Y116339D03*
X458071D03*
X436811Y114764D03*
X450984D03*
X436811Y82087D03*
X450984D03*
X443898Y92323D03*
X458071D03*
X443898Y96654D03*
X458071D03*
X436811Y96260D03*
X450984D03*
X443898Y102166D03*
X458071D03*
X436811Y100591D03*
X450984D03*
X443898Y106496D03*
X458071D03*
X436811Y106103D03*
X450984D03*
X443898Y110827D03*
X458071D03*
X436811Y110433D03*
X450984D03*
X443898Y78150D03*
X458071D03*
X429724Y120670D03*
X443898D03*
X458071D03*
X436811Y120276D03*
X450984D03*
X465157Y67914D03*
X472244Y63977D03*
X479331Y67914D03*
X465157Y114764D03*
X472244Y116339D03*
X479331Y114764D03*
X465157Y82087D03*
Y96260D03*
Y100591D03*
Y106103D03*
Y110433D03*
X479331Y82087D03*
X472244Y92323D03*
Y96654D03*
X479331Y96260D03*
X472244Y102166D03*
X479331Y100591D03*
X472244Y106496D03*
X479331Y106103D03*
X472244Y110827D03*
X479331Y110433D03*
X472244Y78150D03*
X465157Y120276D03*
X472244Y120670D03*
X479331Y120276D03*
X514764Y63977D03*
X550197Y67914D03*
X536024D03*
X521850D03*
X543110Y63977D03*
X528937D03*
X557283D03*
X514764Y116339D03*
Y110827D03*
Y106496D03*
Y102166D03*
Y96654D03*
Y92323D03*
Y78150D03*
X550197Y114764D03*
X536024D03*
X521850D03*
X543110Y116339D03*
X528937D03*
X550197Y110433D03*
X536024D03*
X521850D03*
X543110Y110827D03*
X528937D03*
X550197Y106103D03*
X536024D03*
X521850D03*
X543110Y106496D03*
X528937D03*
X550197Y100591D03*
X536024D03*
X521850D03*
X543110Y102166D03*
X528937D03*
X550197Y96260D03*
X536024D03*
X521850D03*
X543110Y96654D03*
X528937D03*
X543110Y92323D03*
X528937D03*
X550197Y82087D03*
X536024D03*
X521850D03*
X543110Y78150D03*
X528937D03*
X557283Y116339D03*
Y110827D03*
Y106496D03*
Y102166D03*
Y96654D03*
Y92323D03*
Y78150D03*
X514764Y120670D03*
X550197Y120276D03*
X536024D03*
X521850D03*
X543110Y120670D03*
X528937D03*
X557283D03*
X564370Y67914D03*
Y114764D03*
Y110433D03*
Y106103D03*
Y100591D03*
Y96260D03*
Y82087D03*
Y120276D03*
X833859Y1594095D03*
Y1598425D03*
Y1603937D03*
Y1608268D03*
Y1612599D03*
X840945Y1598032D03*
X826772D03*
X840945Y1602363D03*
X826772D03*
X840945Y1607874D03*
X826772D03*
X840945Y1612205D03*
X826772D03*
X840945Y1616536D03*
X826772D03*
X833859Y1618111D03*
Y1622441D03*
Y1626772D03*
Y1632284D03*
Y1636614D03*
Y1640945D03*
Y1646457D03*
Y1650788D03*
X840945Y1622048D03*
X826772D03*
X840945Y1626378D03*
X826772D03*
X840945Y1630709D03*
X826772D03*
X840945Y1636221D03*
X826772D03*
X840945Y1640551D03*
X826772D03*
X840945Y1644882D03*
X826772D03*
X840945Y1650394D03*
X826772D03*
X876378Y1594095D03*
X862205D03*
X848032D03*
X876378Y1598425D03*
X862205D03*
X848032D03*
X876378Y1603937D03*
X862205D03*
X848032D03*
X876378Y1608268D03*
X862205D03*
X848032D03*
X876378Y1612599D03*
X862205D03*
X848032D03*
X890552Y1598032D03*
X869292D03*
X855118D03*
X890552Y1602363D03*
X869292D03*
X855118D03*
X890552Y1607874D03*
X869292D03*
X855118D03*
X890552Y1612205D03*
X869292D03*
X855118D03*
X890552Y1616536D03*
X869292D03*
X855118D03*
X876378Y1618111D03*
X862205D03*
X848032D03*
X876378Y1622441D03*
X862205D03*
X848032D03*
X876378Y1626772D03*
X862205D03*
X848032D03*
X876378Y1632284D03*
X862205D03*
X848032D03*
X876378Y1636614D03*
X862205D03*
X848032D03*
X876378Y1640945D03*
X862205D03*
X848032D03*
X876378Y1646457D03*
X862205D03*
X848032D03*
X876378Y1650788D03*
X862205D03*
X848032D03*
X890552Y1622048D03*
X869292D03*
X855118D03*
X890552Y1626378D03*
X869292D03*
X855118D03*
X890552Y1630709D03*
X869292D03*
X855118D03*
X890552Y1636221D03*
X869292D03*
X855118D03*
X890552Y1640551D03*
X869292D03*
X855118D03*
X890552Y1644882D03*
X869292D03*
X855118D03*
X890552Y1650394D03*
X869292D03*
X855118D03*
X911811Y1603937D03*
Y1608268D03*
Y1612599D03*
X904725Y1602363D03*
Y1607874D03*
Y1612205D03*
Y1616536D03*
X911811Y1594095D03*
Y1598425D03*
X904725Y1598032D03*
X897638Y1594095D03*
Y1598425D03*
Y1603937D03*
Y1608268D03*
Y1612599D03*
X911811Y1632284D03*
Y1636614D03*
Y1640945D03*
Y1646457D03*
Y1650788D03*
X904725Y1630709D03*
Y1636221D03*
Y1640551D03*
Y1644882D03*
Y1650394D03*
X911811Y1618111D03*
Y1622441D03*
Y1626772D03*
X904725Y1622048D03*
Y1626378D03*
X897638Y1618111D03*
Y1622441D03*
Y1626772D03*
Y1632284D03*
Y1636614D03*
Y1640945D03*
Y1646457D03*
Y1650788D03*
X1091089Y988592D03*
X1095420D03*
X1100932D03*
X1105262D03*
X1109593D03*
X1115105D03*
X1119435D03*
X1123766D03*
X1129278D03*
X1133609D03*
X1095026Y995678D03*
X1099357D03*
X1104869D03*
X1109199D03*
X1113530D03*
X1119042D03*
X1123372D03*
X1127703D03*
X1133215D03*
X1091089Y1002765D03*
X1095420D03*
X1100932D03*
X1105262D03*
X1109593D03*
X1115105D03*
X1119435D03*
X1123766D03*
X1129278D03*
X1133609D03*
X1095026Y1009852D03*
X1099357D03*
X1104869D03*
X1109199D03*
X1113530D03*
X1119042D03*
X1123372D03*
X1127703D03*
X1133215D03*
X1091089Y1016938D03*
X1095420D03*
X1100932D03*
X1105262D03*
X1109593D03*
X1115105D03*
X1119435D03*
X1123766D03*
X1129278D03*
X1133609D03*
X1095026Y1024025D03*
X1099357D03*
X1104869D03*
X1109199D03*
X1113530D03*
X1119042D03*
X1123372D03*
X1127703D03*
X1133215D03*
X1091089Y1031111D03*
X1095420D03*
X1100932D03*
X1105262D03*
X1109593D03*
X1115105D03*
X1119435D03*
X1123766D03*
X1129278D03*
X1133609D03*
X1095026Y1038198D03*
X1099357D03*
X1104869D03*
X1109199D03*
X1113530D03*
X1119042D03*
X1123372D03*
X1127703D03*
X1133215D03*
X1091089Y1160257D03*
Y1174430D03*
X1095420Y1160257D03*
Y1174430D03*
X1100932Y1160257D03*
Y1174430D03*
X1105262Y1160257D03*
Y1174430D03*
X1109593Y1160257D03*
Y1174430D03*
X1115105Y1160257D03*
Y1174430D03*
X1119435Y1160257D03*
Y1174430D03*
X1123766Y1160257D03*
Y1174430D03*
X1129278Y1160257D03*
Y1174430D03*
X1133609Y1160257D03*
Y1174430D03*
X1095026Y1167343D03*
X1099357D03*
X1104869D03*
X1109199D03*
X1113530D03*
X1119042D03*
X1123372D03*
X1127703D03*
X1133215D03*
X1091089Y1188603D03*
Y1202776D03*
Y1216949D03*
X1095420Y1188603D03*
Y1202776D03*
Y1216949D03*
X1100932Y1188603D03*
Y1202776D03*
Y1216949D03*
X1105262Y1188603D03*
Y1202776D03*
Y1216949D03*
X1109593Y1188603D03*
Y1202776D03*
Y1216949D03*
X1115105Y1188603D03*
Y1202776D03*
Y1216949D03*
X1119435Y1188603D03*
Y1202776D03*
Y1216949D03*
X1123766Y1188603D03*
Y1202776D03*
Y1216949D03*
X1129278Y1188603D03*
Y1202776D03*
Y1216949D03*
X1133609Y1188603D03*
Y1202776D03*
Y1216949D03*
X1095026Y1181516D03*
Y1195690D03*
Y1209863D03*
Y1224036D03*
X1099357Y1181516D03*
Y1195690D03*
Y1209863D03*
Y1224036D03*
X1104869Y1181516D03*
Y1195690D03*
Y1209863D03*
Y1224036D03*
X1109199Y1181516D03*
Y1195690D03*
Y1209863D03*
Y1224036D03*
X1113530Y1181516D03*
Y1195690D03*
Y1209863D03*
Y1224036D03*
X1119042Y1181516D03*
Y1195690D03*
Y1209863D03*
Y1224036D03*
X1123372Y1181516D03*
Y1195690D03*
Y1209863D03*
Y1224036D03*
X1127703Y1181516D03*
Y1195690D03*
Y1209863D03*
Y1224036D03*
X1133215Y1181516D03*
Y1195690D03*
Y1209863D03*
Y1224036D03*
X1091089Y1231123D03*
Y1245296D03*
Y1259469D03*
Y1273642D03*
X1095420Y1231123D03*
Y1245296D03*
Y1259469D03*
Y1273642D03*
X1100932Y1231123D03*
Y1245296D03*
Y1259469D03*
Y1273642D03*
X1105262Y1231123D03*
Y1245296D03*
Y1259469D03*
Y1273642D03*
X1109593Y1231123D03*
Y1245296D03*
Y1259469D03*
Y1273642D03*
X1115105Y1231123D03*
Y1245296D03*
Y1259469D03*
Y1273642D03*
X1119435Y1231123D03*
Y1245296D03*
Y1259469D03*
Y1273642D03*
X1123766Y1231123D03*
Y1245296D03*
Y1259469D03*
Y1273642D03*
X1129278Y1231123D03*
Y1245296D03*
Y1259469D03*
Y1273642D03*
X1133609Y1231123D03*
Y1245296D03*
Y1259469D03*
Y1273642D03*
X1095026Y1238209D03*
Y1252382D03*
Y1266556D03*
X1099357Y1238209D03*
Y1252382D03*
Y1266556D03*
X1104869Y1238209D03*
Y1252382D03*
Y1266556D03*
X1109199Y1238209D03*
Y1252382D03*
Y1266556D03*
X1113530Y1238209D03*
Y1252382D03*
Y1266556D03*
X1119042Y1238209D03*
Y1252382D03*
Y1266556D03*
X1123372Y1238209D03*
Y1252382D03*
Y1266556D03*
X1127703Y1238209D03*
Y1252382D03*
Y1266556D03*
X1133215Y1238209D03*
Y1252382D03*
Y1266556D03*
X1091089Y1287816D03*
Y1301989D03*
Y1316162D03*
X1095420Y1287816D03*
Y1301989D03*
Y1316162D03*
X1100932Y1287816D03*
Y1301989D03*
Y1316162D03*
X1105262Y1287816D03*
Y1301989D03*
Y1316162D03*
X1109593Y1287816D03*
Y1301989D03*
Y1316162D03*
X1115105Y1287816D03*
Y1301989D03*
Y1316162D03*
X1119435Y1287816D03*
Y1301989D03*
Y1316162D03*
X1123766Y1287816D03*
Y1301989D03*
Y1316162D03*
X1129278Y1287816D03*
Y1301989D03*
Y1316162D03*
X1133609Y1287816D03*
Y1301989D03*
Y1316162D03*
X1095026Y1280729D03*
Y1294902D03*
Y1309075D03*
Y1323249D03*
X1099357Y1280729D03*
Y1294902D03*
Y1309075D03*
Y1323249D03*
X1104869Y1280729D03*
Y1294902D03*
Y1309075D03*
Y1323249D03*
X1109199Y1280729D03*
Y1294902D03*
Y1309075D03*
Y1323249D03*
X1113530Y1280729D03*
Y1294902D03*
Y1309075D03*
Y1323249D03*
X1119042Y1280729D03*
Y1294902D03*
Y1309075D03*
Y1323249D03*
X1123372Y1280729D03*
Y1294902D03*
Y1309075D03*
Y1323249D03*
X1127703Y1280729D03*
Y1294902D03*
Y1309075D03*
Y1323249D03*
X1133215Y1280729D03*
Y1294902D03*
Y1309075D03*
Y1323249D03*
X1091089Y1330335D03*
Y1344508D03*
Y1358682D03*
Y1372855D03*
X1095420Y1330335D03*
Y1344508D03*
Y1358682D03*
Y1372855D03*
X1100932Y1330335D03*
Y1344508D03*
Y1358682D03*
Y1372855D03*
X1105262Y1330335D03*
Y1344508D03*
Y1358682D03*
Y1372855D03*
X1109593Y1330335D03*
Y1344508D03*
Y1358682D03*
Y1372855D03*
X1115105Y1330335D03*
Y1344508D03*
Y1358682D03*
Y1372855D03*
X1119435Y1330335D03*
Y1344508D03*
Y1358682D03*
Y1372855D03*
X1123766Y1330335D03*
Y1344508D03*
Y1358682D03*
Y1372855D03*
X1129278Y1330335D03*
Y1344508D03*
Y1358682D03*
Y1372855D03*
X1133609Y1330335D03*
Y1344508D03*
Y1358682D03*
Y1372855D03*
X1095026Y1337422D03*
Y1351595D03*
Y1365768D03*
X1099357Y1337422D03*
Y1351595D03*
Y1365768D03*
X1104869Y1337422D03*
Y1351595D03*
Y1365768D03*
X1109199Y1337422D03*
Y1351595D03*
Y1365768D03*
X1113530Y1337422D03*
Y1351595D03*
Y1365768D03*
X1119042Y1337422D03*
Y1351595D03*
Y1365768D03*
X1123372Y1337422D03*
Y1351595D03*
Y1365768D03*
X1127703Y1337422D03*
Y1351595D03*
Y1365768D03*
X1133215Y1337422D03*
Y1351595D03*
Y1365768D03*
X1091089Y1387028D03*
Y1401201D03*
X1095420Y1387028D03*
Y1401201D03*
X1100932Y1387028D03*
Y1401201D03*
X1105262Y1387028D03*
Y1401201D03*
X1109593Y1387028D03*
Y1401201D03*
X1115105Y1387028D03*
Y1401201D03*
X1119435Y1387028D03*
Y1401201D03*
X1123766Y1387028D03*
Y1401201D03*
X1129278Y1387028D03*
Y1401201D03*
X1133609Y1387028D03*
Y1401201D03*
X1095026Y1379942D03*
Y1394115D03*
Y1408288D03*
X1099357Y1379942D03*
Y1394115D03*
Y1408288D03*
X1104869Y1379942D03*
Y1394115D03*
Y1408288D03*
X1109199Y1379942D03*
Y1394115D03*
Y1408288D03*
X1113530Y1379942D03*
Y1394115D03*
Y1408288D03*
X1119042Y1379942D03*
Y1394115D03*
Y1408288D03*
X1123372Y1379942D03*
Y1394115D03*
Y1408288D03*
X1127703Y1379942D03*
Y1394115D03*
Y1408288D03*
X1133215Y1379942D03*
Y1394115D03*
Y1408288D03*
X1398228Y63977D03*
X1412402D03*
X1426575D03*
X1405315Y67914D03*
X1419488D03*
X1398228Y116339D03*
Y92323D03*
Y96654D03*
Y102166D03*
Y106496D03*
Y110827D03*
Y78150D03*
X1412402Y116339D03*
X1426575D03*
X1405315Y114764D03*
X1419488D03*
X1405315Y82087D03*
X1419488D03*
X1412402Y92323D03*
X1426575D03*
X1412402Y96654D03*
X1426575D03*
X1405315Y96260D03*
X1419488D03*
X1412402Y102166D03*
X1426575D03*
X1405315Y100591D03*
X1419488D03*
X1412402Y106496D03*
X1426575D03*
X1405315Y106103D03*
X1419488D03*
X1412402Y110827D03*
X1426575D03*
X1405315Y110433D03*
X1419488D03*
X1412402Y78150D03*
X1426575D03*
X1398228Y120670D03*
X1412402D03*
X1426575D03*
X1405315Y120276D03*
X1419488D03*
X1433661Y67914D03*
X1440748Y63977D03*
X1447835Y67914D03*
X1433661Y114764D03*
X1440748Y116339D03*
X1447835Y114764D03*
X1433661Y82087D03*
Y96260D03*
Y100591D03*
Y106103D03*
Y110433D03*
X1447835Y82087D03*
X1440748Y92323D03*
Y96654D03*
X1447835Y96260D03*
X1440748Y102166D03*
X1447835Y100591D03*
X1440748Y106496D03*
X1447835Y106103D03*
X1440748Y110827D03*
X1447835Y110433D03*
X1440748Y78150D03*
X1433661Y120276D03*
X1440748Y120670D03*
X1447835Y120276D03*
X1483268Y63977D03*
X1518701Y67914D03*
X1504528D03*
X1490354D03*
X1511614Y63977D03*
X1497441D03*
X1483268Y116339D03*
Y110827D03*
Y106496D03*
Y102166D03*
Y96654D03*
Y92323D03*
Y78150D03*
X1518701Y114764D03*
X1504528D03*
X1490354D03*
X1511614Y116339D03*
X1497441D03*
X1518701Y110433D03*
X1504528D03*
X1490354D03*
X1511614Y110827D03*
X1497441D03*
X1518701Y106103D03*
X1504528D03*
X1490354D03*
X1511614Y106496D03*
X1497441D03*
X1518701Y100591D03*
X1504528D03*
X1490354D03*
X1511614Y102166D03*
X1497441D03*
X1518701Y96260D03*
X1504528D03*
X1490354D03*
X1511614Y96654D03*
X1497441D03*
X1511614Y92323D03*
X1497441D03*
X1518701Y82087D03*
X1504528D03*
X1490354D03*
X1511614Y78150D03*
X1497441D03*
X1483268Y120670D03*
X1518701Y120276D03*
X1504528D03*
X1490354D03*
X1511614Y120670D03*
X1497441D03*
X1532874Y67914D03*
X1525787Y63977D03*
X1532874Y114764D03*
X1525787Y116339D03*
X1532874Y110433D03*
X1525787Y110827D03*
X1532874Y106103D03*
X1525787Y106496D03*
X1532874Y100591D03*
X1525787Y102166D03*
X1532874Y96260D03*
X1525787Y96654D03*
Y92323D03*
X1532874Y82087D03*
X1525787Y78150D03*
X1532874Y120276D03*
X1525787Y120670D03*
G54D118*
G01X77877Y187461D02*
X74937D01*
G01X82997Y194861D02*
X86637D01*
G01X82997Y647617D02*
X86637D01*
G01X77877Y640217D02*
X74937D01*
G01X82997Y1100373D02*
X86637D01*
G01X77877Y1092973D02*
X74937D01*
G01X207209Y194861D02*
X210849D01*
G01X202089Y187461D02*
X199149D01*
G01X207409Y638617D02*
X210849D01*
G01X202289Y631217D02*
X199149D01*
G01X207209Y1100373D02*
X210849D01*
G01X202089Y1092973D02*
X199149D01*
G01X326302Y187461D02*
X323362D01*
G01X331422Y194861D02*
X335062D01*
G01X331422Y647617D02*
X335062D01*
G01X326302Y640217D02*
X323362D01*
G01X331422Y1100373D02*
X335062D01*
G01X326302Y1092973D02*
X323362D01*
G01X450514Y187461D02*
X447574D01*
G01X455634Y194861D02*
X461122D01*
G01X455634Y647617D02*
X459274D01*
G01X450514Y640217D02*
X447574D01*
G01X453473Y1086386D02*
Y1089300D01*
G01X460873Y1081266D02*
Y1077526D01*
G01X568687Y187660D02*
X568700D01*
Y187600D01*
X570470D01*
X570609Y187461D01*
X574727D01*
G01X579847Y194861D02*
X583487D01*
G01X579847Y647617D02*
X583487D01*
G01X574727Y640217D02*
X571787D01*
G01X579847Y1100373D02*
X583487D01*
G01X574727Y1092973D02*
X571787D01*
G01X695137Y189130D02*
X696806Y187461D01*
X698940D01*
G01X699140Y641717D02*
X696000D01*
G01X698940Y1092973D02*
X696000D01*
G01X704060Y194861D02*
X707700D01*
G01X704260Y649117D02*
X707700D01*
G01X704060Y1100373D02*
X707700D01*
G01X1311200Y175601D02*
Y172661D01*
G01X1302074Y183779D02*
X1303800Y182053D01*
Y180721D01*
G01Y633477D02*
Y636417D01*
G01X1311200Y628357D02*
Y625417D01*
G01Y1081113D02*
Y1078173D01*
G01X1303800Y1086233D02*
Y1089173D01*
G01X1428013Y180721D02*
Y185956D01*
G01X1445994Y174086D02*
X1439867D01*
X1438352Y175601D01*
X1435413D01*
G01X1428013Y633477D02*
Y636417D01*
G01X1435413Y628357D02*
Y625417D01*
G01Y1081113D02*
Y1078173D01*
G01X1428013Y1086233D02*
Y1089173D01*
G01X1552225Y180721D02*
Y183661D01*
G01X1559625Y175601D02*
Y172661D01*
G01X1552225Y633477D02*
Y636417D01*
G01X1559625Y628357D02*
Y625417D01*
G01Y1081113D02*
Y1078173D01*
G01X1552225Y1086233D02*
Y1089173D01*
G01X1676438Y180721D02*
Y183661D01*
G01X1683838Y175601D02*
Y172661D01*
G01X1676438Y633477D02*
Y636417D01*
G01X1683838Y628357D02*
Y625417D01*
G01Y1081113D02*
Y1078173D01*
G01X1676438Y1086233D02*
Y1089173D01*
G01X1808050Y175601D02*
Y172661D01*
G01X1801988Y183904D02*
X1800650Y182566D01*
Y180721D01*
G01Y633477D02*
Y636417D01*
G01X1808050Y628357D02*
Y625417D01*
G01Y1081113D02*
Y1078173D01*
G01X1800650Y1086233D02*
Y1089173D01*
G01X1859117Y171015D02*
Y167375D01*
G01X1851717Y176135D02*
Y179075D01*
G01X1859117Y623771D02*
Y620131D01*
G01X1851717Y628891D02*
Y635331D01*
G54D25*
X64537Y205261D03*
X56637Y179561D03*
Y632317D03*
X64537Y657917D03*
X27593Y692869D03*
X27226Y667518D03*
X64537Y1110673D03*
X56537Y1085073D03*
X26806Y1120485D03*
X27173Y1145836D03*
X88837Y191161D03*
X85196Y629631D03*
X88837Y643917D03*
X116995Y999067D03*
X88837Y1096673D03*
X150303Y714355D03*
X150912Y1158233D03*
X150482Y1186220D03*
X180749Y179661D03*
X188749Y204961D03*
X213049Y191161D03*
X183695Y587067D03*
X213049Y633417D03*
X185199Y621417D03*
X201102Y620496D03*
X188449Y1106373D03*
X213049Y1096673D03*
X181027Y1094839D03*
X181039Y1099043D03*
X304962Y179661D03*
X312962Y205061D03*
X305062Y632417D03*
X312962Y657717D03*
X274570Y714099D03*
X312962Y1110573D03*
X304962Y1085173D03*
X275126Y1158233D03*
X274696Y1186220D03*
X315755Y68379D03*
X326079Y68345D03*
X337262Y191161D03*
X333732Y629429D03*
X337262Y644017D03*
X337362Y1096773D03*
X398727Y714027D03*
X398953Y1185011D03*
X429274Y179661D03*
X437174Y205061D03*
X457903Y629682D03*
X429274Y632317D03*
X437274Y657817D03*
X449973Y1104326D03*
X461474Y191161D03*
Y643917D03*
X504774Y1110573D03*
X553387Y179561D03*
X553487Y632317D03*
X522823Y714280D03*
X553487Y1085173D03*
X523051Y1163084D03*
X522917Y1186666D03*
X585687Y191161D03*
X561487Y204861D03*
X589079Y566331D03*
X585687Y643917D03*
X561487Y657717D03*
X561387Y1110473D03*
X585687Y1096673D03*
X613558Y538745D03*
Y542745D03*
X647257Y714197D03*
X647766Y1160810D03*
X647176Y1186007D03*
X690857Y107247D03*
X685600Y205161D03*
X677600Y179561D03*
X682050Y631917D03*
X697953Y630996D03*
X685600Y657917D03*
X685300Y1106273D03*
X677200Y1093100D03*
X709900Y191161D03*
Y643917D03*
Y1096673D03*
X881800Y41500D03*
X874857Y378495D03*
X879573Y816103D03*
X871123Y814580D03*
X877673Y856903D03*
X933581Y912047D03*
X933313Y1028083D03*
X933224Y1032390D03*
X958300Y1552700D03*
X1019168Y-40100D03*
X1038858Y-75936D03*
X1010700Y58900D03*
Y63600D03*
Y54200D03*
X1011472Y545207D03*
X1011406Y554532D03*
X1030814Y872741D03*
X1038673Y872703D03*
X1029529Y1324216D03*
X1034653Y1349992D03*
X1029529Y1337616D03*
X1029629Y1342668D03*
X1029529Y1330916D03*
X1085868Y-87500D03*
X1062171Y-80978D03*
X1085850Y-60300D03*
X1066218Y22405D03*
X1040773Y835703D03*
X1100900Y-78400D03*
X1109921Y-80838D03*
X1100979Y-86862D03*
X1177002Y96794D03*
X1176849Y101360D03*
X1179600Y249800D03*
X1187432D03*
X1226247Y1145325D03*
X1253300Y244861D03*
X1240364Y1145413D03*
X1310621Y90855D03*
Y86155D03*
X1329300Y194661D03*
Y647417D03*
Y1100173D03*
X1342303Y133842D03*
X1360528Y542311D03*
X1375513Y697517D03*
X1361954Y1123365D03*
X1375513Y1150273D03*
X1361263Y1147073D03*
X1414369Y520457D03*
Y527857D03*
X1422000Y549600D03*
Y553600D03*
X1453513Y194661D03*
X1448500Y526100D03*
X1456500D03*
X1429000Y540100D03*
X1453513Y647417D03*
Y1100173D03*
X1499825Y244661D03*
X1483400Y525900D03*
X1480400Y530900D03*
X1482400Y560400D03*
Y556100D03*
X1499725Y697517D03*
X1485658Y1117943D03*
X1499725Y1150373D03*
X1485883Y1144062D03*
X1577725Y194661D03*
X1572725Y649417D03*
X1586825Y1093873D03*
X1625538Y244661D03*
X1623938Y697517D03*
X1624113Y1128071D03*
X1624348Y1106754D03*
X1635738Y1150273D03*
X1701938Y194661D03*
Y647417D03*
Y1100173D03*
X1750350Y244661D03*
X1758795Y1011067D03*
X1733295Y1120127D03*
X1748150Y1150273D03*
X1733491Y1145478D03*
X1826150Y194661D03*
X1856269Y204961D03*
X1848317Y194075D03*
X1826150Y647417D03*
X1848317Y646831D03*
X1856269Y657817D03*
X1826150Y1100173D03*
X1856391Y1098787D03*
X1848296Y1098813D03*
G54D16*
X25000Y1200800D03*
X30000D03*
X95437Y295961D03*
Y748717D03*
Y1201473D03*
X135422Y1201337D03*
X140422D03*
X219649Y295961D03*
Y748717D03*
X259594Y1201168D03*
X264594D03*
X219649Y1201473D03*
X343862Y295961D03*
Y748717D03*
Y1201473D03*
X383849Y1201042D03*
X388849D03*
X468074Y295961D03*
Y748717D03*
X508103Y1200957D03*
X468074Y1201473D03*
X513103Y1200957D03*
X592287Y295961D03*
X584279Y572631D03*
X592287Y748717D03*
Y1201473D03*
X607460Y566574D03*
X632316Y1200874D03*
X637316D03*
X716500Y295961D03*
Y748717D03*
Y1201473D03*
X751209Y165428D03*
X752500Y1163300D03*
X881256Y1370750D03*
X933524Y927700D03*
X967813Y1559566D03*
X953500Y1559000D03*
X1211205Y1161994D03*
X1216205D03*
X1298500Y295461D03*
Y265961D03*
Y718717D03*
Y748217D03*
Y1171473D03*
Y1200973D03*
X1351321Y1161953D03*
X1346321D03*
X1422713Y295461D03*
Y265961D03*
X1426419Y532557D03*
X1422713Y718717D03*
Y748217D03*
Y1171473D03*
Y1200973D03*
X1470953Y1161827D03*
X1475953D03*
X1507037Y533703D03*
X1546925Y295461D03*
Y265961D03*
Y718717D03*
Y748217D03*
Y1171473D03*
Y1200973D03*
X1615552Y1162006D03*
X1620236D03*
X1671138Y295461D03*
Y265961D03*
Y718717D03*
Y748217D03*
Y1171473D03*
Y1200973D03*
X1760500Y730800D03*
X1723117Y1161953D03*
X1718117D03*
X1795350Y295461D03*
Y265961D03*
Y718717D03*
X1795468Y748394D03*
X1795350Y1171473D03*
Y1200973D03*
X1836400Y1161500D03*
X1841084Y1161521D03*
X1887169Y295961D03*
Y748717D03*
Y1201473D03*
G54D109*
X1384950Y573397D03*
Y579803D03*
G54D43*
X118209Y195492D03*
Y190492D03*
Y185492D03*
Y180492D03*
Y175492D03*
Y170492D03*
Y165492D03*
Y260492D03*
Y255492D03*
Y250492D03*
Y245492D03*
Y240492D03*
Y235492D03*
Y230492D03*
Y225492D03*
Y220492D03*
Y290492D03*
Y285492D03*
Y280492D03*
Y275492D03*
Y270492D03*
Y265492D03*
Y648248D03*
Y643248D03*
Y638248D03*
Y633248D03*
Y628248D03*
Y623248D03*
Y618248D03*
Y693248D03*
Y688248D03*
Y683248D03*
Y678248D03*
Y673248D03*
Y743248D03*
Y738248D03*
Y733248D03*
Y728248D03*
Y723248D03*
Y718248D03*
Y713248D03*
Y708248D03*
Y703248D03*
Y698248D03*
Y1081004D03*
Y1076004D03*
Y1071004D03*
Y1131004D03*
Y1126004D03*
Y1101004D03*
Y1096004D03*
Y1091004D03*
Y1086004D03*
Y1176004D03*
Y1171004D03*
Y1166004D03*
Y1161004D03*
Y1156004D03*
Y1151004D03*
Y1146004D03*
Y1141004D03*
Y1136004D03*
Y1196004D03*
Y1191004D03*
Y1186004D03*
Y1181004D03*
X242421Y195492D03*
Y190492D03*
Y185492D03*
Y180492D03*
Y175492D03*
Y170492D03*
Y165492D03*
Y260492D03*
Y255492D03*
Y250492D03*
Y245492D03*
Y240492D03*
Y235492D03*
Y230492D03*
Y225492D03*
Y220492D03*
Y290492D03*
Y285492D03*
Y280492D03*
Y275492D03*
Y270492D03*
Y265492D03*
Y648248D03*
Y643248D03*
Y638248D03*
Y633248D03*
Y628248D03*
Y623248D03*
Y618248D03*
Y693248D03*
Y688248D03*
Y683248D03*
Y678248D03*
Y673248D03*
Y743248D03*
Y738248D03*
Y733248D03*
Y728248D03*
Y723248D03*
Y718248D03*
Y713248D03*
Y708248D03*
Y703248D03*
Y698248D03*
Y1081004D03*
Y1076004D03*
Y1071004D03*
Y1131004D03*
Y1126004D03*
Y1101004D03*
Y1096004D03*
Y1091004D03*
Y1086004D03*
Y1176004D03*
Y1171004D03*
Y1166004D03*
Y1161004D03*
Y1156004D03*
Y1151004D03*
Y1146004D03*
Y1141004D03*
Y1136004D03*
Y1196004D03*
Y1191004D03*
Y1186004D03*
Y1181004D03*
X366634Y195492D03*
Y190492D03*
Y185492D03*
Y180492D03*
Y175492D03*
Y170492D03*
Y165492D03*
Y260492D03*
Y255492D03*
Y250492D03*
Y245492D03*
Y240492D03*
Y235492D03*
Y230492D03*
Y225492D03*
Y220492D03*
Y290492D03*
Y285492D03*
Y280492D03*
Y275492D03*
Y270492D03*
Y265492D03*
Y648248D03*
Y643248D03*
Y638248D03*
Y633248D03*
Y628248D03*
Y623248D03*
Y618248D03*
Y693248D03*
Y688248D03*
Y683248D03*
Y678248D03*
Y673248D03*
Y743248D03*
Y738248D03*
Y733248D03*
Y728248D03*
Y723248D03*
Y718248D03*
Y713248D03*
Y708248D03*
Y703248D03*
Y698248D03*
Y1081004D03*
Y1076004D03*
Y1071004D03*
Y1131004D03*
Y1126004D03*
Y1101004D03*
Y1096004D03*
Y1091004D03*
Y1086004D03*
Y1176004D03*
Y1171004D03*
Y1166004D03*
Y1161004D03*
Y1156004D03*
Y1151004D03*
Y1146004D03*
Y1141004D03*
Y1136004D03*
Y1196004D03*
Y1191004D03*
Y1186004D03*
Y1181004D03*
X490846Y195492D03*
Y190492D03*
Y185492D03*
Y180492D03*
Y175492D03*
Y170492D03*
Y165492D03*
Y260492D03*
Y255492D03*
Y250492D03*
Y245492D03*
Y240492D03*
Y235492D03*
Y230492D03*
Y225492D03*
Y220492D03*
Y290492D03*
Y285492D03*
Y280492D03*
Y275492D03*
Y270492D03*
Y265492D03*
Y648248D03*
Y643248D03*
Y638248D03*
Y633248D03*
Y628248D03*
Y623248D03*
Y618248D03*
Y693248D03*
Y688248D03*
Y683248D03*
Y678248D03*
Y673248D03*
Y743248D03*
Y738248D03*
Y733248D03*
Y728248D03*
Y723248D03*
Y718248D03*
Y713248D03*
Y708248D03*
Y703248D03*
Y698248D03*
Y1081004D03*
Y1076004D03*
Y1071004D03*
Y1131004D03*
Y1126004D03*
Y1101004D03*
Y1096004D03*
Y1091004D03*
Y1086004D03*
Y1176004D03*
Y1171004D03*
Y1166004D03*
Y1161004D03*
Y1156004D03*
Y1151004D03*
Y1146004D03*
Y1141004D03*
Y1136004D03*
Y1196004D03*
Y1191004D03*
Y1186004D03*
Y1181004D03*
X615059Y195492D03*
Y190492D03*
Y185492D03*
Y180492D03*
Y175492D03*
Y170492D03*
Y165492D03*
Y260492D03*
Y255492D03*
Y250492D03*
Y245492D03*
Y240492D03*
Y235492D03*
Y230492D03*
Y225492D03*
Y220492D03*
Y290492D03*
Y285492D03*
Y280492D03*
Y275492D03*
Y270492D03*
Y265492D03*
Y648248D03*
Y643248D03*
Y638248D03*
Y633248D03*
Y628248D03*
Y623248D03*
Y618248D03*
Y693248D03*
Y688248D03*
Y683248D03*
Y678248D03*
Y673248D03*
Y743248D03*
Y738248D03*
Y733248D03*
Y728248D03*
Y723248D03*
Y718248D03*
Y713248D03*
Y708248D03*
Y703248D03*
Y698248D03*
Y1081004D03*
Y1076004D03*
Y1071004D03*
Y1131004D03*
Y1126004D03*
Y1101004D03*
Y1096004D03*
Y1091004D03*
Y1086004D03*
Y1176004D03*
Y1171004D03*
Y1166004D03*
Y1161004D03*
Y1156004D03*
Y1151004D03*
Y1146004D03*
Y1141004D03*
Y1136004D03*
Y1196004D03*
Y1191004D03*
Y1186004D03*
Y1181004D03*
X739272Y195492D03*
Y190492D03*
Y185492D03*
Y180492D03*
Y175492D03*
Y170492D03*
Y165492D03*
Y260492D03*
Y255492D03*
Y250492D03*
Y245492D03*
Y240492D03*
Y235492D03*
Y230492D03*
Y225492D03*
Y220492D03*
Y290492D03*
Y285492D03*
Y280492D03*
Y275492D03*
Y270492D03*
Y265492D03*
Y648248D03*
Y643248D03*
Y638248D03*
Y633248D03*
Y628248D03*
Y623248D03*
Y618248D03*
Y693248D03*
Y688248D03*
Y683248D03*
Y678248D03*
Y673248D03*
Y743248D03*
Y738248D03*
Y733248D03*
Y728248D03*
Y723248D03*
Y718248D03*
Y713248D03*
Y708248D03*
Y703248D03*
Y698248D03*
Y1081004D03*
Y1076004D03*
Y1071004D03*
Y1131004D03*
Y1126004D03*
Y1101004D03*
Y1096004D03*
Y1091004D03*
Y1086004D03*
Y1176004D03*
Y1171004D03*
Y1166004D03*
Y1161004D03*
Y1156004D03*
Y1151004D03*
Y1146004D03*
Y1141004D03*
Y1136004D03*
Y1196004D03*
Y1191004D03*
Y1186004D03*
Y1181004D03*
X1288878Y195492D03*
Y190492D03*
Y185492D03*
Y180492D03*
Y175492D03*
Y170492D03*
Y165492D03*
Y260492D03*
Y255492D03*
Y250492D03*
Y245492D03*
Y240492D03*
Y235492D03*
Y230492D03*
Y225492D03*
Y220492D03*
Y290492D03*
Y285492D03*
Y280492D03*
Y275492D03*
Y270492D03*
Y265492D03*
Y648248D03*
Y643248D03*
Y638248D03*
Y633248D03*
Y628248D03*
Y623248D03*
Y618248D03*
Y693248D03*
Y688248D03*
Y683248D03*
Y678248D03*
Y673248D03*
Y743248D03*
Y738248D03*
Y733248D03*
Y728248D03*
Y723248D03*
Y718248D03*
Y713248D03*
Y708248D03*
Y703248D03*
Y698248D03*
Y1081004D03*
Y1076004D03*
Y1071004D03*
Y1131004D03*
Y1126004D03*
Y1101004D03*
Y1096004D03*
Y1091004D03*
Y1086004D03*
Y1176004D03*
Y1171004D03*
Y1166004D03*
Y1161004D03*
Y1156004D03*
Y1151004D03*
Y1146004D03*
Y1141004D03*
Y1136004D03*
Y1196004D03*
Y1191004D03*
Y1186004D03*
Y1181004D03*
X1413091Y195492D03*
Y190492D03*
Y185492D03*
Y180492D03*
Y175492D03*
Y170492D03*
Y165492D03*
Y260492D03*
Y255492D03*
Y250492D03*
Y245492D03*
Y240492D03*
Y235492D03*
Y230492D03*
Y225492D03*
Y220492D03*
Y290492D03*
Y285492D03*
Y280492D03*
Y275492D03*
Y270492D03*
Y265492D03*
Y648248D03*
Y643248D03*
Y638248D03*
Y633248D03*
Y628248D03*
Y623248D03*
Y618248D03*
Y693248D03*
Y688248D03*
Y683248D03*
Y678248D03*
Y673248D03*
Y743248D03*
Y738248D03*
Y733248D03*
Y728248D03*
Y723248D03*
Y718248D03*
Y713248D03*
Y708248D03*
Y703248D03*
Y698248D03*
Y1081004D03*
Y1076004D03*
Y1071004D03*
Y1131004D03*
Y1126004D03*
Y1101004D03*
Y1096004D03*
Y1091004D03*
Y1086004D03*
Y1176004D03*
Y1171004D03*
Y1166004D03*
Y1161004D03*
Y1156004D03*
Y1151004D03*
Y1146004D03*
Y1141004D03*
Y1136004D03*
Y1196004D03*
Y1191004D03*
Y1186004D03*
Y1181004D03*
X1537303Y195492D03*
Y190492D03*
Y185492D03*
Y180492D03*
Y175492D03*
Y170492D03*
Y165492D03*
Y260492D03*
Y255492D03*
Y250492D03*
Y245492D03*
Y240492D03*
Y235492D03*
Y230492D03*
Y225492D03*
Y220492D03*
Y290492D03*
Y285492D03*
Y280492D03*
Y275492D03*
Y270492D03*
Y265492D03*
Y648248D03*
Y643248D03*
Y638248D03*
Y633248D03*
Y628248D03*
Y623248D03*
Y618248D03*
Y693248D03*
Y688248D03*
Y683248D03*
Y678248D03*
Y673248D03*
Y743248D03*
Y738248D03*
Y733248D03*
Y728248D03*
Y723248D03*
Y718248D03*
Y713248D03*
Y708248D03*
Y703248D03*
Y698248D03*
Y1081004D03*
Y1076004D03*
Y1071004D03*
Y1131004D03*
Y1126004D03*
Y1101004D03*
Y1096004D03*
Y1091004D03*
Y1086004D03*
Y1176004D03*
Y1171004D03*
Y1166004D03*
Y1161004D03*
Y1156004D03*
Y1151004D03*
Y1146004D03*
Y1141004D03*
Y1136004D03*
Y1196004D03*
Y1191004D03*
Y1186004D03*
Y1181004D03*
X1661516Y195492D03*
Y190492D03*
Y185492D03*
Y180492D03*
Y175492D03*
Y170492D03*
Y165492D03*
Y260492D03*
Y255492D03*
Y250492D03*
Y245492D03*
Y240492D03*
Y235492D03*
Y230492D03*
Y225492D03*
Y220492D03*
Y290492D03*
Y285492D03*
Y280492D03*
Y275492D03*
Y270492D03*
Y265492D03*
Y648248D03*
Y643248D03*
Y638248D03*
Y633248D03*
Y628248D03*
Y623248D03*
Y618248D03*
Y693248D03*
Y688248D03*
Y683248D03*
Y678248D03*
Y673248D03*
Y743248D03*
Y738248D03*
Y733248D03*
Y728248D03*
Y723248D03*
Y718248D03*
Y713248D03*
Y708248D03*
Y703248D03*
Y698248D03*
Y1081004D03*
Y1076004D03*
Y1071004D03*
Y1131004D03*
Y1126004D03*
Y1101004D03*
Y1096004D03*
Y1091004D03*
Y1086004D03*
Y1176004D03*
Y1171004D03*
Y1166004D03*
Y1161004D03*
Y1156004D03*
Y1151004D03*
Y1146004D03*
Y1141004D03*
Y1136004D03*
Y1196004D03*
Y1191004D03*
Y1186004D03*
Y1181004D03*
X1785728Y195492D03*
Y190492D03*
Y185492D03*
Y180492D03*
Y175492D03*
Y170492D03*
Y165492D03*
Y260492D03*
Y255492D03*
Y250492D03*
Y245492D03*
Y240492D03*
Y235492D03*
Y230492D03*
Y225492D03*
Y220492D03*
Y290492D03*
Y285492D03*
Y280492D03*
Y275492D03*
Y270492D03*
Y265492D03*
Y648248D03*
Y643248D03*
Y638248D03*
Y633248D03*
Y628248D03*
Y623248D03*
Y618248D03*
Y693248D03*
Y688248D03*
Y683248D03*
Y678248D03*
Y673248D03*
Y743248D03*
Y738248D03*
Y733248D03*
Y728248D03*
Y723248D03*
Y718248D03*
Y713248D03*
Y708248D03*
Y703248D03*
Y698248D03*
Y1081004D03*
Y1076004D03*
Y1071004D03*
Y1131004D03*
Y1126004D03*
Y1101004D03*
Y1096004D03*
Y1091004D03*
Y1086004D03*
Y1176004D03*
Y1171004D03*
Y1166004D03*
Y1161004D03*
Y1156004D03*
Y1151004D03*
Y1146004D03*
Y1141004D03*
Y1136004D03*
Y1196004D03*
Y1191004D03*
Y1186004D03*
Y1181004D03*
X1909941Y195492D03*
Y190492D03*
Y185492D03*
Y180492D03*
Y175492D03*
Y170492D03*
Y165492D03*
Y260492D03*
Y255492D03*
Y250492D03*
Y245492D03*
Y240492D03*
Y235492D03*
Y230492D03*
Y225492D03*
Y220492D03*
Y290492D03*
Y285492D03*
Y280492D03*
Y275492D03*
Y270492D03*
Y265492D03*
Y648248D03*
Y643248D03*
Y638248D03*
Y633248D03*
Y628248D03*
Y623248D03*
Y618248D03*
Y693248D03*
Y688248D03*
Y683248D03*
Y678248D03*
Y673248D03*
Y743248D03*
Y738248D03*
Y733248D03*
Y728248D03*
Y723248D03*
Y718248D03*
Y713248D03*
Y708248D03*
Y703248D03*
Y698248D03*
Y1081004D03*
Y1076004D03*
Y1071004D03*
Y1131004D03*
Y1126004D03*
Y1101004D03*
Y1096004D03*
Y1091004D03*
Y1086004D03*
Y1176004D03*
Y1171004D03*
Y1166004D03*
Y1161004D03*
Y1156004D03*
Y1151004D03*
Y1146004D03*
Y1141004D03*
Y1136004D03*
Y1196004D03*
Y1191004D03*
Y1186004D03*
Y1181004D03*
G54D70*
X580529Y547752D03*
Y545784D03*
Y543815D03*
Y541847D03*
Y539878D03*
Y537910D03*
X561029D03*
Y539878D03*
Y541847D03*
Y543815D03*
Y545784D03*
Y547752D03*
X930250Y1524279D03*
Y1526247D03*
Y1528216D03*
Y1530184D03*
Y1532153D03*
Y1534121D03*
X949750D03*
Y1532153D03*
Y1530184D03*
Y1528216D03*
Y1526247D03*
Y1524279D03*
X1447450Y544679D03*
Y546647D03*
Y548616D03*
Y550584D03*
X1466950D03*
Y548616D03*
Y546647D03*
Y544679D03*
X1447450Y552553D03*
Y554521D03*
X1466950D03*
Y552553D03*
G54D52*
X139637Y256161D03*
Y708917D03*
Y1161673D03*
X263849Y256161D03*
Y708917D03*
Y1161673D03*
X388062Y256161D03*
Y708917D03*
X387862Y1161673D03*
X500074Y1130873D03*
X512274Y256161D03*
Y708917D03*
X525874Y1152773D03*
X636487Y256161D03*
Y708917D03*
Y1161673D03*
X827508Y37372D03*
X862777Y37234D03*
X932209Y991763D03*
X909282Y1534500D03*
X1107500Y-48400D03*
X1429400Y544600D03*
X1454461Y588256D03*
X1498082Y539100D03*
X1881532Y1054227D03*
G54D34*
X60237Y214661D03*
Y667417D03*
Y1120173D03*
X142737Y240661D03*
Y693417D03*
X142056Y971762D03*
X142737Y1146173D03*
X184449Y214661D03*
X208756Y559762D03*
X206300Y644000D03*
X190199Y671689D03*
X190249Y1123673D03*
X308662Y214661D03*
X266949Y240661D03*
X308662Y667417D03*
X266949Y693417D03*
X308662Y1120173D03*
X266949Y1146173D03*
X342529Y58745D03*
X391162Y240661D03*
Y693417D03*
Y1146173D03*
X432874Y214661D03*
Y667417D03*
X453474Y1117073D03*
X503374Y1141973D03*
X515374Y240661D03*
Y693417D03*
X557087Y214661D03*
X601901Y530600D03*
X557087Y667417D03*
Y1120173D03*
X639587Y240661D03*
Y693417D03*
Y1146173D03*
X694117Y112738D03*
X681300Y214661D03*
X681800Y669917D03*
X687100Y1124073D03*
X753000Y209600D03*
X751800Y681800D03*
X851404Y1538590D03*
X935378Y995820D03*
X914846Y1530405D03*
X971122Y1516969D03*
X1034512Y-70708D03*
X1057833Y-76247D03*
X1086507Y1561743D03*
X1110888Y-55662D03*
X1311800Y195261D03*
Y648017D03*
Y1100773D03*
X1335300Y227761D03*
Y680517D03*
Y1133273D03*
X1436013Y195261D03*
X1459513Y227761D03*
X1436013Y648017D03*
X1459513Y680517D03*
X1436013Y1100773D03*
X1459513Y1133273D03*
X1560225Y195261D03*
X1555225Y650017D03*
X1552625Y1136373D03*
X1583725Y227761D03*
Y680517D03*
X1684438Y195261D03*
X1707938Y227761D03*
X1684438Y648017D03*
X1707938Y680517D03*
X1684438Y1100773D03*
X1707938Y1133273D03*
X1763300Y716500D03*
X1808650Y195261D03*
Y648017D03*
X1783856Y983762D03*
X1808650Y1100773D03*
X1851969Y214661D03*
X1832150Y227761D03*
X1851969Y667417D03*
X1832150Y680517D03*
X1858506Y1117394D03*
X1831750Y1133173D03*
X1884885Y1064038D03*
G54D61*
X429724Y68307D03*
X458071D03*
X443898D03*
X429724Y87993D03*
Y82481D03*
Y73819D03*
X458071Y87993D03*
Y82481D03*
X450984Y91930D03*
Y86418D03*
X443898Y87993D03*
Y82481D03*
X436811Y91930D03*
Y86418D03*
X458071Y73819D03*
X450984Y77756D03*
Y72245D03*
X443898Y73819D03*
X436811Y77756D03*
Y72245D03*
X472244Y68307D03*
X479331Y91930D03*
Y86418D03*
X472244Y87993D03*
Y82481D03*
X465157Y91930D03*
Y86418D03*
X479331Y77756D03*
Y72245D03*
X472244Y73819D03*
X465157Y77756D03*
Y72245D03*
X514764Y68307D03*
X543110D03*
X528937D03*
X557283D03*
X514764Y87993D03*
Y82481D03*
Y73819D03*
X550197Y91930D03*
Y86418D03*
X543110Y87993D03*
Y82481D03*
X536024Y91930D03*
Y86418D03*
X528937Y87993D03*
Y82481D03*
X521850Y91930D03*
Y86418D03*
X550197Y77756D03*
Y72245D03*
X543110Y73819D03*
X536024Y77756D03*
Y72245D03*
X528937Y73819D03*
X521850Y77756D03*
Y72245D03*
X557283Y87993D03*
Y82481D03*
Y73819D03*
X564370Y91930D03*
Y86418D03*
Y77756D03*
Y72245D03*
X1398228Y68307D03*
X1426575D03*
X1412402D03*
X1398228Y87993D03*
Y82481D03*
Y73819D03*
X1426575Y87993D03*
Y82481D03*
X1419488Y91930D03*
Y86418D03*
X1412402Y87993D03*
Y82481D03*
X1405315Y91930D03*
Y86418D03*
X1426575Y73819D03*
X1419488Y77756D03*
Y72245D03*
X1412402Y73819D03*
X1405315Y77756D03*
Y72245D03*
X1440748Y68307D03*
X1447835Y91930D03*
Y86418D03*
X1440748Y87993D03*
Y82481D03*
X1433661Y91930D03*
Y86418D03*
X1447835Y77756D03*
Y72245D03*
X1440748Y73819D03*
X1433661Y77756D03*
Y72245D03*
X1483268Y68307D03*
X1511614D03*
X1497441D03*
X1483268Y87993D03*
Y82481D03*
Y73819D03*
X1518701Y91930D03*
Y86418D03*
X1511614Y87993D03*
Y82481D03*
X1504528Y91930D03*
Y86418D03*
X1497441Y87993D03*
Y82481D03*
X1490354Y91930D03*
Y86418D03*
X1518701Y77756D03*
Y72245D03*
X1511614Y73819D03*
X1504528Y77756D03*
Y72245D03*
X1497441Y73819D03*
X1490354Y77756D03*
Y72245D03*
X1525787Y68307D03*
X1532874Y91930D03*
Y86418D03*
X1525787Y87993D03*
Y82481D03*
X1532874Y77756D03*
Y72245D03*
X1525787Y73819D03*
G54D119*
G01X394744Y-485863D02*
X395618Y-484988D01*
X396273Y-483530D01*
X396710Y-481487D01*
X396273Y-479738D01*
X395400Y-478571D01*
X393871Y-477696D01*
X387976D01*
Y-495196D01*
X395181D01*
X396710Y-494030D01*
X397583Y-492279D01*
X398020Y-490238D01*
X397583Y-488196D01*
X396273Y-486446D01*
X394744Y-485863D01*
X387976D01*
G01X407441Y-495196D02*
Y-483530D01*
G01Y-485863D02*
X408533Y-484696D01*
X409625Y-483821D01*
X411153Y-483530D01*
X412244Y-483821D01*
X413555Y-484696D01*
G01X423413Y-500446D02*
X424723Y-501029D01*
X426470Y-500446D01*
X427561Y-499280D01*
X428435Y-497821D01*
X429744Y-493155D01*
X432583Y-483530D01*
G01X425596D02*
X429744Y-493155D01*
G01X448991Y-484988D02*
X447463Y-483821D01*
X446153Y-483530D01*
X444406Y-484113D01*
X443096Y-485279D01*
X442223Y-487321D01*
X442004Y-489363D01*
X442223Y-491405D01*
X443096Y-493155D01*
X444406Y-494613D01*
X446153Y-495196D01*
X447681Y-494613D01*
X448991Y-493446D01*
G01X459723Y-487321D02*
X466710D01*
X466055Y-485279D01*
X464963Y-484113D01*
X463435Y-483530D01*
X461906Y-483821D01*
X460596Y-484696D01*
X459723Y-486738D01*
X459286Y-488488D01*
Y-490238D01*
X459723Y-491988D01*
X460815Y-493738D01*
X462125Y-494904D01*
X463653Y-495196D01*
X465181Y-494613D01*
X466710Y-492863D01*
G01X502801Y-479155D02*
X501491Y-478279D01*
X499963Y-477696D01*
X498216D01*
X496251Y-478571D01*
X494723Y-480029D01*
X493631Y-481780D01*
X492758Y-484696D01*
X492539Y-487321D01*
X492976Y-489946D01*
X493631Y-491696D01*
X494941Y-493446D01*
X496470Y-494613D01*
X497998Y-495196D01*
X499526D01*
X501055Y-494613D01*
X502365Y-493738D01*
X503457Y-492572D01*
G01X519428Y-495196D02*
Y-483530D01*
G01Y-485571D02*
X518555Y-484405D01*
X517244Y-483821D01*
X515716Y-483530D01*
X514188Y-484113D01*
X512878Y-485279D01*
X512004Y-487029D01*
X511568Y-489363D01*
X512004Y-491696D01*
X512878Y-493446D01*
X514188Y-494613D01*
X515716Y-495196D01*
X517244Y-494904D01*
X518555Y-494030D01*
X519428Y-492863D01*
G01X529286Y-495196D02*
Y-483530D01*
G01Y-486446D02*
X530160Y-484988D01*
X531470Y-483821D01*
X533216Y-483530D01*
X534744Y-483821D01*
X536055Y-484988D01*
X536710Y-487029D01*
Y-495196D01*
G01X545913Y-500446D02*
X547223Y-501029D01*
X548970Y-500446D01*
X550061Y-499280D01*
X550935Y-497821D01*
X552244Y-493155D01*
X555083Y-483530D01*
G01X548096D02*
X552244Y-493155D01*
G01X567998Y-495196D02*
X566688Y-494904D01*
X565378Y-493738D01*
X564504Y-491696D01*
X564068Y-489363D01*
X564504Y-487029D01*
X565378Y-484988D01*
X566688Y-483821D01*
X567998Y-483530D01*
X569308Y-483821D01*
X570618Y-484988D01*
X571491Y-487029D01*
X571710Y-489363D01*
X571491Y-491696D01*
X570618Y-493738D01*
X569308Y-494904D01*
X567998Y-495196D01*
G01X581786D02*
Y-483530D01*
G01Y-486446D02*
X582660Y-484988D01*
X583970Y-483821D01*
X585716Y-483530D01*
X587244Y-483821D01*
X588555Y-484988D01*
X589210Y-487029D01*
Y-495196D01*
G01X616350D02*
Y-477696D01*
X624646D01*
G01X621590Y-486154D02*
X616350D01*
G01X637998Y-495779D02*
X637561Y-495488D01*
Y-494904D01*
X637998Y-494613D01*
X638435Y-494904D01*
Y-495488D01*
X637998Y-495779D01*
G01X650695Y-495196D02*
Y-477696D01*
X655061D01*
X656808Y-478571D01*
X658118Y-479738D01*
X659210Y-481487D01*
X660083Y-483530D01*
X660301Y-486446D01*
X660083Y-489363D01*
X659210Y-491405D01*
X658118Y-493155D01*
X656808Y-494321D01*
X655061Y-495196D01*
X650695D01*
G01X668631D02*
Y-477696D01*
X673871D01*
X675618Y-478571D01*
X676928Y-480613D01*
X677365Y-482946D01*
X676928Y-485279D01*
X675836Y-487029D01*
X673871Y-487905D01*
X668631D01*
G01X692244Y-485863D02*
X693118Y-484988D01*
X693773Y-483530D01*
X694210Y-481487D01*
X693773Y-479738D01*
X692900Y-478571D01*
X691371Y-477696D01*
X685476D01*
Y-495196D01*
X692681D01*
X694210Y-494030D01*
X695083Y-492279D01*
X695520Y-490238D01*
X695083Y-488196D01*
X693773Y-486446D01*
X692244Y-485863D01*
X685476D01*
G01X501071Y-450196D02*
Y-432696D01*
X506748Y-447279D01*
X512425Y-432696D01*
Y-450196D01*
G01X524248D02*
X522938Y-449904D01*
X521628Y-448738D01*
X520754Y-446696D01*
X520318Y-444363D01*
X520754Y-442029D01*
X521628Y-439988D01*
X522938Y-438821D01*
X524248Y-438530D01*
X525558Y-438821D01*
X526868Y-439988D01*
X527741Y-442029D01*
X527960Y-444363D01*
X527741Y-446696D01*
X526868Y-448738D01*
X525558Y-449904D01*
X524248Y-450196D01*
G01X545678Y-432696D02*
Y-450196D01*
G01Y-447572D02*
X544805Y-449030D01*
X543494Y-449904D01*
X541966Y-450196D01*
X540220Y-449613D01*
X538910Y-448155D01*
X538036Y-446405D01*
X537818Y-444363D01*
X538036Y-442321D01*
X538910Y-440571D01*
X540220Y-439113D01*
X541966Y-438530D01*
X543494Y-438821D01*
X544586Y-439405D01*
X545678Y-440571D01*
G01X555973Y-442321D02*
X562960D01*
X562305Y-440279D01*
X561213Y-439113D01*
X559685Y-438530D01*
X558156Y-438821D01*
X556846Y-439696D01*
X555973Y-441738D01*
X555536Y-443488D01*
Y-445238D01*
X555973Y-446988D01*
X557065Y-448738D01*
X558375Y-449904D01*
X559903Y-450196D01*
X561431Y-449613D01*
X562960Y-447863D01*
G01X576748Y-450196D02*
Y-432696D01*
G01X754448Y-495196D02*
Y-477696D01*
X751828Y-481196D01*
G01Y-495196D02*
X757068D01*
G01X767800Y-487905D02*
X769328Y-485863D01*
X770638Y-484696D01*
X772385Y-484113D01*
X773913Y-484696D01*
X775005Y-485863D01*
X775878Y-487613D01*
X776096Y-489654D01*
X775878Y-491405D01*
X775005Y-493155D01*
X773694Y-494613D01*
X772166Y-495196D01*
X770420Y-494613D01*
X768891Y-492863D01*
X768018Y-490238D01*
X767800Y-487321D01*
X768236Y-483530D01*
X768891Y-481487D01*
X769983Y-479446D01*
X771511Y-477988D01*
X773040Y-477696D01*
X774568Y-478279D01*
X775660Y-479738D01*
G01X784645Y-491696D02*
X785954Y-493738D01*
X787701Y-494904D01*
X789666Y-495196D01*
X791413Y-494904D01*
X793160Y-493446D01*
X794251Y-491696D01*
X794470Y-489946D01*
X794033Y-487905D01*
X792505Y-486446D01*
X790976Y-485863D01*
X789011D01*
G01X790976D02*
X792286Y-484988D01*
X793378Y-483530D01*
X793815Y-481780D01*
X793378Y-480029D01*
X792286Y-478571D01*
X790321Y-477696D01*
X788356Y-477988D01*
X786391Y-479155D01*
G01X806948Y-495196D02*
Y-477696D01*
X804328Y-481196D01*
G01Y-495196D02*
X809568D01*
G01X819645Y-492572D02*
X820954Y-494030D01*
X822483Y-494904D01*
X824448Y-495196D01*
X826413Y-494613D01*
X827941Y-493446D01*
X829033Y-491405D01*
X829251Y-489071D01*
X828815Y-486738D01*
X827723Y-485279D01*
X826194Y-484113D01*
X824666Y-483821D01*
X823138Y-484113D01*
X821173Y-485279D01*
X821828Y-477696D01*
X827723D01*
G01X741331Y-450196D02*
Y-432696D01*
X746571D01*
X748318Y-433571D01*
X749628Y-435613D01*
X750065Y-437946D01*
X749628Y-440279D01*
X748536Y-442029D01*
X746571Y-442905D01*
X741331D01*
G01X768001Y-434155D02*
X766691Y-433279D01*
X765163Y-432696D01*
X763416D01*
X761451Y-433571D01*
X759923Y-435029D01*
X758831Y-436780D01*
X757958Y-439696D01*
X757739Y-442321D01*
X758176Y-444946D01*
X758831Y-446696D01*
X760141Y-448446D01*
X761670Y-449613D01*
X763198Y-450196D01*
X764726D01*
X766255Y-449613D01*
X767565Y-448738D01*
X768657Y-447572D01*
G01X782444Y-440863D02*
X783318Y-439988D01*
X783973Y-438530D01*
X784410Y-436487D01*
X783973Y-434738D01*
X783100Y-433571D01*
X781571Y-432696D01*
X775676D01*
Y-450196D01*
X782881D01*
X784410Y-449030D01*
X785283Y-447279D01*
X785720Y-445238D01*
X785283Y-443196D01*
X783973Y-441446D01*
X782444Y-440863D01*
X775676D01*
G01X791648Y-456029D02*
X804748D01*
G01X810676Y-450196D02*
Y-432696D01*
X820720Y-450196D01*
Y-432696D01*
G01X833198Y-450196D02*
X831451Y-449904D01*
X829923Y-448738D01*
X828613Y-446988D01*
X827739Y-444946D01*
X827303Y-442613D01*
Y-440279D01*
X827739Y-437946D01*
X828613Y-435904D01*
X829923Y-434155D01*
X831451Y-432988D01*
X833198Y-432696D01*
X834944Y-432988D01*
X836473Y-434155D01*
X837783Y-435904D01*
X838657Y-437946D01*
X839093Y-440279D01*
Y-442613D01*
X838657Y-444946D01*
X837783Y-446988D01*
X836473Y-448738D01*
X834944Y-449904D01*
X833198Y-450196D01*
G01X884039Y-432696D02*
X889498Y-450196D01*
X894957Y-432696D01*
G01X911365Y-450196D02*
X902631D01*
Y-432696D01*
X911365D01*
G01X907871Y-441154D02*
X902631D01*
G01X920131Y-450196D02*
Y-432696D01*
X925590D01*
X927336Y-433571D01*
X928428Y-434738D01*
X928865Y-437071D01*
X928428Y-439405D01*
X927118Y-440863D01*
X925590Y-441738D01*
X920131D01*
G01X925590D02*
X928865Y-450196D01*
G01X941998Y-450779D02*
X941561Y-450488D01*
Y-449904D01*
X941998Y-449613D01*
X942435Y-449904D01*
Y-450488D01*
X941998Y-450779D01*
G01X915748Y-495196D02*
Y-477696D01*
X913128Y-481196D01*
G01Y-495196D02*
X918368D01*
G01X1082981Y-432696D02*
Y-450196D01*
X1091715D01*
G01X1108778D02*
Y-438530D01*
G01Y-440571D02*
X1107905Y-439405D01*
X1106594Y-438821D01*
X1105066Y-438530D01*
X1103538Y-439113D01*
X1102228Y-440279D01*
X1101354Y-442029D01*
X1100918Y-444363D01*
X1101354Y-446696D01*
X1102228Y-448446D01*
X1103538Y-449613D01*
X1105066Y-450196D01*
X1106594Y-449904D01*
X1107905Y-449030D01*
X1108778Y-447863D01*
G01X1117763Y-455446D02*
X1119073Y-456029D01*
X1120820Y-455446D01*
X1121911Y-454280D01*
X1122785Y-452821D01*
X1124094Y-448155D01*
X1126933Y-438530D01*
G01X1119946D02*
X1124094Y-448155D01*
G01X1136573Y-442321D02*
X1143560D01*
X1142905Y-440279D01*
X1141813Y-439113D01*
X1140285Y-438530D01*
X1138756Y-438821D01*
X1137446Y-439696D01*
X1136573Y-441738D01*
X1136136Y-443488D01*
Y-445238D01*
X1136573Y-446988D01*
X1137665Y-448738D01*
X1138975Y-449904D01*
X1140503Y-450196D01*
X1142031Y-449613D01*
X1143560Y-447863D01*
G01X1154291Y-450196D02*
Y-438530D01*
G01Y-440863D02*
X1155383Y-439696D01*
X1156475Y-438821D01*
X1158003Y-438530D01*
X1159094Y-438821D01*
X1160405Y-439696D01*
G01X1109231Y-477696D02*
Y-495196D01*
X1117965D01*
G01X1131098D02*
Y-477696D01*
X1128478Y-481196D01*
G01Y-495196D02*
X1133718D01*
G01X1312898D02*
X1311151Y-494904D01*
X1309623Y-493738D01*
X1308313Y-491988D01*
X1307439Y-489946D01*
X1307003Y-487613D01*
Y-485279D01*
X1307439Y-482946D01*
X1308313Y-480904D01*
X1309623Y-479155D01*
X1311151Y-477988D01*
X1312898Y-477696D01*
X1314644Y-477988D01*
X1316173Y-479155D01*
X1317483Y-480904D01*
X1318357Y-482946D01*
X1318793Y-485279D01*
Y-487613D01*
X1318357Y-489946D01*
X1317483Y-491988D01*
X1316173Y-493738D01*
X1314644Y-494904D01*
X1312898Y-495196D01*
G01X1314644Y-490529D02*
X1317265Y-495196D01*
G01X1325595Y-477696D02*
Y-490238D01*
X1326468Y-492863D01*
X1328215Y-494613D01*
X1330398Y-495196D01*
X1332581Y-494613D01*
X1334328Y-492863D01*
X1335201Y-490238D01*
Y-477696D01*
G01X1345278D02*
X1350518D01*
G01X1347898D02*
Y-495196D01*
G01X1345278D02*
X1350518D01*
G01X1360376D02*
Y-477696D01*
X1370420Y-495196D01*
Y-477696D01*
G01X1387701Y-479155D02*
X1386391Y-478279D01*
X1384863Y-477696D01*
X1383116D01*
X1381151Y-478571D01*
X1379623Y-480029D01*
X1378531Y-481780D01*
X1377658Y-484696D01*
X1377439Y-487321D01*
X1377876Y-489946D01*
X1378531Y-491696D01*
X1379841Y-493446D01*
X1381370Y-494613D01*
X1382898Y-495196D01*
X1384426D01*
X1385955Y-494613D01*
X1387265Y-493738D01*
X1388357Y-492572D01*
G01X1400398Y-495196D02*
Y-487321D01*
X1396031Y-477696D01*
G01X1404765D02*
X1400398Y-487321D01*
G01X1290595Y-450196D02*
Y-432696D01*
X1294961D01*
X1296708Y-433571D01*
X1298018Y-434738D01*
X1299110Y-436487D01*
X1299983Y-438530D01*
X1300201Y-441446D01*
X1299983Y-444363D01*
X1299110Y-446405D01*
X1298018Y-448155D01*
X1296708Y-449321D01*
X1294961Y-450196D01*
X1290595D01*
G01X1309623Y-442321D02*
X1316610D01*
X1315955Y-440279D01*
X1314863Y-439113D01*
X1313335Y-438530D01*
X1311806Y-438821D01*
X1310496Y-439696D01*
X1309623Y-441738D01*
X1309186Y-443488D01*
Y-445238D01*
X1309623Y-446988D01*
X1310715Y-448738D01*
X1312025Y-449904D01*
X1313553Y-450196D01*
X1315081Y-449613D01*
X1316610Y-447863D01*
G01X1327123Y-448155D02*
X1328215Y-449321D01*
X1329743Y-450196D01*
X1331053D01*
X1332363Y-449613D01*
X1333236Y-448738D01*
X1333673Y-447572D01*
X1333455Y-445821D01*
X1332581Y-444946D01*
X1328651Y-443196D01*
X1327778Y-441154D01*
X1328215Y-439696D01*
X1329088Y-438821D01*
X1330398Y-438530D01*
X1331708Y-438821D01*
X1333018Y-439696D01*
G01X1347898Y-438530D02*
Y-450196D01*
G01Y-433863D02*
X1347461Y-433571D01*
Y-432988D01*
X1347898Y-432696D01*
X1348335Y-432988D01*
Y-433571D01*
X1347898Y-433863D01*
G01X1362341Y-454571D02*
X1363870Y-455738D01*
X1365616Y-456029D01*
X1367144Y-455738D01*
X1368455Y-454280D01*
X1369328Y-452238D01*
Y-438530D01*
G01Y-440863D02*
X1368455Y-439696D01*
X1367144Y-438821D01*
X1365616Y-438530D01*
X1363870Y-439113D01*
X1362778Y-440279D01*
X1361904Y-442321D01*
X1361468Y-444363D01*
X1361686Y-446113D01*
X1362560Y-448155D01*
X1363870Y-449613D01*
X1365616Y-450196D01*
X1366926Y-449904D01*
X1368455Y-448738D01*
X1369328Y-447572D01*
G01X1379186Y-450196D02*
Y-438530D01*
G01Y-441446D02*
X1380060Y-439988D01*
X1381370Y-438821D01*
X1383116Y-438530D01*
X1384644Y-438821D01*
X1385955Y-439988D01*
X1386610Y-442029D01*
Y-450196D01*
G01X1397123Y-442321D02*
X1404110D01*
X1403455Y-440279D01*
X1402363Y-439113D01*
X1400835Y-438530D01*
X1399306Y-438821D01*
X1397996Y-439696D01*
X1397123Y-441738D01*
X1396686Y-443488D01*
Y-445238D01*
X1397123Y-446988D01*
X1398215Y-448738D01*
X1399525Y-449904D01*
X1401053Y-450196D01*
X1402581Y-449613D01*
X1404110Y-447863D01*
G01X1414841Y-450196D02*
Y-438530D01*
G01Y-440863D02*
X1415933Y-439696D01*
X1417025Y-438821D01*
X1418553Y-438530D01*
X1419644Y-438821D01*
X1420955Y-439696D01*
G01X1461598Y-477696D02*
X1459851Y-478279D01*
X1458541Y-479738D01*
X1457668Y-481487D01*
X1457013Y-483821D01*
X1456795Y-486446D01*
X1457013Y-489071D01*
X1457668Y-491405D01*
X1458541Y-493155D01*
X1459851Y-494613D01*
X1461598Y-495196D01*
X1463344Y-494613D01*
X1464655Y-493155D01*
X1465528Y-491405D01*
X1466183Y-489071D01*
X1466401Y-486446D01*
X1466183Y-483821D01*
X1465528Y-481487D01*
X1464655Y-479738D01*
X1463344Y-478279D01*
X1461598Y-477696D01*
G01X1474950Y-487905D02*
X1476478Y-485863D01*
X1477788Y-484696D01*
X1479535Y-484113D01*
X1481063Y-484696D01*
X1482155Y-485863D01*
X1483028Y-487613D01*
X1483246Y-489654D01*
X1483028Y-491405D01*
X1482155Y-493155D01*
X1480844Y-494613D01*
X1479316Y-495196D01*
X1477570Y-494613D01*
X1476041Y-492863D01*
X1475168Y-490238D01*
X1474950Y-487321D01*
X1475386Y-483530D01*
X1476041Y-481487D01*
X1477133Y-479446D01*
X1478661Y-477988D01*
X1480190Y-477696D01*
X1481718Y-478279D01*
X1482810Y-479738D01*
G01X1492668Y-495779D02*
X1500528Y-477696D01*
G01X1514098D02*
X1512351Y-478279D01*
X1511041Y-479738D01*
X1510168Y-481487D01*
X1509513Y-483821D01*
X1509295Y-486446D01*
X1509513Y-489071D01*
X1510168Y-491405D01*
X1511041Y-493155D01*
X1512351Y-494613D01*
X1514098Y-495196D01*
X1515844Y-494613D01*
X1517155Y-493155D01*
X1518028Y-491405D01*
X1518683Y-489071D01*
X1518901Y-486446D01*
X1518683Y-483821D01*
X1518028Y-481487D01*
X1517155Y-479738D01*
X1515844Y-478279D01*
X1514098Y-477696D01*
G01X1527886Y-493155D02*
X1529415Y-494613D01*
X1531161Y-495196D01*
X1532908Y-494613D01*
X1534436Y-492863D01*
X1535528Y-490238D01*
X1535965Y-487613D01*
Y-484405D01*
X1535528Y-481780D01*
X1534436Y-479446D01*
X1533126Y-478279D01*
X1531598Y-477696D01*
X1529851Y-478279D01*
X1528541Y-479446D01*
X1527668Y-481196D01*
X1527231Y-483530D01*
X1527668Y-485571D01*
X1528760Y-487613D01*
X1530070Y-488780D01*
X1531598Y-489071D01*
X1533344Y-488488D01*
X1534655Y-487029D01*
X1535965Y-484405D01*
G01X1545168Y-495779D02*
X1553028Y-477696D01*
G01X1562450Y-480613D02*
X1563760Y-478863D01*
X1565288Y-477988D01*
X1567035Y-477696D01*
X1569218Y-478279D01*
X1570746Y-479738D01*
X1571183Y-481487D01*
X1570965Y-483238D01*
X1570091Y-484696D01*
X1565725Y-487613D01*
X1563760Y-489654D01*
X1562450Y-492572D01*
X1562013Y-495196D01*
X1571183D01*
G01X1584098Y-477696D02*
X1582351Y-478279D01*
X1581041Y-479738D01*
X1580168Y-481487D01*
X1579513Y-483821D01*
X1579295Y-486446D01*
X1579513Y-489071D01*
X1580168Y-491405D01*
X1581041Y-493155D01*
X1582351Y-494613D01*
X1584098Y-495196D01*
X1585844Y-494613D01*
X1587155Y-493155D01*
X1588028Y-491405D01*
X1588683Y-489071D01*
X1588901Y-486446D01*
X1588683Y-483821D01*
X1588028Y-481487D01*
X1587155Y-479738D01*
X1585844Y-478279D01*
X1584098Y-477696D01*
G01X1601598Y-495196D02*
Y-477696D01*
X1598978Y-481196D01*
G01Y-495196D02*
X1604218D01*
G01X1618661D02*
X1619098Y-491405D01*
X1619753Y-488196D01*
X1620626Y-485279D01*
X1621718Y-482071D01*
X1623465Y-477696D01*
X1614731D01*
G01X1509295Y-450196D02*
Y-432696D01*
X1513661D01*
X1515408Y-433571D01*
X1516718Y-434738D01*
X1517810Y-436487D01*
X1518683Y-438530D01*
X1518901Y-441446D01*
X1518683Y-444363D01*
X1517810Y-446405D01*
X1516718Y-448155D01*
X1515408Y-449321D01*
X1513661Y-450196D01*
X1509295D01*
G01X1535528D02*
Y-438530D01*
G01Y-440571D02*
X1534655Y-439405D01*
X1533344Y-438821D01*
X1531816Y-438530D01*
X1530288Y-439113D01*
X1528978Y-440279D01*
X1528104Y-442029D01*
X1527668Y-444363D01*
X1528104Y-446696D01*
X1528978Y-448446D01*
X1530288Y-449613D01*
X1531816Y-450196D01*
X1533344Y-449904D01*
X1534655Y-449030D01*
X1535528Y-447863D01*
G01X1549098Y-432696D02*
Y-450196D01*
G01X1546041Y-438530D02*
X1552155D01*
G01X1563323Y-442321D02*
X1570310D01*
X1569655Y-440279D01*
X1568563Y-439113D01*
X1567035Y-438530D01*
X1565506Y-438821D01*
X1564196Y-439696D01*
X1563323Y-441738D01*
X1562886Y-443488D01*
Y-445238D01*
X1563323Y-446988D01*
X1564415Y-448738D01*
X1565725Y-449904D01*
X1567253Y-450196D01*
X1568781Y-449613D01*
X1570310Y-447863D01*
G54D80*
X794488Y11615D03*
X885040D03*
G54D71*
X577669Y532781D03*
X563889D03*
Y552881D03*
X577669D03*
X933110Y1519150D03*
Y1539250D03*
X946890Y1519150D03*
Y1539250D03*
X1464090Y539550D03*
X1450310D03*
Y559650D03*
X1464090D03*
G54D44*
X77877Y194861D03*
X80437D03*
X82997D03*
X77877Y187461D03*
X80437D03*
X82997D03*
Y647617D03*
X80437D03*
X77877D03*
Y640217D03*
X80437D03*
X82997D03*
Y1100373D03*
X80437D03*
X77877D03*
Y1092973D03*
X80437D03*
X82997D03*
X202089Y194861D03*
X204649D03*
X207209D03*
X202089Y187461D03*
X204649D03*
X207209D03*
X207409Y638617D03*
X204849D03*
X202289D03*
Y631217D03*
X204849D03*
X207409D03*
X207209Y1100373D03*
X204649D03*
X202089D03*
Y1092973D03*
X204649D03*
X207209D03*
X326302Y194861D03*
X328862D03*
X331422D03*
X326302Y187461D03*
X328862D03*
X331422D03*
Y647617D03*
X328862D03*
X326302D03*
Y640217D03*
X328862D03*
X331422D03*
Y1100373D03*
X328862D03*
X326302D03*
Y1092973D03*
X328862D03*
X331422D03*
X450514Y194861D03*
X453074D03*
X455634D03*
X450514Y187461D03*
X453074D03*
X455634D03*
Y647617D03*
X453074D03*
X450514D03*
Y640217D03*
X453074D03*
X455634D03*
X574727Y194861D03*
X577287D03*
X579847D03*
X574727Y187461D03*
X577287D03*
X579847D03*
Y647617D03*
X577287D03*
X574727D03*
Y640217D03*
X577287D03*
X579847D03*
Y1100373D03*
X577287D03*
X574727D03*
Y1092973D03*
X577287D03*
X579847D03*
X698940Y194861D03*
X701500D03*
X698940Y187461D03*
X701500D03*
X699140Y649117D03*
Y641717D03*
X701500Y1100373D03*
X698940D03*
Y1092973D03*
X701500D03*
X704060Y194861D03*
Y187461D03*
X704260Y649117D03*
X701700D03*
Y641717D03*
X704260D03*
X704060Y1100373D03*
Y1092973D03*
X1021660Y-56732D03*
X1019100D03*
X1016540D03*
X1021660Y-49332D03*
X1019100D03*
X1016540D03*
X1006660Y-59968D03*
X1004100D03*
X1001540D03*
X1006660Y-52568D03*
X1004100D03*
X1001540D03*
X1086740Y-77432D03*
X1076960Y-63832D03*
X1074400D03*
X1071840D03*
X1076960Y-56432D03*
X1074400D03*
X1071840D03*
X1086740Y-70032D03*
X1091860Y-77432D03*
X1089300D03*
X1109922Y-72521D03*
X1107362D03*
X1104802D03*
X1109922Y-65121D03*
X1107362D03*
X1104802D03*
X1091860Y-70032D03*
X1089300D03*
G54D62*
X460873Y1081266D03*
X453473D03*
X460873Y1083826D03*
Y1086386D03*
X453473D03*
Y1083826D03*
X1303800Y180721D03*
Y178161D03*
Y175601D03*
X1311200D03*
Y178161D03*
Y180721D03*
X1303800Y633477D03*
Y630917D03*
Y628357D03*
X1311200D03*
Y630917D03*
Y633477D03*
X1303800Y1081113D03*
X1311200D03*
X1303800Y1086233D03*
Y1083673D03*
X1311200D03*
Y1086233D03*
X1428013Y180721D03*
Y178161D03*
Y175601D03*
Y633477D03*
Y630917D03*
Y628357D03*
Y1081113D03*
Y1086233D03*
Y1083673D03*
X1435413Y175601D03*
Y178161D03*
Y180721D03*
Y628357D03*
Y630917D03*
Y633477D03*
Y1081113D03*
Y1083673D03*
Y1086233D03*
X1552225Y180721D03*
Y178161D03*
Y175601D03*
X1559625D03*
Y178161D03*
Y180721D03*
X1552225Y633477D03*
Y630917D03*
Y628357D03*
X1559625D03*
Y630917D03*
Y633477D03*
X1552225Y1081113D03*
X1559625D03*
X1552225Y1086233D03*
Y1083673D03*
X1559625D03*
Y1086233D03*
X1676438Y180721D03*
Y178161D03*
Y175601D03*
X1683838D03*
Y178161D03*
Y180721D03*
X1676438Y633477D03*
Y630917D03*
Y628357D03*
X1683838D03*
Y630917D03*
Y633477D03*
X1676438Y1081113D03*
X1683838D03*
X1676438Y1086233D03*
Y1083673D03*
X1683838D03*
Y1086233D03*
X1800650Y180721D03*
Y178161D03*
Y175601D03*
X1808050D03*
Y178161D03*
Y180721D03*
X1800650Y633477D03*
Y630917D03*
Y628357D03*
X1808050D03*
Y630917D03*
Y633477D03*
X1800650Y1081113D03*
X1808050D03*
X1800650Y1086233D03*
Y1083673D03*
X1808050D03*
Y1086233D03*
X1859117Y171015D03*
Y173575D03*
Y176135D03*
X1851717D03*
Y173575D03*
Y171015D03*
X1859117Y623771D03*
Y626331D03*
Y628891D03*
X1851717D03*
Y626331D03*
Y623771D03*
X1871030Y1076940D03*
Y1079500D03*
Y1082060D03*
X1863630D03*
Y1079500D03*
Y1076940D03*
G54D35*
X56637Y214661D03*
Y667417D03*
Y1120173D03*
X139137Y240661D03*
Y693417D03*
X138456Y971762D03*
X139137Y1146173D03*
X180849Y214661D03*
X205156Y559762D03*
X202700Y644000D03*
X186599Y671689D03*
X186649Y1123673D03*
X263349Y240661D03*
Y693417D03*
Y1146173D03*
X305062Y214661D03*
Y667417D03*
Y1120173D03*
X338929Y58745D03*
X387562Y240661D03*
Y693417D03*
Y1146173D03*
X429274Y214661D03*
Y667417D03*
X449874Y1117073D03*
X499774Y1141973D03*
X511774Y240661D03*
X553487Y214661D03*
Y667417D03*
X511774Y693417D03*
X553487Y1120173D03*
X598301Y530600D03*
X635987Y240661D03*
Y693417D03*
Y1146173D03*
X690517Y112738D03*
X677700Y214661D03*
X678200Y669917D03*
X683500Y1124073D03*
X749400Y209600D03*
X748200Y681800D03*
X847804Y1538590D03*
X931778Y995820D03*
X911246Y1530405D03*
X967522Y1516969D03*
X1030912Y-70708D03*
X1054233Y-76247D03*
X1082907Y1561743D03*
X1107288Y-55662D03*
X1308200Y195261D03*
Y648017D03*
Y1100773D03*
X1331700Y227761D03*
Y680517D03*
Y1133273D03*
X1432413Y195261D03*
X1455913Y227761D03*
X1432413Y648017D03*
X1455913Y680517D03*
X1432413Y1100773D03*
X1455913Y1133273D03*
X1556625Y195261D03*
X1551625Y650017D03*
X1549025Y1136373D03*
X1580125Y227761D03*
Y680517D03*
X1680838Y195261D03*
X1704338Y227761D03*
X1680838Y648017D03*
X1704338Y680517D03*
X1680838Y1100773D03*
X1704338Y1133273D03*
X1759700Y716500D03*
X1805050Y195261D03*
Y648017D03*
X1780256Y983762D03*
X1805050Y1100773D03*
X1848369Y214661D03*
X1828550Y227761D03*
X1848369Y667417D03*
X1828550Y680517D03*
X1854906Y1117394D03*
X1828150Y1133173D03*
X1881285Y1064038D03*
G54D53*
X145237Y256161D03*
Y708917D03*
Y1161673D03*
X269449Y256161D03*
Y708917D03*
Y1161673D03*
X393662Y256161D03*
Y708917D03*
X393462Y1161673D03*
X505674Y1130873D03*
X517874Y256161D03*
Y708917D03*
X531474Y1152773D03*
X642087Y256161D03*
Y708917D03*
Y1161673D03*
X833108Y37372D03*
X868377Y37234D03*
X937809Y991763D03*
X914882Y1534500D03*
X1113100Y-48400D03*
X1435000Y544600D03*
X1460061Y588256D03*
X1503682Y539100D03*
X1887132Y1054227D03*
G54D26*
X56737Y210561D03*
X58384Y513020D03*
X44157Y513016D03*
X56737Y663317D03*
Y1116073D03*
X88737Y176661D03*
Y181161D03*
Y633917D03*
X100863Y985725D03*
X116997Y995001D03*
X102163Y1003325D03*
X88837Y1082173D03*
Y1086673D03*
X139237Y244761D03*
X168411Y512874D03*
X168863Y591025D03*
X167563Y573725D03*
X139237Y697517D03*
X137163Y1005625D03*
X125363Y1001725D03*
X137122Y997250D03*
X124455Y992723D03*
X139237Y1150273D03*
X180949Y210561D03*
X213049Y181361D03*
Y176661D03*
X182638Y512878D03*
X203863Y593625D03*
X192063Y589725D03*
X203822Y585250D03*
X183697Y583001D03*
X191155Y580723D03*
X213049Y623417D03*
Y618917D03*
X202800Y650000D03*
X186699Y667589D03*
X213049Y1082173D03*
Y1086873D03*
X186749Y1119573D03*
X263449Y244761D03*
Y697517D03*
Y1150273D03*
X305162Y210561D03*
X306809Y512878D03*
X292582Y512874D03*
X305162Y663317D03*
Y1116073D03*
X315721Y72855D03*
X326079Y72845D03*
X337362Y176461D03*
X337262Y181161D03*
Y634017D03*
X337362Y1082073D03*
Y1086773D03*
X387662Y244761D03*
Y697517D03*
Y1150273D03*
X429374Y210561D03*
X430959Y512841D03*
X416732Y512837D03*
X429374Y663317D03*
X449974Y1112973D03*
X443973Y1091326D03*
X461474Y176461D03*
Y181161D03*
Y633917D03*
X499874Y1145973D03*
X553587Y210661D03*
X511874Y244661D03*
X541679Y528531D03*
Y532831D03*
X525277Y512878D03*
X511050Y512874D03*
X544179Y566531D03*
Y561531D03*
X553587Y663417D03*
X511874Y697417D03*
X553587Y1116173D03*
X585687Y176661D03*
Y181361D03*
X601579Y538831D03*
Y542831D03*
X576079Y566331D03*
X568079D03*
X595579Y552331D03*
X585687Y634017D03*
Y629417D03*
Y1082173D03*
Y1086873D03*
X621697Y107633D03*
X611701Y112329D03*
X636087Y244761D03*
X638684Y512541D03*
X624457Y512537D03*
X616110Y562574D03*
Y555174D03*
X636087Y697517D03*
Y1150273D03*
X677800Y210561D03*
X678300Y665817D03*
X683600Y1119973D03*
X709900Y176461D03*
Y181161D03*
X749500Y205500D03*
X709900Y633917D03*
Y629417D03*
X748300Y677700D03*
X709900Y1081973D03*
Y1086673D03*
X839000Y1538800D03*
X874850Y359100D03*
X874654Y445462D03*
X874700Y450200D03*
Y454900D03*
X874800Y471100D03*
X874754Y459562D03*
X874743Y464505D03*
X875943Y542405D03*
X885903Y856727D03*
X868672Y1358528D03*
X877912Y1380412D03*
X877911Y1375746D03*
X868508Y1523720D03*
X906900Y1512600D03*
Y1508100D03*
X937300Y1552700D03*
X916300Y1539200D03*
X913300Y1544200D03*
X968690Y1153500D03*
X945300Y1552700D03*
X976513Y1553466D03*
Y1549366D03*
X964832Y1538282D03*
X967800Y1529200D03*
Y1525200D03*
X1038858Y-71536D03*
X1015632Y-66200D03*
X1004132Y-43500D03*
X1011450Y550000D03*
X1025235Y908603D03*
X1025200Y904200D03*
X1009800Y930500D03*
X1034674Y1354526D03*
X1062121Y-76578D03*
X1062904Y79465D03*
X1046300Y442000D03*
X1046337Y429753D03*
X1046301Y434409D03*
X1046515Y557053D03*
X1109900Y-89600D03*
X1109921Y-85538D03*
X1100879Y-82462D03*
X1221510Y236291D03*
X1194650Y284750D03*
X1194429Y1033731D03*
Y1029031D03*
X1250061Y513463D03*
X1235924Y513432D03*
X1254800Y697850D03*
X1250525Y966004D03*
X1236376Y965973D03*
X1254800Y1150173D03*
X1308300Y191161D03*
Y643917D03*
Y1096673D03*
X1331800Y223661D03*
X1346413Y513334D03*
X1332276Y513303D03*
X1331800Y676417D03*
X1348846Y965705D03*
X1334805Y965825D03*
X1331800Y1129173D03*
X1381009Y244829D03*
X1432513Y191161D03*
X1456013Y223661D03*
X1435500Y526100D03*
X1432513Y643917D03*
X1456013Y676417D03*
X1473058Y965763D03*
X1459017Y965883D03*
X1456013Y1129173D03*
X1432513Y1096673D03*
X1556725Y191161D03*
X1551725Y645917D03*
X1549125Y1132273D03*
X1580225Y223661D03*
X1597295Y513418D03*
X1583158Y513387D03*
X1580225Y676417D03*
X1597371Y965889D03*
X1583230Y965809D03*
X1680938Y191161D03*
X1704438Y223661D03*
X1707623Y513134D03*
X1680938Y643917D03*
X1704438Y676417D03*
X1680938Y1096673D03*
X1704438Y1129173D03*
X1721760Y513165D03*
X1759800Y720500D03*
X1759934Y965756D03*
X1745736Y965664D03*
X1758797Y1007001D03*
X1743963Y1015325D03*
X1742663Y997725D03*
X1805150Y191161D03*
Y643917D03*
X1802627Y965626D03*
X1790438Y968689D03*
X1767163Y1013725D03*
X1778922Y1009250D03*
X1766255Y1004723D03*
X1778963Y1017625D03*
X1805150Y1096673D03*
X1848469Y210461D03*
X1842117Y181175D03*
X1828650Y223661D03*
X1845595Y513292D03*
X1831458Y513261D03*
X1842217Y633931D03*
X1828650Y676417D03*
X1848469Y663317D03*
X1828250Y1128973D03*
X1855006Y1113294D03*
X1881385Y1059938D03*
G54D17*
X25000Y1195200D03*
X30000D03*
X95437Y290361D03*
Y743117D03*
Y1195873D03*
X135422Y1195737D03*
X140422D03*
X219649Y290361D03*
Y743117D03*
X259594Y1195568D03*
X264594D03*
X219649Y1195873D03*
X343862Y290361D03*
Y743117D03*
Y1195873D03*
X383849Y1195442D03*
X388849D03*
X468074Y290361D03*
Y743117D03*
X508103Y1195357D03*
X468074Y1195873D03*
X513103Y1195357D03*
X592287Y290361D03*
X584279Y567031D03*
X592287Y743117D03*
Y1195873D03*
X607460Y560974D03*
X632316Y1195274D03*
X637316D03*
X716500Y290361D03*
Y743117D03*
Y1195873D03*
X751209Y159828D03*
X752500Y1157700D03*
X881256Y1365150D03*
X933524Y922100D03*
X967813Y1553966D03*
X953500Y1553400D03*
X1211205Y1156394D03*
X1216205D03*
X1298500Y260361D03*
Y289861D03*
Y742617D03*
Y713117D03*
Y1165873D03*
Y1195373D03*
X1351321Y1156353D03*
X1346321D03*
X1422713Y260361D03*
Y289861D03*
X1426419Y526957D03*
X1422713Y742617D03*
Y713117D03*
Y1165873D03*
Y1195373D03*
X1470953Y1156227D03*
X1475953D03*
X1507037Y528103D03*
X1546925Y260361D03*
Y289861D03*
Y742617D03*
Y713117D03*
Y1165873D03*
Y1195373D03*
X1615552Y1156406D03*
X1620236D03*
X1671138Y260361D03*
Y289861D03*
Y742617D03*
Y713117D03*
Y1165873D03*
Y1195373D03*
X1760500Y725200D03*
X1723117Y1156353D03*
X1718117D03*
X1795350Y260361D03*
Y289861D03*
X1795468Y742794D03*
X1795350Y713117D03*
Y1165873D03*
Y1195373D03*
X1836400Y1155900D03*
X1841084Y1155921D03*
X1887169Y290361D03*
Y743117D03*
Y1195873D03*
G54D81*
X845670Y5709D03*
X841733D03*
X837795D03*
X833858D03*
X829921D03*
X825984D03*
X822047D03*
X818110D03*
X814173D03*
X810236D03*
X806299D03*
X802362D03*
X845670Y29725D03*
X841733D03*
X837795D03*
X833858D03*
X829921D03*
X825984D03*
X822047D03*
X818110D03*
X814173D03*
X810236D03*
X806299D03*
X802362D03*
X877166Y5709D03*
X873229D03*
X869292D03*
X865355D03*
X861418D03*
X857481D03*
X853544D03*
X849607D03*
X877166Y29725D03*
X873229D03*
X869292D03*
X865355D03*
X861418D03*
X857481D03*
X853544D03*
X849607D03*
G54D90*
X991713Y-122342D03*
X986713D03*
X981713D03*
X976713D03*
X971713D03*
X966713D03*
X961713D03*
X1036713D03*
X1031713D03*
X1026713D03*
X1021713D03*
X1016713D03*
X1086713D03*
X1081713D03*
X1076713D03*
X1071713D03*
X1066713D03*
X1061713D03*
X1056713D03*
X1051713D03*
X1046713D03*
X1041713D03*
G54D36*
X72049Y374529D03*
X68109D03*
X72049Y368779D03*
X68109D03*
X72049Y827284D03*
X68109D03*
X72049Y821534D03*
X68109D03*
X72049Y1274290D03*
X68109D03*
X72049Y1280040D03*
X68109D03*
X196261Y374529D03*
X192321D03*
X196261Y368779D03*
X192321D03*
X196261Y827284D03*
X192321D03*
X196261Y821534D03*
X192321D03*
X196261Y1274290D03*
X192321D03*
X196261Y1280040D03*
X192321D03*
X320474Y374529D03*
X316534D03*
X320474Y368779D03*
X316534D03*
X320474Y827284D03*
X316534D03*
X320474Y821534D03*
X316534D03*
X320474Y1274290D03*
X316534D03*
X320474Y1280040D03*
X316534D03*
X444687Y374529D03*
X440747D03*
X444687Y368779D03*
X440747D03*
X444687Y827284D03*
X440747D03*
X444687Y821534D03*
X440747D03*
X444687Y1274290D03*
X440747D03*
X444687Y1280040D03*
X440747D03*
X568899Y374529D03*
X564959D03*
X568899Y368779D03*
X564959D03*
X568899Y827284D03*
X564959D03*
X568899Y821534D03*
X564959D03*
X568899Y1274290D03*
X564959D03*
X568899Y1280040D03*
X564959D03*
X693112Y374529D03*
X689172D03*
X693112Y368779D03*
X689172D03*
X693112Y827284D03*
X689172D03*
X693112Y821534D03*
X689172D03*
X693112Y1274290D03*
X689172D03*
X693112Y1280040D03*
X689172D03*
X1242718Y374529D03*
X1238778D03*
X1242718Y368779D03*
X1238778D03*
X1242718Y827284D03*
X1238778D03*
X1242718Y821534D03*
X1238778D03*
X1242718Y1274290D03*
X1238778D03*
X1242718Y1280040D03*
X1238778D03*
X1366931Y374529D03*
X1362991D03*
X1366931Y368779D03*
X1362991D03*
X1366931Y827284D03*
X1362991D03*
X1366931Y821534D03*
X1362991D03*
X1366931Y1274290D03*
X1362991D03*
X1366931Y1280040D03*
X1362991D03*
X1491143Y374529D03*
X1487203D03*
X1491143Y368779D03*
X1487203D03*
X1491143Y827284D03*
X1487203D03*
X1491143Y821534D03*
X1487203D03*
X1491143Y1274290D03*
X1487203D03*
X1491143Y1280040D03*
X1487203D03*
X1615356Y374529D03*
X1611416D03*
X1615356Y368779D03*
X1611416D03*
X1615356Y827284D03*
X1611416D03*
X1615356Y821534D03*
X1611416D03*
X1615356Y1274290D03*
X1611416D03*
X1615356Y1280040D03*
X1611416D03*
X1739568Y374529D03*
X1735628D03*
X1739568Y368779D03*
X1735628D03*
X1739568Y827284D03*
X1735628D03*
X1739568Y821534D03*
X1735628D03*
X1739568Y1274290D03*
X1735628D03*
X1739568Y1280040D03*
X1735628D03*
X1859841Y374529D03*
Y368779D03*
Y827284D03*
Y821534D03*
Y1274290D03*
Y1280040D03*
X1863781Y374529D03*
Y368779D03*
Y827284D03*
Y821534D03*
Y1274290D03*
Y1280040D03*
G54D45*
X93437Y239661D03*
Y250661D03*
Y692417D03*
Y703417D03*
Y1156173D03*
Y1145173D03*
X217649Y239661D03*
Y250661D03*
Y692417D03*
Y703417D03*
Y1156173D03*
Y1145173D03*
X341862Y239661D03*
Y250661D03*
Y692417D03*
Y703417D03*
Y1156173D03*
Y1145173D03*
X466074Y239661D03*
Y250661D03*
Y692417D03*
Y703417D03*
X515774Y1156173D03*
Y1145173D03*
X590287Y239661D03*
Y250661D03*
Y692417D03*
Y703417D03*
Y1156173D03*
Y1145173D03*
X714500Y239661D03*
Y250661D03*
Y692417D03*
Y703417D03*
Y1156173D03*
Y1145173D03*
X1308500Y253661D03*
Y264661D03*
Y717417D03*
Y706417D03*
Y1170173D03*
Y1159173D03*
X1432713Y253661D03*
Y264661D03*
Y717417D03*
Y706417D03*
Y1170173D03*
Y1159173D03*
X1556925Y253661D03*
Y264661D03*
Y717417D03*
Y706417D03*
Y1170173D03*
Y1159173D03*
X1681138Y253661D03*
Y264661D03*
Y717417D03*
Y706417D03*
Y1170173D03*
Y1159173D03*
X1805350Y253661D03*
Y264661D03*
Y717417D03*
Y706417D03*
Y1170173D03*
Y1159173D03*
X1885169Y250661D03*
Y239661D03*
Y692417D03*
Y703417D03*
X1885553Y1131673D03*
Y1142673D03*
G54D72*
X575700Y533081D03*
X573732D03*
X571763D03*
X569795D03*
X567826D03*
X565858D03*
Y552581D03*
X567826D03*
X569795D03*
X571763D03*
X573732D03*
X575700D03*
X942953Y1519450D03*
X940984D03*
X939016D03*
X937047D03*
X935079D03*
Y1538950D03*
X937047D03*
X939016D03*
X940984D03*
X942953D03*
X944921Y1519450D03*
Y1538950D03*
X1462121Y539850D03*
X1460153D03*
X1458184D03*
X1456216D03*
X1454247D03*
X1452279D03*
Y559350D03*
X1454247D03*
X1456216D03*
X1458184D03*
X1460153D03*
X1462121D03*
G54D63*
X445173Y1097726D03*
X454173D03*
X1323500Y188161D03*
Y640917D03*
Y1093673D03*
X1332500Y188161D03*
Y640917D03*
Y1093673D03*
X1447713Y188161D03*
X1456713D03*
X1447713Y640917D03*
X1456713D03*
X1447713Y1093673D03*
X1456713D03*
X1571925Y188161D03*
X1566925Y642917D03*
X1580925Y188161D03*
X1575925Y642917D03*
X1581025Y1087373D03*
X1590025D03*
X1696138Y188161D03*
X1705138D03*
X1696138Y640917D03*
X1705138D03*
X1696138Y1093673D03*
X1705138D03*
X1843417Y187575D03*
X1852417D03*
X1820350Y188161D03*
X1829350D03*
X1843417Y640331D03*
X1852417D03*
X1820350Y640917D03*
X1829350D03*
X1843896Y1092413D03*
X1852896D03*
X1820350Y1093673D03*
X1829350D03*
G54D27*
X60137Y210561D03*
X61784Y513020D03*
X47557Y513016D03*
X60137Y663317D03*
Y1116073D03*
X92137Y176661D03*
Y181161D03*
Y633917D03*
X104263Y985725D03*
X120397Y995001D03*
X105563Y1003325D03*
X92237Y1082173D03*
Y1086673D03*
X142637Y244761D03*
Y697517D03*
X140563Y1005625D03*
X128763Y1001725D03*
X140522Y997250D03*
X127855Y992723D03*
X142637Y1150273D03*
X184349Y210561D03*
X216449Y181361D03*
Y176661D03*
X186038Y512878D03*
X171811Y512874D03*
X207263Y593625D03*
X195463Y589725D03*
X207222Y585250D03*
X187097Y583001D03*
X194555Y580723D03*
X172263Y591025D03*
X170963Y573725D03*
X216449Y623417D03*
Y618917D03*
X206200Y650000D03*
X190099Y667589D03*
X216449Y1082173D03*
Y1086873D03*
X190149Y1119573D03*
X308562Y210561D03*
X266849Y244761D03*
X310209Y512878D03*
X295982Y512874D03*
X308562Y663317D03*
X266849Y697517D03*
X308562Y1116073D03*
X266849Y1150273D03*
X319121Y72855D03*
X329479Y72845D03*
X340762Y176461D03*
X340662Y181161D03*
Y634017D03*
X340762Y1082073D03*
Y1086773D03*
X391062Y244761D03*
Y697517D03*
Y1150273D03*
X432774Y210561D03*
X434359Y512841D03*
X420132Y512837D03*
X432774Y663317D03*
X453374Y1112973D03*
X447373Y1091326D03*
X464874Y176461D03*
Y181161D03*
Y633917D03*
X503274Y1145973D03*
X515274Y244661D03*
X545079Y528531D03*
Y532831D03*
X528677Y512878D03*
X514450Y512874D03*
X547579Y566531D03*
Y561531D03*
X515274Y697417D03*
X589087Y176661D03*
Y181361D03*
X556987Y210661D03*
X604979Y538831D03*
Y542831D03*
X579479Y566331D03*
X571479D03*
X598979Y552331D03*
X589087Y634017D03*
Y629417D03*
X556987Y663417D03*
X589087Y1082173D03*
Y1086873D03*
X556987Y1116173D03*
X625097Y107633D03*
X615101Y112329D03*
X639487Y244761D03*
X642084Y512541D03*
X627857Y512537D03*
X619510Y562574D03*
Y555174D03*
X639487Y697517D03*
Y1150273D03*
X681200Y210561D03*
X681700Y665817D03*
X687000Y1119973D03*
X713300Y176461D03*
Y181161D03*
Y633917D03*
Y629417D03*
Y1081973D03*
Y1086673D03*
X752900Y205500D03*
X751700Y677700D03*
X842400Y1538800D03*
X878250Y359100D03*
X878054Y445462D03*
X878100Y450200D03*
Y454900D03*
X878200Y471100D03*
X878154Y459562D03*
X878143Y464505D03*
X879343Y542405D03*
X889303Y856727D03*
X872072Y1358528D03*
X881312Y1380412D03*
X881311Y1375746D03*
X871908Y1523720D03*
X910300Y1512600D03*
Y1508100D03*
X940700Y1552700D03*
X919700Y1539200D03*
X916700Y1544200D03*
X972090Y1153500D03*
X948700Y1552700D03*
X979913Y1553466D03*
Y1549366D03*
X968232Y1538282D03*
X971200Y1529200D03*
Y1525200D03*
X1019032Y-66200D03*
X1007532Y-43500D03*
X1014850Y550000D03*
X1028635Y908603D03*
X1028600Y904200D03*
X1013200Y930500D03*
X1038074Y1354526D03*
X1042258Y-71536D03*
X1065521Y-76578D03*
X1066304Y79465D03*
X1049700Y442000D03*
X1049737Y429753D03*
X1049701Y434409D03*
X1049915Y557053D03*
X1113300Y-89600D03*
X1113321Y-85538D03*
X1104279Y-82462D03*
X1224910Y236291D03*
X1198050Y284750D03*
X1197829Y1033731D03*
Y1029031D03*
X1253461Y513463D03*
X1239324Y513432D03*
X1258200Y697850D03*
X1253925Y966004D03*
X1239776Y965973D03*
X1258200Y1150173D03*
X1311700Y191161D03*
Y643917D03*
Y1096673D03*
X1335200Y223661D03*
X1349813Y513334D03*
X1335676Y513303D03*
X1335200Y676417D03*
X1352246Y965705D03*
X1338205Y965825D03*
X1335200Y1129173D03*
X1384409Y244829D03*
X1435913Y191161D03*
X1459413Y223661D03*
X1438900Y526100D03*
X1435913Y643917D03*
X1459413Y676417D03*
X1462417Y965883D03*
X1459413Y1129173D03*
X1435913Y1096673D03*
X1476458Y965763D03*
X1560125Y191161D03*
X1555125Y645917D03*
X1552525Y1132273D03*
X1583625Y223661D03*
X1600695Y513418D03*
X1586558Y513387D03*
X1583625Y676417D03*
X1600771Y965889D03*
X1586630Y965809D03*
X1684338Y191161D03*
X1707838Y223661D03*
X1711023Y513134D03*
X1684338Y643917D03*
X1707838Y676417D03*
X1684338Y1096673D03*
X1707838Y1129173D03*
X1725160Y513165D03*
X1763200Y720500D03*
X1763334Y965756D03*
X1749136Y965664D03*
X1762197Y1007001D03*
X1747363Y1015325D03*
X1746063Y997725D03*
X1808550Y191161D03*
Y643917D03*
X1806027Y965626D03*
X1793838Y968689D03*
X1770563Y1013725D03*
X1782322Y1009250D03*
X1769655Y1004723D03*
X1782363Y1017625D03*
X1808550Y1096673D03*
X1851869Y210461D03*
X1845517Y181175D03*
X1832050Y223661D03*
X1848995Y513292D03*
X1834858Y513261D03*
X1845617Y633931D03*
X1832050Y676417D03*
X1851869Y663317D03*
X1831650Y1128973D03*
X1858406Y1113294D03*
X1884785Y1059938D03*
G54D54*
X139937Y270661D03*
Y723417D03*
X147063Y1005225D03*
X140100Y1176000D03*
X213763Y593225D03*
X264149Y270661D03*
Y723417D03*
X264200Y1176000D03*
X388362Y270661D03*
Y723417D03*
X388200Y1176000D03*
X512574Y270661D03*
Y723417D03*
X512500Y1176000D03*
X636787Y270461D03*
Y723417D03*
X636800Y1176000D03*
X749000Y723417D03*
X751300Y270500D03*
X760900Y1176000D03*
X884000Y503300D03*
X884069Y536587D03*
X884143Y522805D03*
Y516205D03*
X884069Y529987D03*
X883969Y548187D03*
X884143Y509905D03*
X884069Y587087D03*
X884143Y593105D03*
Y599205D03*
X884043Y605505D03*
Y611905D03*
X869534Y1363511D03*
X1005471Y14243D03*
X1005571Y7943D03*
Y20443D03*
X1005471Y26543D03*
Y32343D03*
X1005371Y44043D03*
X1005457Y38271D03*
X1005557Y49871D03*
X1005898Y72514D03*
Y79114D03*
X1005157Y579054D03*
X1072205Y31082D03*
Y38982D03*
X1067705Y35182D03*
X1067805Y27282D03*
X1067705Y42682D03*
X1072382Y46195D03*
X1067200Y48900D03*
X1072200Y52000D03*
X1072132Y64668D03*
Y70368D03*
X1051915Y518253D03*
Y524853D03*
X1051869Y538079D03*
Y531479D03*
X1051957Y505702D03*
Y512302D03*
X1051131Y586321D03*
X1051185Y574247D03*
X1051147Y598615D03*
Y592415D03*
X1051185Y580347D03*
X1051200Y568300D03*
X1051181Y562366D03*
X1250500Y273500D03*
X1254000Y722917D03*
X1253900Y1176000D03*
X1378700Y270400D03*
X1378213Y722917D03*
X1378400Y1176000D03*
X1500900Y265600D03*
X1502425Y722917D03*
X1502300Y1176000D03*
X1628000Y270500D03*
X1626638Y722917D03*
X1626000Y1176000D03*
X1750900Y270500D03*
X1753000Y756000D03*
X1747400Y1176000D03*
X1788863Y1017225D03*
X1877400Y265200D03*
X1874807Y707280D03*
X1887000Y1170756D03*
G54D18*
X35506Y-110687D03*
X63128Y89671D03*
X60754Y1316385D03*
X72380Y1596505D03*
X1861177Y91072D03*
X1874818Y-110232D03*
G54D73*
X570779Y542831D03*
X940000Y1529200D03*
X1457200Y549600D03*
G54D37*
X43728Y499434D03*
X57963Y499397D03*
X47603Y506934D03*
X39853D03*
X61838Y506897D03*
X54088D03*
X167982Y499392D03*
X164107Y506892D03*
X182217Y499355D03*
X171857Y506892D03*
X186092Y506855D03*
X178342D03*
X292153Y499392D03*
X306388Y499355D03*
X296028Y506892D03*
X288278D03*
X310263Y506855D03*
X302513D03*
X416303Y499355D03*
X430538Y499318D03*
X420178Y506855D03*
X412428D03*
X434413Y506818D03*
X426663D03*
X506746Y506892D03*
X510621Y499392D03*
X524856Y499355D03*
X514496Y506892D03*
X528731Y506855D03*
X520981D03*
X624028Y499055D03*
X638263Y499018D03*
X627903Y506555D03*
X620153D03*
X642138Y506518D03*
X634388D03*
X858500Y1511250D03*
X862375Y1518750D03*
X854625D03*
X868458Y1529687D03*
X872333Y1537187D03*
X864583D03*
X937399Y897695D03*
X941274Y905195D03*
X933524D03*
X1239758Y499401D03*
X1253867Y499400D03*
X1243633Y506901D03*
X1235883D03*
X1257742Y506900D03*
X1249992D03*
X1240222Y951942D03*
X1244097Y959442D03*
X1236347D03*
X1254331Y951941D03*
X1258206Y959441D03*
X1250456D03*
X1336110Y499272D03*
X1350219Y499271D03*
X1339985Y506772D03*
X1332235D03*
X1354094Y506771D03*
X1346344D03*
X1338611Y952153D03*
X1342486Y959653D03*
X1334736D03*
X1352803Y952194D03*
X1356678Y959694D03*
X1348928D03*
X1453451Y499121D03*
X1472480Y499018D03*
X1457326Y506621D03*
X1449576D03*
X1468605Y506518D03*
X1462823Y952111D03*
X1466698Y959611D03*
X1458948D03*
X1473140Y959652D03*
X1476355Y506518D03*
X1477015Y952152D03*
X1480890Y959652D03*
X1586992Y499356D03*
X1601101Y499355D03*
X1590867Y506856D03*
X1583117D03*
X1604976Y506855D03*
X1597226D03*
X1587036Y952237D03*
X1590911Y959737D03*
X1583161D03*
X1601228Y952278D03*
X1605103Y959778D03*
X1597353D03*
X1711457Y499103D03*
X1715332Y506603D03*
X1707582D03*
X1725566Y499102D03*
X1729441Y506602D03*
X1721691D03*
X1749573Y952193D03*
X1753448Y959693D03*
X1745698D03*
X1763765Y952234D03*
X1759890Y959734D03*
X1792236Y951851D03*
X1796111Y959351D03*
X1788361D03*
X1806452Y952110D03*
X1810327Y959610D03*
X1802577D03*
X1767640Y959734D03*
X1835292Y499230D03*
X1849401Y499229D03*
X1839167Y506730D03*
X1831417D03*
X1853276Y506729D03*
X1845526D03*
G54D91*
X972995Y1165653D03*
X975555D03*
X978115D03*
Y1172153D03*
X972995D03*
X1325735Y65129D03*
X1328295D03*
X1325735Y71629D03*
X1330855Y65129D03*
Y71629D03*
G54D55*
X338971Y64135D03*
X345471Y66695D03*
Y64135D03*
X338971Y69255D03*
X345471D03*
X536871Y547216D03*
Y544656D03*
Y542096D03*
X543371D03*
Y547216D03*
X682452Y112770D03*
Y107650D03*
X675952D03*
Y110210D03*
Y112770D03*
X841508Y1533251D03*
Y1530691D03*
Y1528131D03*
X848008D03*
Y1533251D03*
X907950Y1525060D03*
Y1522500D03*
Y1519940D03*
X914450D03*
Y1525060D03*
X1233900Y230740D03*
Y235860D03*
X1240400D03*
Y233300D03*
Y230740D03*
X1491108Y545215D03*
Y547775D03*
Y550335D03*
X1484608D03*
Y545215D03*
G54D28*
X66437Y188161D03*
Y179161D03*
Y631917D03*
Y640917D03*
Y1084673D03*
Y1093673D03*
X190649Y188161D03*
Y179161D03*
X194749Y621417D03*
Y630417D03*
X190651Y1086035D03*
Y1095035D03*
X314862Y188161D03*
Y179161D03*
Y631917D03*
Y640917D03*
Y1084673D03*
Y1093673D03*
X439074Y188161D03*
Y179161D03*
Y631917D03*
Y640917D03*
X513517Y576931D03*
Y567931D03*
X563287Y188161D03*
Y179161D03*
Y631917D03*
Y640917D03*
Y1084673D03*
Y1093673D03*
X687500Y188161D03*
Y179161D03*
X691600Y631917D03*
Y640917D03*
X687500Y1084673D03*
Y1093673D03*
X882500Y1522868D03*
Y1531868D03*
X1087700Y-51200D03*
Y-42200D03*
X1514297Y544511D03*
Y553511D03*
G54D64*
X527145Y564270D03*
X525145Y558670D03*
X529145D03*
X899288Y1539560D03*
X897288Y1533960D03*
X901288D03*
X1100800Y-42800D03*
X1098800Y-48400D03*
X1102800D03*
G54D82*
X808001Y46220D03*
Y66488D03*
X803167Y631566D03*
Y651834D03*
X808000Y1203666D03*
Y1223934D03*
X1038655Y107235D03*
Y127503D03*
X1126047Y873270D03*
Y893538D03*
X1105647Y914783D03*
Y935051D03*
G54D19*
G01X104313Y985725D02*
X105663D01*
X108063Y988125D01*
G01X100813Y985725D02*
Y981785D01*
X101403Y981195D01*
G01X116947Y995001D02*
X121806Y990142D01*
X125324D01*
X127905Y992723D01*
G01X99700Y991400D02*
X98463Y992637D01*
Y1004725D01*
X101463Y1007725D01*
X116063D01*
X117063Y1006725D01*
G01X120445Y999067D02*
Y1000009D01*
X118414Y1002040D01*
Y1005374D01*
X117063Y1006725D01*
G01X120447Y995001D02*
Y999065D01*
X120445Y999067D01*
G01X108063Y991925D02*
Y988125D01*
G01X108363Y995475D02*
Y992225D01*
X108063Y991925D01*
G01X112500Y995530D02*
Y994162D01*
X114300Y992362D01*
G01X102113Y1003325D02*
Y998225D01*
G01X104230Y992209D02*
X102113Y994326D01*
Y998225D01*
G01X166400Y579400D02*
X165163Y580637D01*
Y592725D01*
X168163Y595725D01*
X182763D01*
X183763Y594725D01*
G01X168813Y586225D02*
Y591025D01*
G01X170930Y580209D02*
Y582108D01*
X168813Y584225D01*
Y586225D01*
G01X167513Y573725D02*
Y569785D01*
X168103Y569195D01*
G01X515800Y1028000D02*
X509800Y1034000D01*
X345200D01*
X342000Y1030800D01*
X235400D01*
X230700Y1026100D01*
X152900D01*
X140613Y1013813D01*
Y1005625D01*
G01X137063Y993725D02*
X137072Y993734D01*
Y997250D01*
G01X127905Y992723D02*
X130203Y990425D01*
X133763D01*
X137063Y993725D01*
G01X137072Y997250D02*
Y1000272D01*
X140000Y1003200D01*
X145038D01*
X147063Y1005225D01*
G01X145363Y997741D02*
X148179Y994925D01*
X227063D01*
G01X131110Y993257D02*
X131063Y993304D01*
Y997225D01*
G01X137113Y1005625D02*
X136763Y1005975D01*
X133063D01*
G01X131063Y997225D02*
X128813Y999475D01*
Y1001725D01*
G01D02*
Y1003225D01*
X128063Y1003975D01*
Y1006725D01*
G01X133063Y1005975D02*
X132313Y1006725D01*
X128063D01*
G01X207313Y593625D02*
Y598113D01*
G01X203763Y581725D02*
X203772Y581734D01*
Y585250D01*
G01X194605Y580723D02*
X196903Y578425D01*
X200463D01*
X203763Y581725D01*
G01X183647Y583001D02*
X188506Y578142D01*
X192024D01*
X194605Y580723D01*
G01X203772Y585250D02*
Y587634D01*
X205363Y589225D01*
X209763D01*
X213763Y593225D01*
G01X194763Y594725D02*
X199013D01*
X199763Y593975D01*
G01X194763Y594725D02*
Y591975D01*
X195513Y591225D01*
Y589725D01*
G01X197763Y585225D02*
Y581304D01*
X197810Y581257D01*
G01X195513Y589725D02*
Y587475D01*
X197763Y585225D01*
G01X199763Y593975D02*
X203463D01*
X203813Y593625D01*
G01X187145Y587067D02*
Y588009D01*
X185114Y590040D01*
Y593374D01*
X183763Y594725D01*
G01X187147Y583001D02*
Y587065D01*
X187145Y587067D01*
G01X171013Y573725D02*
X172363D01*
X174763Y576125D01*
G01Y579925D02*
Y576125D01*
G01X175063Y583475D02*
Y580225D01*
X174763Y579925D01*
G01X179200Y583530D02*
Y582162D01*
X181000Y580362D01*
G01X340201Y118481D02*
Y109715D01*
G01X342761D02*
Y114861D01*
G01X341114Y123622D02*
X340201Y122709D01*
Y118481D01*
G01X525579Y541531D02*
X531614D01*
X532179Y542096D01*
X536871D01*
G01X543371D02*
X546044D01*
X548716Y544768D01*
X550161D01*
G01X561029Y543815D02*
X554979D01*
X554026Y544768D01*
X550161D01*
G01X549279Y524831D02*
Y520081D01*
G01X563889Y532781D02*
X561129D01*
X555479Y527131D01*
X551579D01*
X549279Y524831D01*
G01X560729Y549721D02*
X555499D01*
X554889Y550331D01*
G01X547629Y561531D02*
X549079D01*
X554889Y555721D01*
Y550331D01*
G01X530130Y547167D02*
X530179Y547216D01*
X536871D01*
G01X602379Y547831D02*
X598779D01*
G01X570779Y542831D02*
X573732Y539878D01*
Y533081D01*
G01X585479Y537731D02*
X585300Y537910D01*
X580529D01*
G01X585479Y543994D02*
X585300Y543815D01*
X580529D01*
G01Y545784D02*
X583932D01*
X585979Y547831D01*
X587279D01*
G01X592779D02*
X587279D01*
G01X595529Y552331D02*
X592779Y549581D01*
Y547831D01*
G01X571763Y533081D02*
Y528847D01*
X575779Y524831D01*
G01Y520081D02*
Y524831D01*
G01X580279Y520081D02*
X575779D01*
G01X580829Y535941D02*
X583144D01*
X584470Y534615D01*
X588978D01*
G01X594267Y534120D02*
X593772Y534615D01*
X588978D01*
G01X608918Y512620D02*
X605293D01*
X601418Y516495D01*
G01X598351Y530600D02*
Y526590D01*
X599247Y525694D01*
G01X594267Y530620D02*
X598331D01*
X598351Y530600D01*
G01X601418Y516495D02*
Y523523D01*
X599247Y525694D01*
G01X601851Y530600D02*
Y528059D01*
X604119Y525791D01*
X606884D01*
G01X591779Y539081D02*
X590866Y539994D01*
X583951D01*
X583835Y539878D01*
X580529D01*
G01X591779Y539081D02*
X592329Y539631D01*
X595112D01*
X596414Y538329D01*
G01X601529Y538831D02*
X600729Y539631D01*
X597716D01*
X596414Y538329D01*
G01X591779Y542581D02*
X590992Y541794D01*
X584567D01*
X584514Y541847D01*
X580529D01*
G01X601529Y542831D02*
X600129Y541431D01*
X598312D01*
X596414Y543329D01*
G01X591779Y542581D02*
X592929Y541431D01*
X594516D01*
X596414Y543329D01*
G01X576029Y561181D02*
Y566331D01*
G01X573732Y552581D02*
Y556784D01*
X576029Y559081D01*
Y561181D01*
G01X575779Y570581D02*
X579652D01*
X579718Y570647D01*
G01X576029Y566331D02*
Y568481D01*
X575779Y568731D01*
Y570581D01*
G01X568029Y560831D02*
Y566331D01*
G01X571763Y552581D02*
Y557097D01*
X568029Y560831D01*
G01X567779Y570581D02*
X571506D01*
X571540Y570615D01*
G01X568029Y566331D02*
Y568481D01*
X567779Y568731D01*
Y570581D01*
G01X577669Y552881D02*
X578829D01*
X586279Y560331D01*
G01X588779Y570581D02*
X592779D01*
G01D02*
Y566581D01*
X592529Y566331D01*
G01D02*
Y564581D01*
X590779Y562831D01*
X588779D01*
X586279Y560331D01*
G01X562279Y565331D02*
Y570581D01*
G01X569795Y552581D02*
Y554815D01*
X562279Y562331D01*
Y565331D01*
G01X575700Y552581D02*
Y554727D01*
X580053Y559080D01*
G01X571529Y562951D02*
Y566331D01*
G01X579529Y562951D02*
Y559604D01*
X580053Y559080D01*
G01X584279Y566831D02*
X583779Y566331D01*
X579529D01*
G01X589029D02*
X584779D01*
X584279Y566831D01*
G01X579529Y566331D02*
Y562951D01*
G01X621058Y538995D02*
X620208Y539845D01*
X618108D01*
X617008Y538745D01*
G01X627000Y538581D02*
X625736Y539845D01*
X623966D01*
X623116Y538995D01*
X621058D01*
G01Y542495D02*
X620208Y541645D01*
X618108D01*
X617008Y542745D01*
G01X627000Y542909D02*
X625736Y541645D01*
X623966D01*
X623116Y542495D01*
X621058D01*
G01X613508Y538745D02*
X612322Y539931D01*
X610959D01*
X609334Y538306D01*
G01X605029Y538831D02*
X606129Y539931D01*
X607709D01*
X609334Y538306D01*
G01X613508Y542745D02*
X612494Y541731D01*
X610909D01*
X609334Y543306D01*
G01X605029Y542831D02*
X606129Y541731D01*
X607759D01*
X609334Y543306D01*
G01X615100Y520350D02*
X615080Y520370D01*
X608918D01*
G01D02*
Y523757D01*
X606884Y525791D01*
G01X683341Y586324D02*
Y580479D01*
G01X689747Y586324D02*
Y580479D01*
G01X872333Y1537187D02*
X876190D01*
G01X933531Y912047D02*
X933524Y912054D01*
Y916449D01*
G01D02*
Y921900D01*
G01X924580D02*
X929232D01*
G01D02*
X933524D01*
G01Y905195D02*
Y912040D01*
X933531Y912047D01*
G01X945790Y950412D02*
X938835Y943457D01*
Y941695D01*
G01X939016Y1519450D02*
Y1517216D01*
X938000Y1516200D01*
Y1511000D01*
G01Y1506450D02*
Y1511000D01*
G01X942000Y1506450D02*
X938000D01*
G01X940984Y1519450D02*
Y1514416D01*
X944200Y1511200D01*
X946300D01*
G01X918500Y1506450D02*
Y1510200D01*
G01X933110Y1519150D02*
X931950D01*
X927250Y1514450D01*
X922750D01*
X918500Y1510200D01*
G01X922500Y1509700D02*
Y1506450D01*
G01X935079Y1519450D02*
Y1515779D01*
X932500Y1513200D01*
Y1505500D01*
G01X922500Y1506450D02*
X926500D01*
G01D02*
X927450Y1505500D01*
X932500D01*
G01X940000Y1529200D02*
X942953Y1526247D01*
Y1519450D01*
G01X935079Y1538950D02*
Y1541121D01*
X931500Y1544700D01*
X929000D01*
G01X926500Y1549950D02*
Y1547200D01*
X929000Y1544700D01*
G01X921500Y1544200D02*
X916750D01*
G01X933110Y1539250D02*
X930450D01*
X925500Y1544200D01*
X921500D01*
G01X930250Y1530184D02*
X924300D01*
G01X914450Y1519940D02*
X914056D01*
X924300Y1530184D01*
G01X942953Y1538950D02*
Y1543153D01*
X945250Y1545450D01*
Y1547450D01*
G01X940984Y1538950D02*
Y1543466D01*
X937250Y1547200D01*
G01X937000Y1556950D02*
X937250Y1556700D01*
Y1552700D01*
G01X941000Y1556950D02*
X937000D01*
G01X937250Y1552700D02*
Y1547200D01*
G01X929950Y1536090D02*
X924720D01*
X924110Y1536700D01*
G01X919750Y1539200D02*
X921610D01*
X924110Y1536700D01*
G01X931500Y1548200D02*
Y1556950D01*
G01X939016Y1538950D02*
Y1541432D01*
X934948Y1545500D01*
X934200D01*
X931500Y1548200D01*
G01X940750Y1549200D02*
Y1552700D01*
G01X900000Y1526500D02*
X901440Y1525060D01*
X907950D01*
G01X948845Y938500D02*
X947276D01*
X944776Y941000D01*
G01X948845Y938500D02*
X951150D01*
X953420Y940770D01*
Y944100D01*
G01X945790Y950412D02*
Y945819D01*
G01D02*
Y943243D01*
X944776Y942229D01*
Y941000D01*
G01X950300Y1506450D02*
X946300D01*
G01D02*
Y1511200D01*
G01X967998Y1512551D02*
X972337Y1508212D01*
X975023D01*
G01X967572Y1516969D02*
Y1512977D01*
X967998Y1512551D01*
G01X963488Y1516989D02*
X967552D01*
X967572Y1516969D01*
G01X975023Y1508212D02*
X975523D01*
X979398Y1504337D01*
X982523D01*
G01X988573Y1509962D02*
Y1513673D01*
G01X971072Y1516969D02*
Y1514187D01*
X973172Y1512087D01*
X982523D01*
G01D02*
X984109Y1513673D01*
X988573D01*
G01X950050Y1536090D02*
X951561D01*
X955800Y1540329D01*
Y1541753D01*
X961008Y1546961D01*
G01X967813Y1553766D02*
X961008Y1546961D01*
G01X972413Y1553416D02*
X970317D01*
X969967Y1553766D01*
X967813D01*
G01X976463Y1553466D02*
X976413Y1553416D01*
X972413D01*
G01X954700Y1524100D02*
X954521Y1524279D01*
X949750D01*
G01X954700Y1530363D02*
X954521Y1530184D01*
X949750D01*
G01X1007010Y1521346D02*
Y1535647D01*
X1006010Y1536647D01*
X990017D01*
X979610Y1526240D01*
X975927D01*
X974787Y1525100D01*
G01D02*
X974687Y1525200D01*
X971250D01*
G01X1007010Y1553748D02*
Y1539447D01*
X1006010Y1538447D01*
X989271D01*
X978864Y1528040D01*
X976047D01*
X974787Y1529300D01*
G01D02*
X974687Y1529200D01*
X971250D01*
G01X949750Y1534121D02*
X952769D01*
X959987Y1541339D01*
G01X967813Y1549166D02*
Y1549165D01*
X959987Y1541339D01*
G01X972413Y1549416D02*
X968063D01*
X967813Y1549166D01*
G01X976463Y1549366D02*
X976413Y1549416D01*
X972413D01*
G01X945000Y1556950D02*
X945250Y1556700D01*
Y1552700D01*
G01X949000Y1556950D02*
X945000D01*
G01X945250Y1552700D02*
Y1547450D01*
G01X949750Y1532153D02*
X953378D01*
X953788Y1532563D01*
X953847D01*
X955210Y1533926D01*
X956597D01*
G01X958000Y1556950D02*
X962000D01*
G01X946890Y1539250D02*
Y1540450D01*
X948198Y1541758D01*
X950807D01*
X955236Y1546187D01*
G01X961750Y1552700D02*
X961749D01*
X955236Y1546187D01*
G01X962000Y1556950D02*
Y1552950D01*
X961750Y1552700D01*
G01X950050Y1522310D02*
X952365D01*
X953691Y1520984D01*
X958199D01*
G01X963488Y1520489D02*
X962993Y1520984D01*
X958199D01*
G01X944921Y1538950D02*
Y1541221D01*
X948750Y1545050D01*
G01Y1549200D02*
Y1545050D01*
G01X953500Y1553200D02*
X953000Y1552700D01*
X948750D01*
G01X958250D02*
X954000D01*
X953500Y1553200D01*
G01X948750Y1552700D02*
Y1549200D01*
G01X961000Y1525450D02*
X960150Y1526300D01*
X952600D01*
X952547Y1526247D01*
X949750D01*
G01X967750Y1525200D02*
X966650Y1526300D01*
X961850D01*
X961000Y1525450D01*
G01Y1528950D02*
X960150Y1528100D01*
X952700D01*
X952584Y1528216D01*
X949750D01*
G01X967750Y1529200D02*
X966650Y1528100D01*
X961850D01*
X961000Y1528950D01*
G01X1012750Y921375D02*
Y926499D01*
G01X1014700Y935000D02*
Y931950D01*
X1013250Y930500D01*
G01X1013450Y939000D02*
Y936250D01*
X1014700Y935000D01*
G01X1012750Y926499D02*
Y930000D01*
X1013250Y930500D01*
G01X1013450Y939000D02*
X1019540D01*
X1020540Y940000D01*
Y943600D01*
G01X1061713Y-122342D02*
Y-112887D01*
X1074551Y-100049D01*
X1111451D01*
X1112600Y-98900D01*
Y-94000D01*
G01X1106300Y-94800D02*
Y-92000D01*
X1105400Y-91100D01*
G01X1104329Y-82462D02*
X1104429Y-82562D01*
Y-86862D01*
G01X1104350Y-78400D02*
Y-82441D01*
X1104329Y-82462D01*
G01X1104802Y-72521D02*
Y-76048D01*
X1104350Y-76500D01*
Y-78400D01*
G01X1105400Y-91100D02*
X1104429Y-90129D01*
Y-86862D01*
G01X1109871Y-85538D02*
Y-89579D01*
X1109850Y-89600D01*
G01X1109871Y-80838D02*
Y-78000D01*
X1109922Y-77949D01*
Y-72521D01*
G01X1109871Y-85538D02*
Y-80838D01*
G01X1112600Y-94000D02*
Y-92350D01*
X1109850Y-89600D01*
G01X1103300Y-60000D02*
X1101100D01*
X1099500Y-61600D01*
Y-75600D01*
X1100850Y-76950D01*
Y-78400D01*
G01X1115603Y-60293D02*
X1118593D01*
X1120000Y-61700D01*
Y-88700D01*
X1119100Y-89600D01*
X1113350D01*
G01X1150232Y1316358D02*
X1147896Y1318694D01*
Y1415084D01*
X1134100Y1428880D01*
Y1433300D01*
G01X1341922Y105649D02*
Y110604D01*
X1338401Y114125D01*
Y118335D01*
G01X1340961D02*
Y122988D01*
X1343170Y125197D01*
G01X1343112Y128997D02*
X1343170D01*
Y125197D01*
G01X1360478Y542311D02*
X1357316D01*
G01X1425600Y544600D02*
X1429200D01*
G01X1421969Y520507D02*
X1423719Y522257D01*
X1426419D01*
G01X1417819Y520457D02*
X1417869Y520507D01*
X1421969D01*
G01X1440400Y537300D02*
X1430500Y527400D01*
Y526338D01*
X1426419Y522257D01*
G01X1421239Y562229D02*
X1420039Y561029D01*
X1415951D01*
X1413817Y558895D01*
Y552876D01*
X1415993Y550700D01*
X1420850D01*
X1421950Y549600D01*
G01X1421969Y527907D02*
X1423119Y526757D01*
X1426419D01*
G01X1417819Y527857D02*
X1417869Y527907D01*
X1421969D01*
G01X1426419Y526757D02*
X1429920Y530258D01*
Y532420D01*
X1432800Y535300D01*
G01X1425450Y549600D02*
X1426550Y550700D01*
X1428861D01*
X1430431Y549130D01*
G01X1392452Y573397D02*
X1396297D01*
G01X1421239Y558029D02*
X1420039Y559229D01*
X1416697D01*
X1415617Y558149D01*
Y553622D01*
X1416739Y552500D01*
X1420850D01*
X1421950Y553600D01*
G01X1392452Y579803D02*
X1396297D01*
G01X1426950Y571600D02*
X1423075Y575475D01*
X1419450D01*
G01X1413400Y567850D02*
X1419325D01*
X1419450Y567725D01*
G01D02*
X1423325D01*
X1428200Y562850D01*
G01X1425450Y553600D02*
X1426550Y552500D01*
X1428801D01*
X1430431Y554130D01*
G01X1457200Y549600D02*
X1454247Y552553D01*
Y559350D01*
G01X1465700Y515000D02*
Y518350D01*
G01X1439200Y515000D02*
Y518350D01*
G01X1452200Y515000D02*
Y518350D01*
G01X1460200Y515000D02*
Y518350D01*
G01X1443700Y515000D02*
Y519600D01*
G01X1448261Y515000D02*
Y518284D01*
G01X1456439Y515000D02*
Y518316D01*
G01X1470700Y528850D02*
Y530000D01*
X1467000Y533700D01*
G01X1462121Y539850D02*
Y537079D01*
X1465500Y533700D01*
X1467000D01*
G01X1464090Y539550D02*
X1465850D01*
X1475600Y529800D01*
Y525900D01*
G01X1440400Y537300D02*
Y537436D01*
X1445674Y542710D01*
X1447150D01*
G01X1442500Y548400D02*
X1442716Y548616D01*
X1447450D01*
G01X1432800Y535300D02*
X1437200Y539700D01*
X1439800D01*
X1444779Y544679D01*
X1447450D01*
G01X1466950Y548616D02*
X1473000D01*
X1473953Y547663D01*
X1477818D01*
G01X1454247Y539850D02*
Y531753D01*
X1452584Y530090D01*
G01D02*
X1451950Y529456D01*
Y526100D01*
G01X1452200Y521850D02*
X1448327D01*
X1448261Y521784D01*
G01X1451950Y526100D02*
Y523950D01*
X1452200Y523700D01*
Y521850D01*
G01X1459950Y531600D02*
Y526100D01*
G01X1456216Y539850D02*
Y535334D01*
X1459950Y531600D01*
G01X1460200Y521850D02*
X1456473D01*
X1456439Y521816D01*
G01X1459950Y526100D02*
Y523950D01*
X1460200Y523700D01*
Y521850D01*
G01X1447450Y546647D02*
X1444047D01*
X1442000Y544600D01*
X1440700D01*
G01X1435200D02*
X1440700D01*
G01X1432450Y540100D02*
X1435200Y542850D01*
Y544600D01*
G01X1450310Y539550D02*
X1449150D01*
X1441700Y532100D01*
G01X1439200Y521850D02*
X1435200D01*
G01D02*
Y525850D01*
X1435450Y526100D01*
G01D02*
Y527850D01*
X1437200Y529600D01*
X1439200D01*
X1441700Y532100D01*
G01X1467250Y542710D02*
X1472480D01*
X1473090Y542100D01*
G01X1480350Y530900D02*
X1478900D01*
X1473090Y536710D01*
Y542100D01*
G01X1465700Y527100D02*
Y521850D01*
G01X1458184Y539850D02*
Y537616D01*
X1465700Y530100D01*
Y527100D01*
G01X1456450Y529600D02*
Y526100D01*
G01X1452279Y539850D02*
Y536316D01*
X1449614Y533651D01*
G01X1448450Y529600D02*
Y532487D01*
X1449614Y533651D01*
G01X1448450Y526100D02*
Y529600D01*
G01X1438950Y526100D02*
X1439450Y525600D01*
X1443700D01*
G01D02*
X1447950D01*
X1448450Y526100D01*
G01X1436200Y549850D02*
X1436950Y550600D01*
X1444100D01*
X1444116Y550584D01*
X1447450D01*
G01X1436200Y549850D02*
X1434142D01*
X1433292Y550700D01*
X1432001D01*
X1430431Y549130D01*
G01X1459200Y579600D02*
Y575850D01*
G01X1452200Y579600D02*
Y575850D01*
G01X1442500Y554700D02*
X1442679Y554521D01*
X1447450D01*
G01X1458184Y559350D02*
Y563584D01*
X1459200Y564600D01*
Y568200D01*
G01D02*
Y572350D01*
G01D02*
X1455750D01*
G01X1456216Y559350D02*
Y563584D01*
X1452200Y567600D01*
G01Y572350D02*
Y567600D01*
G01X1447700Y572350D02*
X1452200D01*
G01X1464090Y559650D02*
X1466850D01*
X1472500Y565300D01*
X1476400D01*
X1478700Y567600D01*
G01X1437200Y562850D02*
Y559800D01*
X1439000Y558000D01*
G01X1447150Y556490D02*
X1446310D01*
X1444800Y558000D01*
X1439000D01*
G01X1433200Y571600D02*
X1426950D01*
G01X1433200Y566350D02*
Y571600D01*
G01X1437200Y566350D02*
X1433200D01*
G01Y562850D02*
X1428200D01*
G01X1436200Y553350D02*
X1437150Y552400D01*
X1444000D01*
X1444153Y552553D01*
X1447450D01*
G01X1436200Y553350D02*
X1434142D01*
X1433292Y552500D01*
X1432061D01*
X1430431Y554130D01*
G01X1511614Y110827D02*
X1507900Y114541D01*
Y122135D01*
X1511177Y125412D01*
G01X1502400Y550900D02*
X1496365D01*
X1495800Y550335D01*
X1491108D01*
G01X1483350Y525900D02*
X1475600D01*
G01X1484608Y550335D02*
X1481935D01*
X1479263Y547663D01*
X1477818D01*
G01X1497849Y545264D02*
X1497800Y545215D01*
X1491108D01*
G01X1478700Y567600D02*
Y572350D01*
G01X1758747Y1007001D02*
X1763606Y1002142D01*
X1767124D01*
X1769705Y1004723D01*
G01X1762245Y1011067D02*
Y1012009D01*
X1760214Y1014040D01*
Y1017374D01*
X1758863Y1018725D01*
G01X1762247Y1007001D02*
Y1011065D01*
X1762245Y1011067D01*
G01X1740499Y1008223D02*
X1740263Y1008459D01*
Y1016725D01*
X1743263Y1019725D01*
X1757863D01*
X1758863Y1018725D01*
G01X1746113Y997725D02*
X1747463D01*
X1749863Y1000125D01*
G01Y1003925D02*
Y1000125D01*
G01X1750163Y1007475D02*
Y1004225D01*
X1749863Y1003925D01*
G01X1754300Y1007530D02*
Y1006162D01*
X1756100Y1004362D01*
G01X1743913Y1015325D02*
Y1010225D01*
G01X1746030Y1004209D02*
Y1006108D01*
X1743913Y1008225D01*
Y1010225D01*
G01X1742613Y997725D02*
X1737359D01*
X1737241Y997843D01*
G01X1788726Y1034726D02*
X1782413Y1028413D01*
Y1017625D01*
G01D02*
X1784477D01*
X1791335Y1024483D01*
X1873978D01*
X1879516Y1018945D01*
Y978152D01*
X1910769Y946899D01*
Y917898D01*
X1904858Y911987D01*
Y902000D01*
X1909358Y897500D01*
G01X1778863Y1005725D02*
X1778872Y1005734D01*
Y1009250D01*
G01X1769705Y1004723D02*
X1772003Y1002425D01*
X1775563D01*
X1778863Y1005725D01*
G01X1778872Y1009250D02*
Y1011634D01*
X1780463Y1013225D01*
X1784863D01*
X1788863Y1017225D01*
G01X1769863Y1018725D02*
X1774113D01*
X1774863Y1017975D01*
G01X1769863Y1018725D02*
Y1015975D01*
X1770613Y1015225D01*
Y1013725D01*
G01X1772863Y1009225D02*
Y1005304D01*
G01X1770613Y1013725D02*
Y1011475D01*
X1772863Y1009225D01*
G01X1774863Y1017975D02*
X1778563D01*
X1778913Y1017625D01*
G01X1855676Y800787D02*
X1880587D01*
X1886950Y807150D01*
Y810719D01*
X1901431Y825200D01*
X1905000D01*
X1914751Y834951D01*
Y890394D01*
X1911676Y893469D01*
G01X1904000Y938000D02*
X1908769Y933231D01*
Y918727D01*
X1902441Y912399D01*
Y888500D01*
G01X1872190Y936766D02*
X1888234D01*
X1904000Y921000D01*
X60540Y-85109D03*
X59536Y1573374D03*
X80019Y51968D03*
X111024Y153681D03*
Y302303D03*
Y606437D03*
Y755059D03*
Y1059193D03*
Y1207815D03*
X79000Y1301900D03*
X127263Y20472D03*
X173228Y1114173D03*
X235236Y153681D03*
Y302303D03*
Y606437D03*
Y755059D03*
Y1059193D03*
Y1207815D03*
X359449Y153681D03*
Y302303D03*
Y606437D03*
Y755059D03*
Y1059193D03*
Y1207815D03*
X496653Y80906D03*
Y110552D03*
X483661Y153681D03*
Y302303D03*
Y606437D03*
Y755059D03*
X503248Y829921D03*
X483661Y1059193D03*
Y1207815D03*
X607874Y302303D03*
Y755059D03*
Y1207815D03*
X631200Y51968D03*
X607874Y153681D03*
Y606437D03*
Y1059193D03*
X678444Y20472D03*
X670079Y1114173D03*
X732087Y153681D03*
Y302303D03*
Y606437D03*
Y755059D03*
Y1059193D03*
Y1207815D03*
X942126Y58465D03*
Y346457D03*
Y437598D03*
Y725590D03*
X949902Y-115157D03*
X1098524D03*
X1110236Y58465D03*
Y346457D03*
Y437598D03*
Y725590D03*
X1250689Y51969D03*
X1281693Y153681D03*
Y302303D03*
Y606437D03*
Y755059D03*
Y1059193D03*
Y1207815D03*
X1297933Y20472D03*
X1343700Y1114173D03*
X1405906Y153681D03*
Y302303D03*
Y606437D03*
Y755059D03*
Y1059193D03*
Y1207815D03*
X1465157Y80906D03*
Y110552D03*
X1530118Y153681D03*
Y302303D03*
Y606437D03*
Y755059D03*
Y1059193D03*
Y1207815D03*
X1654331Y153681D03*
Y302303D03*
Y606437D03*
Y755059D03*
X1673917Y829921D03*
X1654331Y1059193D03*
Y1207815D03*
X1801870Y51969D03*
X1778543Y153681D03*
Y302303D03*
Y606437D03*
Y755059D03*
Y1059193D03*
Y1207815D03*
X1849114Y20472D03*
X1826700Y77600D03*
X1840551Y1114173D03*
X1865705Y1573374D03*
X1898432Y-93682D03*
X1902756Y153681D03*
Y302303D03*
Y606437D03*
Y755059D03*
Y1059193D03*
Y1207815D03*
X1908500Y1346800D03*
G54D46*
X83237Y247161D03*
Y699917D03*
Y1152673D03*
X130863Y997225D03*
X207449Y247161D03*
X197563Y585225D03*
X207449Y699917D03*
Y1152673D03*
X331662Y247161D03*
Y699917D03*
Y1152673D03*
X455874Y247161D03*
Y699917D03*
X530097Y553231D03*
X580087Y247161D03*
X575329Y506627D03*
X598579Y547831D03*
X580087Y699917D03*
Y1152673D03*
X704300Y247161D03*
Y699917D03*
Y1152673D03*
X874400Y1482760D03*
X957613Y1495424D03*
X967801Y1533926D03*
X1014500Y935000D03*
X1256300Y256161D03*
X1254300Y708917D03*
X1255600Y1161800D03*
X1378513Y708917D03*
X1380513Y256161D03*
X1379800Y1161700D03*
X1502825Y256061D03*
X1502725Y708917D03*
X1504500Y1161700D03*
X1628538Y256061D03*
X1626938Y708917D03*
X1638938Y1161673D03*
X1753350Y256061D03*
X1752500Y1161800D03*
X1772663Y1009225D03*
X1874969Y247161D03*
Y699917D03*
X1876448Y1133143D03*
G54D65*
X534679Y561531D03*
X906700Y1539500D03*
G54D47*
X77637Y247161D03*
Y699917D03*
Y1152673D03*
X125263Y997225D03*
X201849Y247161D03*
X191963Y585225D03*
X201849Y699917D03*
Y1152673D03*
X326062Y247161D03*
Y699917D03*
Y1152673D03*
X450274Y247161D03*
Y699917D03*
X524497Y553231D03*
X574487Y247161D03*
X569729Y506627D03*
X592979Y547831D03*
X574487Y699917D03*
Y1152673D03*
X698700Y247161D03*
Y699917D03*
Y1152673D03*
X868800Y1482760D03*
X952013Y1495424D03*
X962201Y1533926D03*
X1008900Y935000D03*
X1250700Y256161D03*
X1248700Y708917D03*
X1250000Y1161800D03*
X1374913Y256161D03*
X1372913Y708917D03*
X1374200Y1161700D03*
X1497225Y256061D03*
X1497125Y708917D03*
X1498900Y1161700D03*
X1622938Y256061D03*
X1621338Y708917D03*
X1633338Y1161673D03*
X1747750Y256061D03*
X1746900Y1161800D03*
X1767063Y1009225D03*
X1869369Y247161D03*
Y699917D03*
X1870848Y1133143D03*
G54D29*
X64437Y209361D03*
Y662017D03*
Y1114773D03*
X138428Y966735D03*
X188649Y209061D03*
X205128Y554735D03*
X188349Y1110473D03*
X312862Y209161D03*
Y661917D03*
Y1114773D03*
X437074Y209161D03*
X437174Y661917D03*
X504674Y1114573D03*
X561387Y209161D03*
Y661917D03*
X561287Y1114673D03*
X685500Y209261D03*
Y662017D03*
X685200Y1110373D03*
X870963Y818831D03*
X869863Y1487165D03*
X1032430Y834829D03*
X1009900Y939000D03*
X1182540Y257688D03*
X1177965Y281343D03*
X1228892Y225125D03*
X1253200Y240661D03*
X1251200Y693417D03*
Y1146173D03*
X1377413Y240661D03*
X1375413Y693417D03*
Y1146173D03*
X1499725Y240561D03*
X1499625Y693417D03*
Y1146173D03*
X1625438Y240561D03*
X1623838Y693417D03*
X1635638Y1146173D03*
X1750250Y240561D03*
X1748050Y1146173D03*
X1780228Y978735D03*
X1856169Y209161D03*
Y661917D03*
X1856391Y1102987D03*
G54D83*
X853379Y59870D03*
X878179D03*
X1181568Y77168D03*
X1206368D03*
G54D56*
X324841Y87515D03*
X327401D03*
X329961D03*
X332521D03*
X335081D03*
X337641D03*
X340201D03*
X342761D03*
X345321D03*
X347881D03*
X350441D03*
X353001D03*
Y109715D03*
X350441D03*
X347881D03*
X345321D03*
X342761D03*
X340201D03*
X337641D03*
X335081D03*
X332521D03*
X329961D03*
X327401D03*
X324841D03*
X876781Y1450061D03*
X879341D03*
X881901D03*
X884461D03*
X887021D03*
X889581D03*
X892141D03*
X894701D03*
Y1472261D03*
X892141D03*
X889581D03*
X887021D03*
X884461D03*
X881901D03*
X879341D03*
X876781D03*
X896420Y921900D03*
X898980D03*
X901540D03*
X904100D03*
X906660D03*
X909220D03*
X911780D03*
X914340D03*
X916900D03*
X919460D03*
X922020D03*
X924580D03*
Y944100D03*
X922020D03*
X919460D03*
X916900D03*
X914340D03*
X911780D03*
X909220D03*
X906660D03*
X904100D03*
X901540D03*
X898980D03*
X896420D03*
X927080Y1013600D03*
X924520D03*
X921960D03*
X919400D03*
X916840D03*
X914280D03*
X911720D03*
X909160D03*
X906600D03*
X904040D03*
X901480D03*
X898920D03*
Y991400D03*
X901480D03*
X904040D03*
X906600D03*
X909160D03*
X911720D03*
X914280D03*
X916840D03*
X919400D03*
X921960D03*
X924520D03*
X927080D03*
X897261Y1450061D03*
X899821D03*
X902381D03*
X904941D03*
Y1472261D03*
X902381D03*
X899821D03*
X897261D03*
X953420Y921900D03*
X955980D03*
X958540D03*
X961100D03*
X963660D03*
X966220D03*
X968780D03*
X971340D03*
X973900D03*
X976460D03*
X979020D03*
X981580D03*
Y944100D03*
X979020D03*
X976460D03*
X973900D03*
X971340D03*
X968780D03*
X966220D03*
X963660D03*
X961100D03*
X958540D03*
X955980D03*
X953420D03*
X948420Y992400D03*
X950980D03*
X953540D03*
X956100D03*
X958660D03*
X961220D03*
X963780D03*
X966340D03*
X968900D03*
X971460D03*
X974020D03*
X976580D03*
Y1014600D03*
X974020D03*
X971460D03*
X968900D03*
X966340D03*
X963780D03*
X961220D03*
X958660D03*
X956100D03*
X953540D03*
X950980D03*
X948420D03*
X1020540Y921400D03*
X1023100D03*
X1025660D03*
X1028220D03*
X1030780D03*
X1033340D03*
X1035900D03*
X1038460D03*
Y943600D03*
X1035900D03*
X1033340D03*
X1030780D03*
X1028220D03*
X1025660D03*
X1023100D03*
X1020540D03*
X997614Y992740D03*
X1000174D03*
X1002734D03*
X1005294D03*
X1007854D03*
X1010414D03*
X1012974D03*
X1015534D03*
X1018094D03*
X1020654D03*
X1023214D03*
X1025774D03*
Y1014940D03*
X1023214D03*
X1020654D03*
X1018094D03*
X1015534D03*
X1012974D03*
X1010414D03*
X1007854D03*
X1005294D03*
X1002734D03*
X1000174D03*
X997614D03*
X1025920Y1083900D03*
X1028480D03*
X1031040D03*
X1033600D03*
X1036160D03*
X1038720D03*
Y1106100D03*
X1036160D03*
X1033600D03*
X1031040D03*
X1028480D03*
X1025920D03*
X1073420Y1084900D03*
X1075980D03*
X1078540D03*
X1081100D03*
X1083660D03*
X1086220D03*
X1041280Y1083900D03*
X1043840D03*
X1046400D03*
X1048960D03*
X1051520D03*
X1054080D03*
X1086220Y1107100D03*
X1083660D03*
X1081100D03*
X1078540D03*
X1075980D03*
X1073420D03*
X1054080Y1106100D03*
X1051520D03*
X1048960D03*
X1046400D03*
X1043840D03*
X1041280D03*
X1088780Y1084900D03*
X1091340D03*
X1093900D03*
X1096460D03*
X1099020D03*
X1101580D03*
X1116420D03*
X1118980D03*
X1121540D03*
X1124100D03*
X1126660D03*
X1129220D03*
X1131780D03*
X1134340D03*
X1101580Y1107100D03*
X1099020D03*
X1096460D03*
X1093900D03*
X1091340D03*
X1088780D03*
X1134340D03*
X1131780D03*
X1129220D03*
X1126660D03*
X1124100D03*
X1121540D03*
X1118980D03*
X1116420D03*
X1136900Y1084900D03*
X1139460D03*
X1142020D03*
X1144580D03*
Y1107100D03*
X1142020D03*
X1139460D03*
X1136900D03*
X1323041Y96135D03*
X1325601D03*
X1328161D03*
Y118335D03*
X1325601D03*
X1323041D03*
X1330721Y96135D03*
X1333281D03*
X1335841D03*
X1338401D03*
X1340961D03*
X1343521D03*
X1346081D03*
X1348641D03*
X1351201D03*
Y118335D03*
X1348641D03*
X1346081D03*
X1343521D03*
X1340961D03*
X1338401D03*
X1335841D03*
X1333281D03*
X1330721D03*
G54D38*
X72500Y498200D03*
X67500D03*
X72500Y950955D03*
X67500D03*
X126063Y974025D03*
X196712Y498200D03*
X191712D03*
X192763Y562025D03*
X216712Y950755D03*
X221712D03*
X313312Y103231D03*
X320925Y498200D03*
X315925D03*
X320925Y950955D03*
X315925D03*
X445138Y498200D03*
X440138D03*
X445138Y950955D03*
X440138D03*
X539350Y498200D03*
X534350D03*
X520479Y558913D03*
X569350Y950955D03*
X564350D03*
X652663Y506200D03*
X647663D03*
X607460Y550474D03*
X693563Y950955D03*
X688563D03*
X749000Y666200D03*
X865663Y838753D03*
X892700Y1534118D03*
X939000Y1007400D03*
X944776Y935200D03*
X987970Y1008207D03*
X967813Y1543366D03*
X1027063Y855053D03*
X1017000Y1099200D03*
X1064500Y1100200D03*
X1094200Y-48400D03*
X1107100Y1100100D03*
X1269878Y498621D03*
X1264878D03*
X1268742Y950786D03*
X1263742D03*
X1312999Y111325D03*
X1364882Y498200D03*
X1359882D03*
X1367382Y950955D03*
X1362382D03*
X1426419Y516457D03*
X1443700Y519800D03*
X1491594Y498200D03*
X1486594D03*
X1491594Y950955D03*
X1486594D03*
X1615807Y498200D03*
X1610807D03*
X1615807Y950955D03*
X1610807D03*
X1740019Y498200D03*
X1735019D03*
X1740019Y950955D03*
X1735019D03*
X1767863Y986025D03*
X1782666Y950944D03*
X1777666D03*
X1859232Y498200D03*
X1869500Y184944D03*
X1864232Y498200D03*
X1869500Y637700D03*
G54D74*
X601418Y516495D03*
X608918Y520370D03*
Y512620D03*
X975023Y1508212D03*
X982523Y1512087D03*
Y1504337D03*
X1005250Y917500D03*
X1012750Y913625D03*
Y921375D03*
G54D92*
X986614Y1619764D03*
X974016D03*
Y1597126D03*
X986614D03*
X974016Y1642401D03*
X986614D03*
X1030709Y1619764D03*
X1014961D03*
X1002362D03*
Y1597126D03*
X1014961D03*
X1030709D03*
X1002362Y1642401D03*
X1014961D03*
X1030709D03*
X1043307Y1619764D03*
Y1597126D03*
Y1642401D03*
G54D84*
X871346Y86000D03*
X860378D03*
X1178334Y726750D03*
X1187784Y47968D03*
X1198752D03*
X1189302Y726750D03*
G54D48*
X94237Y284461D03*
Y276861D03*
Y737217D03*
Y729617D03*
Y1189973D03*
Y1182373D03*
X218449Y284461D03*
Y276861D03*
Y737217D03*
Y729617D03*
Y1189973D03*
Y1182373D03*
X342662Y284461D03*
Y276861D03*
Y737217D03*
Y729617D03*
Y1189973D03*
Y1182373D03*
X466874Y284461D03*
Y276861D03*
Y737217D03*
Y729617D03*
Y1189973D03*
Y1182373D03*
X591087Y284461D03*
Y276861D03*
X587974Y513895D03*
Y521495D03*
X563279Y519131D03*
Y511531D03*
X591087Y737217D03*
Y729617D03*
Y1189973D03*
Y1182373D03*
X715300Y284461D03*
Y276861D03*
Y737217D03*
Y729617D03*
Y1189973D03*
Y1182373D03*
X880200Y693200D03*
Y700800D03*
X932500Y1505500D03*
Y1497900D03*
X964035Y1496252D03*
Y1503852D03*
X956286Y1502925D03*
Y1510525D03*
X1018483Y1460325D03*
Y1467925D03*
X1074455Y1459711D03*
Y1467311D03*
X1046355Y1459711D03*
Y1467311D03*
X1313000Y287361D03*
Y294961D03*
X1305000Y287361D03*
Y294961D03*
X1313000Y740117D03*
X1305000D03*
X1313000Y747717D03*
X1305000D03*
X1313000Y1192873D03*
Y1200473D03*
X1305000Y1192873D03*
Y1200473D03*
X1402257Y549931D03*
Y542331D03*
X1437213Y287361D03*
Y294961D03*
X1429213Y287361D03*
Y294961D03*
X1441631Y581215D03*
Y573615D03*
X1464700Y573300D03*
Y580900D03*
X1437213Y740117D03*
X1429213D03*
X1437213Y747717D03*
X1429213D03*
X1437213Y1192873D03*
Y1200473D03*
X1429213Y1192873D03*
Y1200473D03*
X1561425Y287361D03*
Y294961D03*
X1553425Y287361D03*
Y294961D03*
X1561425Y740117D03*
X1553425D03*
X1561425Y747717D03*
X1553425D03*
Y1192873D03*
Y1200473D03*
X1561425Y1192873D03*
Y1200473D03*
X1685638Y287361D03*
Y294961D03*
X1677638Y287361D03*
Y294961D03*
X1685638Y740117D03*
X1677638D03*
X1685638Y747717D03*
X1677638D03*
X1685638Y1192873D03*
Y1200473D03*
X1677638Y1192873D03*
Y1200473D03*
X1809850Y287361D03*
Y294961D03*
X1801850Y287361D03*
Y294961D03*
X1809968Y740294D03*
X1801968D03*
X1809968Y747894D03*
X1801968D03*
X1809850Y1192873D03*
Y1200473D03*
X1801850Y1192873D03*
Y1200473D03*
X1885969Y284461D03*
Y276861D03*
Y737217D03*
Y729617D03*
X1865992Y1146330D03*
Y1138730D03*
X1885969Y1189973D03*
Y1182373D03*
G54D75*
X648392Y588186D03*
Y593186D03*
Y598186D03*
Y603186D03*
G54D39*
X72500Y503800D03*
X67500D03*
X72500Y956555D03*
X67500D03*
X126063Y979625D03*
X196712Y503800D03*
X191712D03*
X192763Y567625D03*
X216712Y956355D03*
X221712D03*
X313312Y108831D03*
X320925Y503800D03*
X315925D03*
X320925Y956555D03*
X315925D03*
X445138Y503800D03*
X440138D03*
X445138Y956555D03*
X440138D03*
X539350Y503800D03*
X534350D03*
X520479Y564513D03*
X569350Y956555D03*
X564350D03*
X652663Y511800D03*
X647663D03*
X607460Y556074D03*
X693563Y956555D03*
X688563D03*
X749000Y671800D03*
X865663Y844353D03*
X892700Y1539718D03*
X939000Y1013000D03*
X944776Y940800D03*
X987970Y1013807D03*
X967813Y1548966D03*
X1027063Y860653D03*
X1017000Y1104800D03*
X1064500Y1105800D03*
X1094200Y-42800D03*
X1107100Y1105700D03*
X1269878Y504221D03*
X1264878D03*
X1268742Y956386D03*
X1263742D03*
X1312999Y116925D03*
X1364882Y503800D03*
X1359882D03*
X1367382Y956555D03*
X1362382D03*
X1426419Y522057D03*
X1443700Y525400D03*
X1491594Y503800D03*
X1486594D03*
X1491594Y956555D03*
X1486594D03*
X1615807Y503800D03*
X1610807D03*
X1615807Y956555D03*
X1610807D03*
X1740019Y503800D03*
X1735019D03*
X1740019Y956555D03*
X1735019D03*
X1782666Y956544D03*
X1777666D03*
X1767863Y991625D03*
X1859232Y503800D03*
X1869500Y190544D03*
X1864232Y503800D03*
X1869500Y643300D03*
G54D57*
X317812Y103731D03*
X591779Y539031D03*
X568779Y516531D03*
X621058Y538945D03*
X696787Y584595D03*
X752500Y1140200D03*
X870163Y840253D03*
X943500Y1008900D03*
X928384Y1349782D03*
X928439Y1363514D03*
X942925Y1372857D03*
X938000Y1502900D03*
X948845Y934950D03*
X961000Y1525400D03*
X1031563Y856553D03*
X992994Y1009540D03*
X1021200Y1100800D03*
X1068700Y1101800D03*
X1111600Y1101600D03*
X1317655Y112751D03*
X1376243Y574719D03*
X1460200Y518300D03*
X1452200D03*
X1439200D03*
X1465700D03*
X1433200Y562800D03*
X1487541Y535562D03*
X1883000Y187444D03*
Y640200D03*
G54D93*
X974016Y1591220D03*
Y1603031D03*
Y1613858D03*
X986614Y1591220D03*
Y1613858D03*
Y1603031D03*
X974016Y1625669D03*
Y1636496D03*
Y1648307D03*
X986614Y1625669D03*
Y1636496D03*
Y1648307D03*
X1002362Y1591220D03*
Y1603031D03*
Y1613858D03*
X1014961Y1591220D03*
Y1603031D03*
Y1613858D03*
X1030709Y1591220D03*
Y1613858D03*
Y1603031D03*
X1002362Y1625669D03*
Y1636496D03*
Y1648307D03*
X1014961Y1625669D03*
Y1636496D03*
Y1648307D03*
X1030709Y1625669D03*
Y1636496D03*
Y1648307D03*
X1043307Y1591220D03*
Y1603031D03*
Y1613858D03*
Y1625669D03*
Y1636496D03*
Y1648307D03*
X1101457Y1588583D03*
X1119685D03*
X1101457Y1601181D03*
X1119685D03*
G54D66*
X539079Y561531D03*
X911100Y1539500D03*
G54D67*
X543338Y553169D03*
X567779Y570531D03*
X575779D03*
X588779D03*
X562279D03*
X876956Y1365750D03*
X929232Y921850D03*
X928194Y1373048D03*
X942879Y1361757D03*
X931500Y1556900D03*
X937000D03*
X973055Y1179453D03*
X945000Y1556900D03*
X958000D03*
X1032053Y-42075D03*
X999500Y1184200D03*
X1054625Y-47250D03*
X1320055Y71629D03*
X1436200Y549800D03*
X1459200Y572300D03*
X1598400Y1111200D03*
G54D49*
X131201Y377154D03*
X131200Y829910D03*
X131201Y1282666D03*
X379232Y377154D03*
Y829910D03*
Y1282666D03*
X627263Y377154D03*
Y829910D03*
Y1282666D03*
X796457Y263003D03*
Y735444D03*
X961418Y1087413D03*
Y1429932D03*
X1181890Y555917D03*
X1181870Y969280D03*
X1181890Y1559854D03*
X1301870Y377154D03*
Y829910D03*
Y1282666D03*
X1549901Y377154D03*
Y829910D03*
Y1282666D03*
X1797933Y377154D03*
Y829910D03*
Y1282666D03*
G54D85*
X870100Y691616D03*
Y702584D03*
G54D94*
X1013662Y-103956D03*
X1010512D03*
X1007363D03*
X1004213D03*
X1001063D03*
X997914D03*
X994764D03*
G54D76*
X683341Y586324D03*
X689747D03*
G54D58*
X317812Y107331D03*
X591779Y542631D03*
X568779Y520131D03*
X621058Y542545D03*
X696787Y588195D03*
X752500Y1143800D03*
X870163Y843853D03*
X943500Y1012500D03*
X928384Y1353382D03*
X928439Y1367114D03*
X942925Y1376457D03*
X938000Y1506500D03*
X948845Y938550D03*
X961000Y1529000D03*
X1031563Y860153D03*
X992994Y1013140D03*
X1021200Y1104400D03*
X1068700Y1105400D03*
X1111600Y1105200D03*
X1317655Y116351D03*
X1376243Y578319D03*
X1460200Y521900D03*
X1452200D03*
X1439200D03*
X1465700D03*
X1433200Y566400D03*
X1487541Y539162D03*
X1883000Y191044D03*
Y643800D03*
G54D68*
X543338Y556769D03*
X567779Y574131D03*
X575779D03*
X588779D03*
X562279D03*
X876956Y1369350D03*
X929232Y925450D03*
X942879Y1365357D03*
X928194Y1376648D03*
X931500Y1560500D03*
X937000D03*
X973055Y1183053D03*
X945000Y1560500D03*
X958000D03*
X1032053Y-38475D03*
X999500Y1187800D03*
X1054625Y-43650D03*
X1320055Y75229D03*
X1436200Y553400D03*
X1459200Y575900D03*
X1598400Y1114800D03*
G54D59*
X381096Y461995D03*
X1620100Y60000D03*
G54D77*
X683341Y593826D03*
X689747D03*
G54D86*
X883763Y829253D03*
X881203D03*
X878643D03*
X876083D03*
Y845553D03*
X878643D03*
X881203D03*
X883763D03*
X1037483Y861953D03*
X1040043D03*
Y845653D03*
X1037483D03*
X1042603Y861953D03*
X1045163D03*
Y845653D03*
X1042603D03*
G54D95*
X1017695Y-85425D03*
X1029295D03*
X1040397Y-84867D03*
X1051997D03*
G54D69*
X580829Y549721D03*
Y535941D03*
X560729D03*
Y549721D03*
X929950Y1522310D03*
Y1536090D03*
X950050D03*
Y1522310D03*
X1447150Y542710D03*
X1467250D03*
X1447150Y556490D03*
X1467250D03*
G54D87*
X895676Y1372183D03*
Y1369623D03*
Y1367063D03*
Y1364503D03*
Y1361943D03*
Y1359383D03*
Y1356823D03*
Y1374743D03*
X917876Y1356823D03*
Y1359383D03*
Y1361943D03*
Y1364503D03*
Y1367063D03*
Y1369623D03*
Y1372183D03*
Y1374743D03*
G54D96*
X1032080Y-52355D03*
X1039560D03*
Y-61355D03*
X1035820D03*
X1032080D03*
X1054593Y-57597D03*
X1062073D03*
Y-66597D03*
X1058333D03*
X1054593D03*
G54D78*
X671392Y598186D03*
Y593186D03*
Y603186D03*
G54D88*
X944881Y-58267D03*
G54D79*
X663392Y595686D03*
G54D97*
X1039845Y1467746D03*
X1026345D03*
X1030845D03*
X1035345D03*
X1039845Y1463246D03*
X1026345D03*
X1030845D03*
X1035345D03*
X1005400Y1463157D03*
X1000900D03*
X996400D03*
X1009900D03*
X1005400Y1467657D03*
X1000900D03*
X996400D03*
X1009900D03*
X1035345Y1476746D03*
X1030845D03*
X1026345D03*
X1039845D03*
Y1472246D03*
X1026345D03*
X1030845D03*
X1035345D03*
X1005400Y1472157D03*
X1000900D03*
X996400D03*
X1009900D03*
Y1476657D03*
X1005400D03*
X1000900D03*
X996400D03*
X1023583Y1489593D03*
X995783D03*
X1000500Y1511400D03*
X1036578Y1511210D03*
X1014690Y1511178D03*
X1010190D03*
X1005690D03*
X1031790Y1511078D03*
X1027290D03*
X1019600Y1511100D03*
X1023583Y1501593D03*
Y1507593D03*
Y1495593D03*
X995783D03*
Y1501593D03*
Y1507593D03*
X1040583Y1517883D03*
X1031799Y1534392D03*
X1031882Y1528985D03*
X1026459Y1528919D03*
X1026376Y1534326D03*
X1014867D03*
X1014950Y1528919D03*
X1020290Y1534392D03*
X1020373Y1528985D03*
X1040500Y1529290D03*
X1040583Y1523883D03*
X1062700Y1463100D03*
X1058200D03*
X1067200D03*
X1062700Y1467600D03*
X1058200D03*
X1067200D03*
X1053700Y1463100D03*
Y1467600D03*
X1062700Y1472100D03*
X1058200D03*
X1067200D03*
Y1476600D03*
X1058200D03*
X1062700D03*
X1053700Y1472100D03*
Y1476600D03*
X1078683Y1489593D03*
X1051383D03*
X1041810Y1511084D03*
X1055310D03*
X1059810D03*
X1064310D03*
X1068810D03*
X1073310D03*
X1078683Y1495593D03*
Y1501593D03*
Y1507593D03*
Y1516593D03*
X1051383Y1495593D03*
Y1501593D03*
Y1507593D03*
X1078683Y1522593D03*
G54D98*
X1030055Y1505511D03*
X1035055D03*
X1002255D03*
X1007255D03*
X1012255D03*
X1057855D03*
X1062855D03*
X1067855D03*
X1040055D03*
X1376200Y563900D03*
X1381200D03*
X1386200D03*
G54D89*
X929331Y16536D03*
X937205Y20473D03*
Y12599D03*
X929331Y63780D03*
X937205Y67717D03*
X929331Y48032D03*
Y40158D03*
Y32284D03*
Y24410D03*
X937205Y51969D03*
Y44095D03*
Y36221D03*
Y28347D03*
X929331Y111024D03*
Y103150D03*
Y95276D03*
Y87402D03*
Y79528D03*
Y71654D03*
X937205Y114961D03*
Y107087D03*
Y99213D03*
Y91339D03*
Y83465D03*
Y75591D03*
X929331Y166142D03*
Y158268D03*
Y150394D03*
Y142520D03*
Y134646D03*
Y126772D03*
Y118898D03*
X937205Y162205D03*
Y154331D03*
Y146457D03*
Y138583D03*
Y130709D03*
Y122835D03*
X929331Y213386D03*
Y205512D03*
Y197638D03*
Y189764D03*
Y181890D03*
Y174016D03*
X937205Y209449D03*
Y201575D03*
Y193701D03*
Y185827D03*
Y177953D03*
Y170079D03*
X929331Y260630D03*
Y252756D03*
Y244882D03*
Y237008D03*
Y229134D03*
Y221260D03*
X937205Y256693D03*
Y248819D03*
Y240945D03*
Y233071D03*
Y225197D03*
Y217323D03*
X929331Y307874D03*
Y300000D03*
Y292126D03*
Y284252D03*
Y276378D03*
Y268504D03*
X937205Y303937D03*
Y296063D03*
Y288189D03*
Y280315D03*
Y272441D03*
Y264567D03*
X929331Y339371D03*
Y331496D03*
Y323622D03*
Y315748D03*
X937205Y335434D03*
Y327559D03*
Y319685D03*
Y311811D03*
X929331Y403543D03*
Y395669D03*
X937205Y407480D03*
Y399606D03*
Y391732D03*
X929331Y450787D03*
Y442913D03*
X937205Y454724D03*
Y446850D03*
X929331Y427165D03*
Y419291D03*
Y411417D03*
X937205Y431102D03*
Y423228D03*
Y415354D03*
X929331Y498031D03*
Y490157D03*
Y482283D03*
Y474409D03*
Y466535D03*
Y458661D03*
X937205Y501968D03*
Y494094D03*
Y486220D03*
Y478346D03*
Y470472D03*
Y462598D03*
X929331Y553149D03*
Y545275D03*
Y537401D03*
Y529527D03*
Y521653D03*
Y513779D03*
Y505905D03*
X937205Y549212D03*
Y541338D03*
Y533464D03*
Y525590D03*
Y517716D03*
Y509842D03*
X929331Y600393D03*
Y592519D03*
Y584645D03*
Y576771D03*
Y568897D03*
Y561023D03*
X937205Y596456D03*
Y588582D03*
Y580708D03*
Y572834D03*
Y564960D03*
Y557086D03*
X929331Y647637D03*
Y639763D03*
Y631889D03*
Y624015D03*
Y616141D03*
Y608267D03*
X937205Y643700D03*
Y635826D03*
Y627952D03*
Y620078D03*
Y612204D03*
Y604330D03*
X929331Y694881D03*
Y687007D03*
Y679133D03*
Y671259D03*
Y663385D03*
Y655511D03*
X937205Y690944D03*
Y683070D03*
Y675196D03*
Y667322D03*
Y659448D03*
Y651574D03*
X929331Y718504D03*
Y710629D03*
Y702755D03*
X937205Y714567D03*
Y706692D03*
Y698818D03*
X954921Y16536D03*
X947047Y20473D03*
Y12599D03*
X954921Y63780D03*
X947047Y67717D03*
X954921Y48032D03*
Y40158D03*
Y32284D03*
Y24410D03*
X947047Y51969D03*
Y44095D03*
Y36221D03*
Y28347D03*
X954921Y111024D03*
Y103150D03*
Y95276D03*
Y87402D03*
Y79528D03*
Y71654D03*
X947047Y114961D03*
Y107087D03*
Y99213D03*
Y91339D03*
Y83465D03*
Y75591D03*
X954921Y166142D03*
Y158268D03*
Y150394D03*
Y142520D03*
Y134646D03*
Y126772D03*
Y118898D03*
X947047Y162205D03*
Y154331D03*
Y146457D03*
Y138583D03*
Y130709D03*
Y122835D03*
X954921Y213386D03*
Y205512D03*
Y197638D03*
Y189764D03*
Y181890D03*
Y174016D03*
X947047Y209449D03*
Y201575D03*
Y193701D03*
Y185827D03*
Y177953D03*
Y170079D03*
X954921Y260630D03*
Y252756D03*
Y244882D03*
Y237008D03*
Y229134D03*
Y221260D03*
X947047Y256693D03*
Y248819D03*
Y240945D03*
Y233071D03*
Y225197D03*
Y217323D03*
X954921Y307874D03*
Y300000D03*
Y292126D03*
Y284252D03*
Y276378D03*
Y268504D03*
X947047Y303937D03*
Y296063D03*
Y288189D03*
Y280315D03*
Y272441D03*
Y264567D03*
X954921Y339371D03*
Y331496D03*
Y323622D03*
Y315748D03*
X947047Y335434D03*
Y327559D03*
Y319685D03*
Y311811D03*
X954921Y403543D03*
Y395669D03*
X947047Y407480D03*
Y399606D03*
Y391732D03*
X954921Y450787D03*
Y442913D03*
X947047Y454724D03*
Y446850D03*
X954921Y427165D03*
Y419291D03*
Y411417D03*
X947047Y431102D03*
Y423228D03*
Y415354D03*
X954921Y498031D03*
Y490157D03*
Y482283D03*
Y474409D03*
Y466535D03*
Y458661D03*
X947047Y501968D03*
Y494094D03*
Y486220D03*
Y478346D03*
Y470472D03*
Y462598D03*
X954921Y553149D03*
Y545275D03*
Y537401D03*
Y529527D03*
Y521653D03*
Y513779D03*
Y505905D03*
X947047Y549212D03*
Y541338D03*
Y533464D03*
Y525590D03*
Y517716D03*
Y509842D03*
X954921Y600393D03*
Y592519D03*
Y584645D03*
Y576771D03*
Y568897D03*
Y561023D03*
X947047Y596456D03*
Y588582D03*
Y580708D03*
Y572834D03*
Y564960D03*
Y557086D03*
X954921Y647637D03*
Y639763D03*
Y631889D03*
Y624015D03*
Y616141D03*
Y608267D03*
X947047Y643700D03*
Y635826D03*
Y627952D03*
Y620078D03*
Y612204D03*
Y604330D03*
X954921Y694881D03*
Y687007D03*
Y679133D03*
Y671259D03*
Y663385D03*
Y655511D03*
X947047Y690944D03*
Y683070D03*
Y675196D03*
Y667322D03*
Y659448D03*
Y651574D03*
X954921Y718504D03*
Y710629D03*
Y702755D03*
X947047Y714567D03*
Y706692D03*
Y698818D03*
X988795Y1571058D03*
Y1576658D03*
X1026106Y1545595D03*
Y1539995D03*
X1031706Y1545595D03*
Y1539995D03*
X1020574Y1540059D03*
Y1545659D03*
X1039758Y1559605D03*
X1014974Y1540059D03*
Y1545659D03*
X1039358Y1565405D03*
X1033717Y1563634D03*
X1028223Y1563763D03*
X1022623D03*
X994305Y1566342D03*
X1017023Y1563763D03*
X1011476Y1565175D03*
X1005658Y1565005D03*
X1000058D03*
X1039958Y1553705D03*
Y1548105D03*
Y1542505D03*
X1039358Y1571005D03*
Y1576605D03*
X1005658Y1575905D03*
X1033917Y1574834D03*
X1033717Y1569234D03*
X1000058Y1575905D03*
X1028423Y1574963D03*
X1028223Y1569363D03*
X994460Y1577240D03*
X1022823Y1574963D03*
X1022623Y1569363D03*
X1017223Y1574963D03*
X1017023Y1569363D03*
X994305Y1571942D03*
X1011676Y1576375D03*
X1011476Y1570775D03*
X1005658Y1570605D03*
X1000058D03*
X1078358Y1561105D03*
Y1566705D03*
X1072758Y1561105D03*
Y1566705D03*
X1067158Y1561105D03*
Y1566705D03*
X1061558Y1561105D03*
Y1566705D03*
X1055768Y1566675D03*
X1055418Y1560785D03*
X1055618Y1554885D03*
Y1549285D03*
Y1543685D03*
X1078358Y1572305D03*
X1072758D03*
X1067158D03*
X1061558D03*
X1055768Y1572275D03*
Y1577875D03*
X1123031Y16536D03*
X1097441D03*
X1115157Y20473D03*
Y12599D03*
X1105315Y20473D03*
Y12599D03*
X1123031Y63780D03*
X1097441D03*
X1115157Y67717D03*
X1105315D03*
X1123031Y48032D03*
Y40158D03*
Y32284D03*
Y24410D03*
X1097441Y48032D03*
Y40158D03*
Y32284D03*
Y24410D03*
X1115157Y51969D03*
Y44095D03*
Y36221D03*
Y28347D03*
X1105315Y51969D03*
Y44095D03*
Y36221D03*
Y28347D03*
X1123031Y111024D03*
Y103150D03*
Y95276D03*
Y87402D03*
Y79528D03*
Y71654D03*
X1097441Y111024D03*
Y103150D03*
Y95276D03*
Y87402D03*
Y79528D03*
Y71654D03*
X1115157Y114961D03*
Y107087D03*
Y99213D03*
Y91339D03*
Y83465D03*
Y75591D03*
X1105315Y114961D03*
Y107087D03*
Y99213D03*
Y91339D03*
Y83465D03*
Y75591D03*
X1123031Y166142D03*
Y158268D03*
Y150394D03*
Y142520D03*
Y134646D03*
Y126772D03*
Y118898D03*
X1097441Y166142D03*
Y158268D03*
Y150394D03*
Y142520D03*
Y134646D03*
Y126772D03*
Y118898D03*
X1115157Y162205D03*
Y154331D03*
Y146457D03*
Y138583D03*
Y130709D03*
Y122835D03*
X1105315Y162205D03*
Y154331D03*
Y146457D03*
Y138583D03*
Y130709D03*
Y122835D03*
X1123031Y213386D03*
Y205512D03*
Y197638D03*
Y189764D03*
Y181890D03*
Y174016D03*
X1097441Y213386D03*
Y205512D03*
Y197638D03*
Y189764D03*
Y181890D03*
Y174016D03*
X1115157Y209449D03*
Y201575D03*
Y193701D03*
Y185827D03*
Y177953D03*
Y170079D03*
X1105315Y209449D03*
Y201575D03*
Y193701D03*
Y185827D03*
Y177953D03*
Y170079D03*
X1123031Y260630D03*
Y252756D03*
Y244882D03*
Y237008D03*
Y229134D03*
Y221260D03*
X1097441Y260630D03*
Y252756D03*
Y244882D03*
Y237008D03*
Y229134D03*
Y221260D03*
X1115157Y256693D03*
Y248819D03*
Y240945D03*
Y233071D03*
Y225197D03*
Y217323D03*
X1105315Y256693D03*
Y248819D03*
Y240945D03*
Y233071D03*
Y225197D03*
Y217323D03*
X1123031Y307874D03*
Y300000D03*
Y292126D03*
Y284252D03*
Y276378D03*
Y268504D03*
X1097441Y307874D03*
Y300000D03*
Y292126D03*
Y284252D03*
Y276378D03*
Y268504D03*
X1115157Y303937D03*
Y296063D03*
Y288189D03*
Y280315D03*
Y272441D03*
Y264567D03*
X1105315Y303937D03*
Y296063D03*
Y288189D03*
Y280315D03*
Y272441D03*
Y264567D03*
X1123031Y339371D03*
Y331496D03*
Y323622D03*
Y315748D03*
X1097441Y339371D03*
Y331496D03*
Y323622D03*
Y315748D03*
X1115157Y335434D03*
Y327559D03*
Y319685D03*
Y311811D03*
X1105315Y335434D03*
Y327559D03*
Y319685D03*
Y311811D03*
X1123031Y403543D03*
Y395669D03*
X1097441Y403543D03*
Y395669D03*
X1115157Y407480D03*
Y399606D03*
Y391732D03*
X1105315Y407480D03*
Y399606D03*
Y391732D03*
X1123031Y450787D03*
Y442913D03*
X1097441Y450787D03*
Y442913D03*
X1115157Y454724D03*
Y446850D03*
X1105315Y454724D03*
Y446850D03*
X1123031Y427165D03*
Y419291D03*
Y411417D03*
X1097441Y427165D03*
Y419291D03*
Y411417D03*
X1115157Y431102D03*
Y423228D03*
Y415354D03*
X1105315Y431102D03*
Y423228D03*
Y415354D03*
X1123031Y498031D03*
Y490157D03*
Y482283D03*
Y474409D03*
Y466535D03*
Y458661D03*
X1097441Y498031D03*
Y490157D03*
Y482283D03*
Y474409D03*
Y466535D03*
Y458661D03*
X1115157Y501968D03*
Y494094D03*
Y486220D03*
Y478346D03*
Y470472D03*
Y462598D03*
X1105315Y501968D03*
Y494094D03*
Y486220D03*
Y478346D03*
Y470472D03*
Y462598D03*
X1123031Y553149D03*
Y545275D03*
Y537401D03*
Y529527D03*
Y521653D03*
Y513779D03*
Y505905D03*
X1097441Y553149D03*
Y545275D03*
Y537401D03*
Y529527D03*
Y521653D03*
Y513779D03*
Y505905D03*
X1115157Y549212D03*
Y541338D03*
Y533464D03*
Y525590D03*
Y517716D03*
Y509842D03*
X1105315Y549212D03*
Y541338D03*
Y533464D03*
Y525590D03*
Y517716D03*
Y509842D03*
X1123031Y600393D03*
Y592519D03*
Y584645D03*
Y576771D03*
Y568897D03*
Y561023D03*
X1097441Y600393D03*
Y592519D03*
Y584645D03*
Y576771D03*
Y568897D03*
Y561023D03*
X1115157Y596456D03*
Y588582D03*
Y580708D03*
Y572834D03*
Y564960D03*
Y557086D03*
X1105315Y596456D03*
Y588582D03*
Y580708D03*
Y572834D03*
Y564960D03*
Y557086D03*
X1123031Y647637D03*
Y639763D03*
Y631889D03*
Y624015D03*
Y616141D03*
Y608267D03*
X1097441Y647637D03*
Y639763D03*
Y631889D03*
Y624015D03*
Y616141D03*
Y608267D03*
X1115157Y643700D03*
Y635826D03*
Y627952D03*
Y620078D03*
Y612204D03*
Y604330D03*
X1105315Y643700D03*
Y635826D03*
Y627952D03*
Y620078D03*
Y612204D03*
Y604330D03*
X1123031Y694881D03*
Y687007D03*
Y679133D03*
Y671259D03*
Y663385D03*
Y655511D03*
X1097441Y694881D03*
Y687007D03*
Y679133D03*
Y671259D03*
Y663385D03*
Y655511D03*
X1115157Y690944D03*
Y683070D03*
Y675196D03*
Y667322D03*
Y659448D03*
Y651574D03*
X1105315Y690944D03*
Y683070D03*
Y675196D03*
Y667322D03*
Y659448D03*
Y651574D03*
X1123031Y718504D03*
Y710629D03*
Y702755D03*
X1097441Y718504D03*
Y710629D03*
Y702755D03*
X1115157Y714567D03*
Y706692D03*
Y698818D03*
X1105315Y714567D03*
Y706692D03*
Y698818D03*
G54D99*
X1037555Y1497511D03*
X1009755D03*
X1065355D03*
X1383700Y555900D03*
M02*
